G04 ================== begin FILE IDENTIFICATION RECORD ==================*
G04 Layout Name:  13130-1b.brd*
G04 Film Name:    BMASK*
G04 File Format:  Gerber RS274X*
G04 File Origin:  Cadence Allegro 16.5-S037*
G04 Origin Date:  Thu Nov 13 17:26:08 2014*
G04 *
G04 Layer:  VIA CLASS/SOLDERMASK_BOTTOM*
G04 Layer:  PIN/SOLDERMASK_BOTTOM*
G04 Layer:  PACKAGE GEOMETRY/SOLDERMASK_BOTTOM*
G04 Layer:  DRAWING FORMAT/LAYER_PCB_STORY*
G04 Layer:  DRAWING FORMAT/LAYER_SOLDER_B*
G04 Layer:  BOARD GEOMETRY/SOLDERMASK_BOTTOM*
G04 *
G04 Offset:    (0.00 0.00)*
G04 Mirror:    No*
G04 Mode:      Positive*
G04 Rotation:  0*
G04 FullContactRelief:  No*
G04 UndefLineWidth:     6.00*
G04 ================== end FILE IDENTIFICATION RECORD ====================*
%FSLAX35Y35*MOIN*%
%IR0*IPPOS*OFA0.00000B0.00000*MIA0B0*SFA1.00000B1.00000*%
%AMMACRO34*
4,1,40,.008,.009,
-.008,.009,
-.008347,.00897,
-.008684,.008879,
-.009,.008732,
-.009286,.008532,
-.009532,.008286,
-.009732,.008,
-.009879,.007684,
-.00997,.007347,
-.01,.007,
-.01,-.007,
-.00997,-.007347,
-.009879,-.007684,
-.009732,-.008,
-.009532,-.008286,
-.009286,-.008532,
-.009,-.008732,
-.008684,-.008879,
-.008347,-.00897,
-.008,-.009,
.008,-.009,
.008347,-.00897,
.008684,-.008879,
.009,-.008732,
.009286,-.008532,
.009532,-.008286,
.009732,-.008,
.009879,-.007684,
.00997,-.007347,
.01,-.007,
.01,.007,
.00997,.007347,
.009879,.007684,
.009732,.008,
.009532,.008286,
.009286,.008532,
.009,.008732,
.008684,.008879,
.008347,.00897,
.008,.009,
0.0*
%
%ADD34MACRO34*%
%ADD43C,.02*%
%ADD46C,.04*%
%AMMACRO19*
4,1,40,-.009,.01,
.009,.01,
.009347,.00997,
.009684,.009879,
.01,.009732,
.010286,.009532,
.010532,.009286,
.010732,.009,
.010879,.008684,
.01097,.008347,
.011,.008,
.011,-.008,
.01097,-.008347,
.010879,-.008684,
.010732,-.009,
.010532,-.009286,
.010286,-.009532,
.01,-.009732,
.009684,-.009879,
.009347,-.00997,
.009,-.01,
-.009,-.01,
-.009347,-.00997,
-.009684,-.009879,
-.01,-.009732,
-.010286,-.009532,
-.010532,-.009286,
-.010732,-.009,
-.010879,-.008684,
-.01097,-.008347,
-.011,-.008,
-.011,.008,
-.01097,.008347,
-.010879,.008684,
-.010732,.009,
-.010532,.009286,
-.010286,.009532,
-.01,.009732,
-.009684,.009879,
-.009347,.00997,
-.009,.01,
0.0*
%
%ADD19MACRO19*%
%ADD58R,.126X.091*%
%ADD40C,.032*%
%AMMACRO20*
4,1,40,.01,.009,
.01,-.009,
.00997,-.009347,
.009879,-.009684,
.009732,-.01,
.009532,-.010286,
.009286,-.010532,
.009,-.010732,
.008684,-.010879,
.008347,-.01097,
.008,-.011,
-.008,-.011,
-.008347,-.01097,
-.008684,-.010879,
-.009,-.010732,
-.009286,-.010532,
-.009532,-.010286,
-.009732,-.01,
-.009879,-.009684,
-.00997,-.009347,
-.01,-.009,
-.01,.009,
-.00997,.009347,
-.009879,.009684,
-.009732,.01,
-.009532,.010286,
-.009286,.010532,
-.009,.010732,
-.008684,.010879,
-.008347,.01097,
-.008,.011,
.008,.011,
.008347,.01097,
.008684,.010879,
.009,.010732,
.009286,.010532,
.009532,.010286,
.009732,.01,
.009879,.009684,
.00997,.009347,
.01,.009,
0.0*
%
%ADD20MACRO20*%
%ADD99R,.047X.108*%
%ADD98C,.06*%
%ADD65C,.024*%
%ADD30R,.028X.126*%
%ADD24R,.108X.047*%
%ADD51R,.008X.035*%
%ADD49R,.035X.008*%
%ADD50R,.008X.027*%
%ADD48R,.027X.008*%
%AMMACRO37*
4,1,40,-.0155,-.016,
-.0155,.016,
-.015439,.016695,
-.015259,.017368,
-.014964,.018,
-.014564,.018571,
-.014071,.019064,
-.0135,.019464,
-.012868,.019759,
-.012195,.019939,
-.0115,.02,
.0115,.02,
.012195,.019939,
.012868,.019759,
.0135,.019464,
.014071,.019064,
.014564,.018571,
.014964,.018,
.015259,.017368,
.015439,.016695,
.0155,.016,
.0155,-.016,
.015439,-.016695,
.015259,-.017368,
.014964,-.018,
.014564,-.018571,
.014071,-.019064,
.0135,-.019464,
.012868,-.019759,
.012195,-.019939,
.0115,-.02,
-.0115,-.02,
-.012195,-.019939,
-.012868,-.019759,
-.0135,-.019464,
-.014071,-.019064,
-.014564,-.018571,
-.014964,-.018,
-.015259,-.017368,
-.015439,-.016695,
-.0155,-.016,
0.0*
%
%ADD37MACRO37*%
%ADD28C,.044*%
%ADD11C,.08*%
%ADD57C,.063*%
%AMMACRO36*
4,1,40,-.016,.0155,
.016,.0155,
.016695,.015439,
.017368,.015259,
.018,.014964,
.018571,.014564,
.019064,.014071,
.019464,.0135,
.019759,.012868,
.019939,.012195,
.02,.0115,
.02,-.0115,
.019939,-.012195,
.019759,-.012868,
.019464,-.0135,
.019064,-.014071,
.018571,-.014564,
.018,-.014964,
.017368,-.015259,
.016695,-.015439,
.016,-.0155,
-.016,-.0155,
-.016695,-.015439,
-.017368,-.015259,
-.018,-.014964,
-.018571,-.014564,
-.019064,-.014071,
-.019464,-.0135,
-.019759,-.012868,
-.019939,-.012195,
-.02,-.0115,
-.02,.0115,
-.019939,.012195,
-.019759,.012868,
-.019464,.0135,
-.019064,.014071,
-.018571,.014564,
-.018,.014964,
-.017368,.015259,
-.016695,.015439,
-.016,.0155,
0.0*
%
%ADD36MACRO36*%
%ADD29R,.028X.165*%
%ADD16C,.028*%
%ADD64C,.056*%
%ADD27C,.065*%
%AMMACRO70*
4,1,40,.002,-.016,
.003389,-.015878,
.004736,-.015518,
.006,-.014928,
.007142,-.014128,
.008128,-.013142,
.008928,-.012,
.009518,-.010736,
.009878,-.009389,
.01,-.008,
.01,.008,
.009878,.009389,
.009518,.010736,
.008928,.012,
.008128,.013142,
.007142,.014128,
.006,.014928,
.004736,.015518,
.003389,.015878,
.002,.016,
-.002,.016,
-.003389,.015878,
-.004736,.015518,
-.006,.014928,
-.007142,.014128,
-.008128,.013142,
-.008928,.012,
-.009518,.010736,
-.009878,.009389,
-.01,.008,
-.01,-.008,
-.009878,-.009389,
-.009518,-.010736,
-.008928,-.012,
-.008128,-.013142,
-.007142,-.014128,
-.006,-.014928,
-.004736,-.015518,
-.003389,-.015878,
-.002,-.016,
.002,-.016,
0.0*
%
%ADD70MACRO70*%
%ADD12C,.086*%
%AMMACRO97*
4,1,40,.0155,.016,
.0155,-.016,
.015439,-.016695,
.015259,-.017368,
.014964,-.018,
.014564,-.018571,
.014071,-.019064,
.0135,-.019464,
.012868,-.019759,
.012195,-.019939,
.0115,-.02,
-.0115,-.02,
-.012195,-.019939,
-.012868,-.019759,
-.0135,-.019464,
-.014071,-.019064,
-.014564,-.018571,
-.014964,-.018,
-.015259,-.017368,
-.015439,-.016695,
-.0155,-.016,
-.0155,.016,
-.015439,.016695,
-.015259,.017368,
-.014964,.018,
-.014564,.018571,
-.014071,.019064,
-.0135,.019464,
-.012868,.019759,
-.012195,.019939,
-.0115,.02,
.0115,.02,
.012195,.019939,
.012868,.019759,
.0135,.019464,
.014071,.019064,
.014564,.018571,
.014964,.018,
.015259,.017368,
.015439,.016695,
.0155,.016,
0.0*
%
%ADD97MACRO97*%
%AMMACRO38*
4,1,40,-.008,-.009,
.008,-.009,
.008347,-.00897,
.008684,-.008879,
.009,-.008732,
.009286,-.008532,
.009532,-.008286,
.009732,-.008,
.009879,-.007684,
.00997,-.007347,
.01,-.007,
.01,.007,
.00997,.007347,
.009879,.007684,
.009732,.008,
.009532,.008286,
.009286,.008532,
.009,.008732,
.008684,.008879,
.008347,.00897,
.008,.009,
-.008,.009,
-.008347,.00897,
-.008684,.008879,
-.009,.008732,
-.009286,.008532,
-.009532,.008286,
-.009732,.008,
-.009879,.007684,
-.00997,.007347,
-.01,.007,
-.01,-.007,
-.00997,-.007347,
-.009879,-.007684,
-.009732,-.008,
-.009532,-.008286,
-.009286,-.008532,
-.009,-.008732,
-.008684,-.008879,
-.008347,-.00897,
-.008,-.009,
0.0*
%
%ADD38MACRO38*%
%AMMACRO26*
4,1,40,.009,-.008,
.009,.008,
.00897,.008347,
.008879,.008684,
.008732,.009,
.008532,.009286,
.008286,.009532,
.008,.009732,
.007684,.009879,
.007347,.00997,
.007,.01,
-.007,.01,
-.007347,.00997,
-.007684,.009879,
-.008,.009732,
-.008286,.009532,
-.008532,.009286,
-.008732,.009,
-.008879,.008684,
-.00897,.008347,
-.009,.008,
-.009,-.008,
-.00897,-.008347,
-.008879,-.008684,
-.008732,-.009,
-.008532,-.009286,
-.008286,-.009532,
-.008,-.009732,
-.007684,-.009879,
-.007347,-.00997,
-.007,-.01,
.007,-.01,
.007347,-.00997,
.007684,-.009879,
.008,-.009732,
.008286,-.009532,
.008532,-.009286,
.008732,-.009,
.008879,-.008684,
.00897,-.008347,
.009,-.008,
0.0*
%
%ADD26MACRO26*%
%AMMACRO35*
4,1,40,.0055,-.0145,
.006889,-.014378,
.008236,-.014018,
.0095,-.013428,
.010642,-.012628,
.011628,-.011642,
.012428,-.0105,
.013018,-.009236,
.013378,-.007889,
.0135,-.0065,
.0135,.0065,
.013378,.007889,
.013018,.009236,
.012428,.0105,
.011628,.011642,
.010642,.012628,
.0095,.013428,
.008236,.014018,
.006889,.014378,
.0055,.0145,
-.0055,.0145,
-.006889,.014378,
-.008236,.014018,
-.0095,.013428,
-.010642,.012628,
-.011628,.011642,
-.012428,.0105,
-.013018,.009236,
-.013378,.007889,
-.0135,.0065,
-.0135,-.0065,
-.013378,-.007889,
-.013018,-.009236,
-.012428,-.0105,
-.011628,-.011642,
-.010642,-.012628,
-.0095,-.013428,
-.008236,-.014018,
-.006889,-.014378,
-.0055,-.0145,
.0055,-.0145,
0.0*
%
%ADD35MACRO35*%
%AMMACRO78*
4,1,6,.0135,.025,
-.0065,.005,
-.0135,.005,
-.0135,-.005,
-.0065,-.005,
.0135,-.025,
.0135,.025,
0.0*
%
%ADD78MACRO78*%
%AMMACRO61*
4,1,6,-.005,.0135,
-.005,.0065,
-.025,-.0135,
.025,-.0135,
.005,.0065,
.005,.0135,
-.005,.0135,
0.0*
%
%ADD61MACRO61*%
%AMMACRO96*
4,1,40,.0155,.016,
.0155,-.016,
.015439,-.016695,
.015259,-.017368,
.014964,-.018,
.014564,-.018571,
.014071,-.019064,
.0135,-.019464,
.012868,-.019759,
.012195,-.019939,
.0115,-.02,
-.0115,-.02,
-.012195,-.019939,
-.012868,-.019759,
-.0135,-.019464,
-.014071,-.019064,
-.014564,-.018571,
-.014964,-.018,
-.015259,-.017368,
-.015439,-.016695,
-.0155,-.016,
-.0155,.016,
-.015439,.016695,
-.015259,.017368,
-.014964,.018,
-.014564,.018571,
-.014071,.019064,
-.0135,.019464,
-.012868,.019759,
-.012195,.019939,
-.0115,.02,
.0115,.02,
.012195,.019939,
.012868,.019759,
.0135,.019464,
.014071,.019064,
.014564,.018571,
.014964,.018,
.015259,.017368,
.015439,.016695,
.0155,.016,
0.0*
%
%ADD96MACRO96*%
%AMMACRO39*
4,1,40,-.008,-.009,
.008,-.009,
.008347,-.00897,
.008684,-.008879,
.009,-.008732,
.009286,-.008532,
.009532,-.008286,
.009732,-.008,
.009879,-.007684,
.00997,-.007347,
.01,-.007,
.01,.007,
.00997,.007347,
.009879,.007684,
.009732,.008,
.009532,.008286,
.009286,.008532,
.009,.008732,
.008684,.008879,
.008347,.00897,
.008,.009,
-.008,.009,
-.008347,.00897,
-.008684,.008879,
-.009,.008732,
-.009286,.008532,
-.009532,.008286,
-.009732,.008,
-.009879,.007684,
-.00997,.007347,
-.01,.007,
-.01,-.007,
-.00997,-.007347,
-.009879,-.007684,
-.009732,-.008,
-.009532,-.008286,
-.009286,-.008532,
-.009,-.008732,
-.008684,-.008879,
-.008347,-.00897,
-.008,-.009,
0.0*
%
%ADD39MACRO39*%
%AMMACRO17*
4,1,40,.009,-.008,
.009,.008,
.00897,.008347,
.008879,.008684,
.008732,.009,
.008532,.009286,
.008286,.009532,
.008,.009732,
.007684,.009879,
.007347,.00997,
.007,.01,
-.007,.01,
-.007347,.00997,
-.007684,.009879,
-.008,.009732,
-.008286,.009532,
-.008532,.009286,
-.008732,.009,
-.008879,.008684,
-.00897,.008347,
-.009,.008,
-.009,-.008,
-.00897,-.008347,
-.008879,-.008684,
-.008732,-.009,
-.008532,-.009286,
-.008286,-.009532,
-.008,-.009732,
-.007684,-.009879,
-.007347,-.00997,
-.007,-.01,
.007,-.01,
.007347,-.00997,
.007684,-.009879,
.008,-.009732,
.008286,-.009532,
.008532,-.009286,
.008732,-.009,
.008879,-.008684,
.00897,-.008347,
.009,-.008,
0.0*
%
%ADD17MACRO17*%
%ADD63R,.03X.014*%
%ADD56R,.014X.03*%
%ADD93R,.022X.032*%
%ADD42R,.014X.032*%
%ADD41R,.032X.014*%
%ADD23R,.061X.012*%
%ADD95R,.032X.042*%
%ADD73R,.025X.012*%
%ADD68R,.014X.032*%
%ADD67R,.032X.014*%
%ADD60R,.034X.012*%
%ADD59R,.012X.034*%
%ADD75R,.012X.026*%
%ADD74R,.026X.012*%
%ADD14R,.042X.032*%
%ADD81R,.061X.024*%
%AMMACRO18*
4,1,40,.009,-.01,
-.009,-.01,
-.009347,-.00997,
-.009684,-.009879,
-.01,-.009732,
-.010286,-.009532,
-.010532,-.009286,
-.010732,-.009,
-.010879,-.008684,
-.01097,-.008347,
-.011,-.008,
-.011,.008,
-.01097,.008347,
-.010879,.008684,
-.010732,.009,
-.010532,.009286,
-.010286,.009532,
-.01,.009732,
-.009684,.009879,
-.009347,.00997,
-.009,.01,
.009,.01,
.009347,.00997,
.009684,.009879,
.01,.009732,
.010286,.009532,
.010532,.009286,
.010732,.009,
.010879,.008684,
.01097,.008347,
.011,.008,
.011,-.008,
.01097,-.008347,
.010879,-.008684,
.010732,-.009,
.010532,-.009286,
.010286,-.009532,
.01,-.009732,
.009684,-.009879,
.009347,-.00997,
.009,-.01,
0.0*
%
%ADD18MACRO18*%
%AMMACRO15*
4,1,40,-.01,-.009,
-.01,.009,
-.00997,.009347,
-.009879,.009684,
-.009732,.01,
-.009532,.010286,
-.009286,.010532,
-.009,.010732,
-.008684,.010879,
-.008347,.01097,
-.008,.011,
.008,.011,
.008347,.01097,
.008684,.010879,
.009,.010732,
.009286,.010532,
.009532,.010286,
.009732,.01,
.009879,.009684,
.00997,.009347,
.01,.009,
.01,-.009,
.00997,-.009347,
.009879,-.009684,
.009732,-.01,
.009532,-.010286,
.009286,-.010532,
.009,-.010732,
.008684,-.010879,
.008347,-.01097,
.008,-.011,
-.008,-.011,
-.008347,-.01097,
-.008684,-.010879,
-.009,-.010732,
-.009286,-.010532,
-.009532,-.010286,
-.009732,-.01,
-.009879,-.009684,
-.00997,-.009347,
-.01,-.009,
0.0*
%
%ADD15MACRO15*%
%ADD71R,.04X.073*%
%ADD47R,.012X.055*%
%ADD10C,.14*%
%ADD72R,.073X.04*%
%AMMACRO53*
4,1,40,.0155,.016,
.0155,-.016,
.015439,-.016695,
.015259,-.017368,
.014964,-.018,
.014564,-.018571,
.014071,-.019064,
.0135,-.019464,
.012868,-.019759,
.012195,-.019939,
.0115,-.02,
-.0115,-.02,
-.012195,-.019939,
-.012868,-.019759,
-.0135,-.019464,
-.014071,-.019064,
-.014564,-.018571,
-.014964,-.018,
-.015259,-.017368,
-.015439,-.016695,
-.0155,-.016,
-.0155,.016,
-.015439,.016695,
-.015259,.017368,
-.014964,.018,
-.014564,.018571,
-.014071,.019064,
-.0135,.019464,
-.012868,.019759,
-.012195,.019939,
-.0115,.02,
.0115,.02,
.012195,.019939,
.012868,.019759,
.0135,.019464,
.014071,.019064,
.014564,.018571,
.014964,.018,
.015259,.017368,
.015439,.016695,
.0155,.016,
0.0*
%
%ADD53MACRO53*%
%AMMACRO32*
4,1,40,.016,-.0155,
-.016,-.0155,
-.016695,-.015439,
-.017368,-.015259,
-.018,-.014964,
-.018571,-.014564,
-.019064,-.014071,
-.019464,-.0135,
-.019759,-.012868,
-.019939,-.012195,
-.02,-.0115,
-.02,.0115,
-.019939,.012195,
-.019759,.012868,
-.019464,.0135,
-.019064,.014071,
-.018571,.014564,
-.018,.014964,
-.017368,.015259,
-.016695,.015439,
-.016,.0155,
.016,.0155,
.016695,.015439,
.017368,.015259,
.018,.014964,
.018571,.014564,
.019064,.014071,
.019464,.0135,
.019759,.012868,
.019939,.012195,
.02,.0115,
.02,-.0115,
.019939,-.012195,
.019759,-.012868,
.019464,-.0135,
.019064,-.014071,
.018571,-.014564,
.018,-.014964,
.017368,-.015259,
.016695,-.015439,
.016,-.0155,
0.0*
%
%ADD32MACRO32*%
%ADD13R,.037X.061*%
%ADD83R,.138X.181*%
%ADD31R,.061X.037*%
%ADD25C,.126*%
%ADD79R,.071X.047*%
%AMMACRO92*
4,1,40,-.002,.016,
-.003389,.015878,
-.004736,.015518,
-.006,.014928,
-.007142,.014128,
-.008128,.013142,
-.008928,.012,
-.009518,.010736,
-.009878,.009389,
-.01,.008,
-.01,-.008,
-.009878,-.009389,
-.009518,-.010736,
-.008928,-.012,
-.008128,-.013142,
-.007142,-.014128,
-.006,-.014928,
-.004736,-.015518,
-.003389,-.015878,
-.002,-.016,
.002,-.016,
.003389,-.015878,
.004736,-.015518,
.006,-.014928,
.007142,-.014128,
.008128,-.013142,
.008928,-.012,
.009518,-.010736,
.009878,-.009389,
.01,-.008,
.01,.008,
.009878,.009389,
.009518,.010736,
.008928,.012,
.008128,.013142,
.007142,.014128,
.006,.014928,
.004736,.015518,
.003389,.015878,
.002,.016,
-.002,.016,
0.0*
%
%ADD92MACRO92*%
%ADD69O,.189X.126*%
%AMMACRO66*
4,1,40,-.016,-.002,
-.015878,-.003389,
-.015518,-.004736,
-.014928,-.006,
-.014128,-.007142,
-.013142,-.008128,
-.012,-.008928,
-.010736,-.009518,
-.009389,-.009878,
-.008,-.01,
.008,-.01,
.009389,-.009878,
.010736,-.009518,
.012,-.008928,
.013142,-.008128,
.014128,-.007142,
.014928,-.006,
.015518,-.004736,
.015878,-.003389,
.016,-.002,
.016,.002,
.015878,.003389,
.015518,.004736,
.014928,.006,
.014128,.007142,
.013142,.008128,
.012,.008928,
.010736,.009518,
.009389,.009878,
.008,.01,
-.008,.01,
-.009389,.009878,
-.010736,.009518,
-.012,.008928,
-.013142,.008128,
-.014128,.007142,
-.014928,.006,
-.015518,.004736,
-.015878,.003389,
-.016,.002,
-.016,-.002,
0.0*
%
%ADD66MACRO66*%
%ADD55R,.079X.022*%
%ADD54C,.119*%
%ADD82R,.177X.181*%
%ADD44R,.124X.124*%
%ADD80R,.075X.095*%
%ADD76R,.098X.072*%
%ADD52R,.165X.165*%
%ADD45R,.089X.076*%
%AMMACRO94*
4,1,40,-.0145,-.0055,
-.014378,-.006889,
-.014018,-.008236,
-.013428,-.0095,
-.012628,-.010642,
-.011642,-.011628,
-.0105,-.012428,
-.009236,-.013018,
-.007889,-.013378,
-.0065,-.0135,
.0065,-.0135,
.007889,-.013378,
.009236,-.013018,
.0105,-.012428,
.011642,-.011628,
.012628,-.010642,
.013428,-.0095,
.014018,-.008236,
.014378,-.006889,
.0145,-.0055,
.0145,.0055,
.014378,.006889,
.014018,.008236,
.013428,.0095,
.012628,.010642,
.011642,.011628,
.0105,.012428,
.009236,.013018,
.007889,.013378,
.0065,.0135,
-.0065,.0135,
-.007889,.013378,
-.009236,.013018,
-.0105,.012428,
-.011642,.011628,
-.012628,.010642,
-.013428,.0095,
-.014018,.008236,
-.014378,.006889,
-.0145,.0055,
-.0145,-.0055,
0.0*
%
%ADD94MACRO94*%
%AMMACRO21*
4,1,40,-.009,.008,
-.009,-.008,
-.00897,-.008347,
-.008879,-.008684,
-.008732,-.009,
-.008532,-.009286,
-.008286,-.009532,
-.008,-.009732,
-.007684,-.009879,
-.007347,-.00997,
-.007,-.01,
.007,-.01,
.007347,-.00997,
.007684,-.009879,
.008,-.009732,
.008286,-.009532,
.008532,-.009286,
.008732,-.009,
.008879,-.008684,
.00897,-.008347,
.009,-.008,
.009,.008,
.00897,.008347,
.008879,.008684,
.008732,.009,
.008532,.009286,
.008286,.009532,
.008,.009732,
.007684,.009879,
.007347,.00997,
.007,.01,
-.007,.01,
-.007347,.00997,
-.007684,.009879,
-.008,.009732,
-.008286,.009532,
-.008532,.009286,
-.008732,.009,
-.008879,.008684,
-.00897,.008347,
-.009,.008,
0.0*
%
%ADD21MACRO21*%
%AMMACRO33*
4,1,40,.008,.009,
-.008,.009,
-.008347,.00897,
-.008684,.008879,
-.009,.008732,
-.009286,.008532,
-.009532,.008286,
-.009732,.008,
-.009879,.007684,
-.00997,.007347,
-.01,.007,
-.01,-.007,
-.00997,-.007347,
-.009879,-.007684,
-.009732,-.008,
-.009532,-.008286,
-.009286,-.008532,
-.009,-.008732,
-.008684,-.008879,
-.008347,-.00897,
-.008,-.009,
.008,-.009,
.008347,-.00897,
.008684,-.008879,
.009,-.008732,
.009286,-.008532,
.009532,-.008286,
.009732,-.008,
.009879,-.007684,
.00997,-.007347,
.01,-.007,
.01,.007,
.00997,.007347,
.009879,.007684,
.009732,.008,
.009532,.008286,
.009286,.008532,
.009,.008732,
.008684,.008879,
.008347,.00897,
.008,.009,
0.0*
%
%ADD33MACRO33*%
%AMMACRO62*
4,1,6,-.025,.0135,
-.005,-.0065,
-.005,-.0135,
.005,-.0135,
.005,-.0065,
.025,.0135,
-.025,.0135,
0.0*
%
%ADD62MACRO62*%
%AMMACRO77*
4,1,6,.0135,.005,
.0065,.005,
-.0135,.025,
-.0135,-.025,
.0065,-.005,
.0135,-.005,
.0135,.005,
0.0*
%
%ADD77MACRO77*%
%AMMACRO22*
4,1,40,-.009,.008,
-.009,-.008,
-.00897,-.008347,
-.008879,-.008684,
-.008732,-.009,
-.008532,-.009286,
-.008286,-.009532,
-.008,-.009732,
-.007684,-.009879,
-.007347,-.00997,
-.007,-.01,
.007,-.01,
.007347,-.00997,
.007684,-.009879,
.008,-.009732,
.008286,-.009532,
.008532,-.009286,
.008732,-.009,
.008879,-.008684,
.00897,-.008347,
.009,-.008,
.009,.008,
.00897,.008347,
.008879,.008684,
.008732,.009,
.008532,.009286,
.008286,.009532,
.008,.009732,
.007684,.009879,
.007347,.00997,
.007,.01,
-.007,.01,
-.007347,.00997,
-.007684,.009879,
-.008,.009732,
-.008286,.009532,
-.008532,.009286,
-.008732,.009,
-.008879,.008684,
-.00897,.008347,
-.009,.008,
0.0*
%
%ADD22MACRO22*%
%ADD100C,.006*%
G75*
%LPD*%
G75*
G36*
G01X57574Y10330D02*
X390064D01*
Y32642D01*
X57574D01*
Y10330D01*
G37*
G54D100*
G01X70851Y-113865D02*
Y-96365D01*
G01X80021D02*
Y-113865D01*
G01Y-105115D02*
X70851D01*
G01X92936Y-113865D02*
X91626Y-113573D01*
X90316Y-112407D01*
X89442Y-110365D01*
X89006Y-108032D01*
X89442Y-105698D01*
X90316Y-103657D01*
X91626Y-102490D01*
X92936Y-102199D01*
X94246Y-102490D01*
X95556Y-103657D01*
X96429Y-105698D01*
X96648Y-108032D01*
X96429Y-110365D01*
X95556Y-112407D01*
X94246Y-113573D01*
X92936Y-113865D01*
G01X106724D02*
Y-102199D01*
G01Y-105115D02*
X107598Y-103657D01*
X108908Y-102490D01*
X110654Y-102199D01*
X112182Y-102490D01*
X113493Y-103657D01*
X114148Y-105698D01*
Y-113865D01*
G01X124661Y-105990D02*
X131648D01*
X130993Y-103948D01*
X129901Y-102782D01*
X128373Y-102199D01*
X126844Y-102490D01*
X125534Y-103365D01*
X124661Y-105407D01*
X124224Y-107157D01*
Y-108907D01*
X124661Y-110657D01*
X125753Y-112407D01*
X127063Y-113573D01*
X128591Y-113865D01*
X130119Y-113282D01*
X131648Y-111532D01*
G01X140851Y-119115D02*
X142161Y-119698D01*
X143908Y-119115D01*
X144999Y-117949D01*
X145873Y-116490D01*
X147182Y-111824D01*
X150021Y-102199D01*
G01X143034D02*
X147182Y-111824D01*
G01X182182Y-104532D02*
X183056Y-103657D01*
X183711Y-102199D01*
X184148Y-100156D01*
X183711Y-98407D01*
X182838Y-97240D01*
X181309Y-96365D01*
X175414D01*
Y-113865D01*
X182619D01*
X184148Y-112699D01*
X185021Y-110948D01*
X185458Y-108907D01*
X185021Y-106865D01*
X183711Y-105115D01*
X182182Y-104532D01*
X175414D01*
G01X201866Y-113865D02*
Y-102199D01*
G01Y-104240D02*
X200993Y-103074D01*
X199682Y-102490D01*
X198154Y-102199D01*
X196626Y-102782D01*
X195316Y-103948D01*
X194442Y-105698D01*
X194006Y-108032D01*
X194442Y-110365D01*
X195316Y-112115D01*
X196626Y-113282D01*
X198154Y-113865D01*
X199682Y-113573D01*
X200993Y-112699D01*
X201866Y-111532D01*
G01X219366Y-96365D02*
Y-113865D01*
G01Y-111241D02*
X218493Y-112699D01*
X217182Y-113573D01*
X215654Y-113865D01*
X213908Y-113282D01*
X212598Y-111824D01*
X211724Y-110074D01*
X211506Y-108032D01*
X211724Y-105990D01*
X212598Y-104240D01*
X213908Y-102782D01*
X215654Y-102199D01*
X217182Y-102490D01*
X218274Y-103074D01*
X219366Y-104240D01*
G01X229879Y-118240D02*
X231408Y-119407D01*
X233154Y-119698D01*
X234682Y-119407D01*
X235993Y-117949D01*
X236866Y-115907D01*
Y-102199D01*
G01Y-104532D02*
X235993Y-103365D01*
X234682Y-102490D01*
X233154Y-102199D01*
X231408Y-102782D01*
X230316Y-103948D01*
X229442Y-105990D01*
X229006Y-108032D01*
X229224Y-109782D01*
X230098Y-111824D01*
X231408Y-113282D01*
X233154Y-113865D01*
X234464Y-113573D01*
X235993Y-112407D01*
X236866Y-111241D01*
G01X247161Y-105990D02*
X254148D01*
X253493Y-103948D01*
X252401Y-102782D01*
X250873Y-102199D01*
X249344Y-102490D01*
X248034Y-103365D01*
X247161Y-105407D01*
X246724Y-107157D01*
Y-108907D01*
X247161Y-110657D01*
X248253Y-112407D01*
X249563Y-113573D01*
X251091Y-113865D01*
X252619Y-113282D01*
X254148Y-111532D01*
G01X264879Y-113865D02*
Y-102199D01*
G01Y-104532D02*
X265971Y-103365D01*
X267063Y-102490D01*
X268591Y-102199D01*
X269682Y-102490D01*
X270993Y-103365D01*
G01X298569Y-113865D02*
Y-96365D01*
X303809D01*
X305556Y-97240D01*
X306866Y-99282D01*
X307303Y-101615D01*
X306866Y-103948D01*
X305774Y-105698D01*
X303809Y-106574D01*
X298569D01*
G01X324366Y-113865D02*
Y-102199D01*
G01Y-104240D02*
X323493Y-103074D01*
X322182Y-102490D01*
X320654Y-102199D01*
X319126Y-102782D01*
X317816Y-103948D01*
X316942Y-105698D01*
X316506Y-108032D01*
X316942Y-110365D01*
X317816Y-112115D01*
X319126Y-113282D01*
X320654Y-113865D01*
X322182Y-113573D01*
X323493Y-112699D01*
X324366Y-111532D01*
G01X334224Y-113865D02*
Y-102199D01*
G01Y-105115D02*
X335098Y-103657D01*
X336408Y-102490D01*
X338154Y-102199D01*
X339682Y-102490D01*
X340993Y-103657D01*
X341648Y-105698D01*
Y-113865D01*
G01X355436Y-96365D02*
Y-113865D01*
G01X352379Y-102199D02*
X358493D01*
G01X369224Y-113865D02*
Y-96365D01*
G01Y-104823D02*
X370316Y-103365D01*
X371408Y-102490D01*
X373154Y-102199D01*
X374464Y-102490D01*
X375993Y-103657D01*
X376648Y-105407D01*
Y-113865D01*
G01X387161Y-105990D02*
X394148D01*
X393493Y-103948D01*
X392401Y-102782D01*
X390873Y-102199D01*
X389344Y-102490D01*
X388034Y-103365D01*
X387161Y-105407D01*
X386724Y-107157D01*
Y-108907D01*
X387161Y-110657D01*
X388253Y-112407D01*
X389563Y-113573D01*
X391091Y-113865D01*
X392619Y-113282D01*
X394148Y-111532D01*
G01X404879Y-113865D02*
Y-102199D01*
G01Y-104532D02*
X405971Y-103365D01*
X407063Y-102490D01*
X408591Y-102199D01*
X409682Y-102490D01*
X410993Y-103365D01*
G01X437259Y-113865D02*
Y-96365D01*
X442936Y-110948D01*
X448613Y-96365D01*
Y-113865D01*
G01X462182Y-104532D02*
X463056Y-103657D01*
X463711Y-102199D01*
X464148Y-100156D01*
X463711Y-98407D01*
X462838Y-97240D01*
X461309Y-96365D01*
X455414D01*
Y-113865D01*
X462619D01*
X464148Y-112699D01*
X465021Y-110948D01*
X465458Y-108907D01*
X465021Y-106865D01*
X463711Y-105115D01*
X462182Y-104532D01*
X455414D01*
G01X227259Y-68865D02*
Y-51365D01*
X232936Y-65948D01*
X238613Y-51365D01*
Y-68865D01*
G01X250436D02*
X249126Y-68573D01*
X247816Y-67407D01*
X246942Y-65365D01*
X246506Y-63032D01*
X246942Y-60698D01*
X247816Y-58657D01*
X249126Y-57490D01*
X250436Y-57199D01*
X251746Y-57490D01*
X253056Y-58657D01*
X253929Y-60698D01*
X254148Y-63032D01*
X253929Y-65365D01*
X253056Y-67407D01*
X251746Y-68573D01*
X250436Y-68865D01*
G01X271866Y-51365D02*
Y-68865D01*
G01Y-66241D02*
X270993Y-67699D01*
X269682Y-68573D01*
X268154Y-68865D01*
X266408Y-68282D01*
X265098Y-66824D01*
X264224Y-65074D01*
X264006Y-63032D01*
X264224Y-60990D01*
X265098Y-59240D01*
X266408Y-57782D01*
X268154Y-57199D01*
X269682Y-57490D01*
X270774Y-58074D01*
X271866Y-59240D01*
G01X282161Y-60990D02*
X289148D01*
X288493Y-58948D01*
X287401Y-57782D01*
X285873Y-57199D01*
X284344Y-57490D01*
X283034Y-58365D01*
X282161Y-60407D01*
X281724Y-62157D01*
Y-63907D01*
X282161Y-65657D01*
X283253Y-67407D01*
X284563Y-68573D01*
X286091Y-68865D01*
X287619Y-68282D01*
X289148Y-66532D01*
G01X302936Y-68865D02*
Y-51365D01*
G01X542319Y-68865D02*
Y-51365D01*
X547559D01*
X549306Y-52240D01*
X550616Y-54282D01*
X551053Y-56615D01*
X550616Y-58948D01*
X549524Y-60698D01*
X547559Y-61574D01*
X542319D01*
G01X568989Y-52824D02*
X567679Y-51948D01*
X566151Y-51365D01*
X564404D01*
X562439Y-52240D01*
X560911Y-53698D01*
X559819Y-55449D01*
X558946Y-58365D01*
X558727Y-60990D01*
X559164Y-63615D01*
X559819Y-65365D01*
X561129Y-67115D01*
X562658Y-68282D01*
X564186Y-68865D01*
X565714D01*
X567243Y-68282D01*
X568553Y-67407D01*
X569645Y-66241D01*
G01X583432Y-59532D02*
X584306Y-58657D01*
X584961Y-57199D01*
X585398Y-55156D01*
X584961Y-53407D01*
X584088Y-52240D01*
X582559Y-51365D01*
X576664D01*
Y-68865D01*
X583869D01*
X585398Y-67699D01*
X586271Y-65948D01*
X586708Y-63907D01*
X586271Y-61865D01*
X584961Y-60115D01*
X583432Y-59532D01*
X576664D01*
G01X592636Y-74698D02*
X605736D01*
G01X611664Y-68865D02*
Y-51365D01*
X621708Y-68865D01*
Y-51365D01*
G01X634186Y-68865D02*
X632439Y-68573D01*
X630911Y-67407D01*
X629601Y-65657D01*
X628727Y-63615D01*
X628291Y-61282D01*
Y-58948D01*
X628727Y-56615D01*
X629601Y-54573D01*
X630911Y-52824D01*
X632439Y-51657D01*
X634186Y-51365D01*
X635932Y-51657D01*
X637461Y-52824D01*
X638771Y-54573D01*
X639645Y-56615D01*
X640081Y-58948D01*
Y-61282D01*
X639645Y-63615D01*
X638771Y-65657D01*
X637461Y-67407D01*
X635932Y-68573D01*
X634186Y-68865D01*
G01X555436Y-113865D02*
Y-96365D01*
X552816Y-99865D01*
G01Y-113865D02*
X558056D01*
G01X568133Y-110365D02*
X569442Y-112407D01*
X571189Y-113573D01*
X573154Y-113865D01*
X574901Y-113573D01*
X576648Y-112115D01*
X577739Y-110365D01*
X577958Y-108615D01*
X577521Y-106574D01*
X575993Y-105115D01*
X574464Y-104532D01*
X572499D01*
G01X574464D02*
X575774Y-103657D01*
X576866Y-102199D01*
X577303Y-100449D01*
X576866Y-98698D01*
X575774Y-97240D01*
X573809Y-96365D01*
X571844Y-96657D01*
X569879Y-97824D01*
G01X590436Y-113865D02*
Y-96365D01*
X587816Y-99865D01*
G01Y-113865D02*
X593056D01*
G01X603133Y-110365D02*
X604442Y-112407D01*
X606189Y-113573D01*
X608154Y-113865D01*
X609901Y-113573D01*
X611648Y-112115D01*
X612739Y-110365D01*
X612958Y-108615D01*
X612521Y-106574D01*
X610993Y-105115D01*
X609464Y-104532D01*
X607499D01*
G01X609464D02*
X610774Y-103657D01*
X611866Y-102199D01*
X612303Y-100449D01*
X611866Y-98698D01*
X610774Y-97240D01*
X608809Y-96365D01*
X606844Y-96657D01*
X604879Y-97824D01*
G01X625436Y-96365D02*
X623689Y-96948D01*
X622379Y-98407D01*
X621506Y-100156D01*
X620851Y-102490D01*
X620633Y-105115D01*
X620851Y-107740D01*
X621506Y-110074D01*
X622379Y-111824D01*
X623689Y-113282D01*
X625436Y-113865D01*
X627182Y-113282D01*
X628493Y-111824D01*
X629366Y-110074D01*
X630021Y-107740D01*
X630239Y-105115D01*
X630021Y-102490D01*
X629366Y-100156D01*
X628493Y-98407D01*
X627182Y-96948D01*
X625436Y-96365D01*
G01X685027Y-51365D02*
X690486Y-68865D01*
X695945Y-51365D01*
G01X712353Y-68865D02*
X703619D01*
Y-51365D01*
X712353D01*
G01X708859Y-59823D02*
X703619D01*
G01X721119Y-68865D02*
Y-51365D01*
X726578D01*
X728324Y-52240D01*
X729416Y-53407D01*
X729853Y-55740D01*
X729416Y-58074D01*
X728106Y-59532D01*
X726578Y-60407D01*
X721119D01*
G01X726578D02*
X729853Y-68865D01*
G01X742986Y-69448D02*
X742549Y-69157D01*
Y-68573D01*
X742986Y-68282D01*
X743423Y-68573D01*
Y-69157D01*
X742986Y-69448D01*
G01X707986Y-113865D02*
Y-96365D01*
X705366Y-99865D01*
G01Y-113865D02*
X710606D01*
G01X727232Y-104532D02*
X728106Y-103657D01*
X728761Y-102199D01*
X729198Y-100156D01*
X728761Y-98407D01*
X727888Y-97240D01*
X726359Y-96365D01*
X720464D01*
Y-113865D01*
X727669D01*
X729198Y-112699D01*
X730071Y-110948D01*
X730508Y-108907D01*
X730071Y-106865D01*
X728761Y-105115D01*
X727232Y-104532D01*
X720464D01*
G01X891190D02*
X890316Y-103657D01*
X889661Y-102199D01*
X889224Y-100156D01*
X889661Y-98407D01*
X890534Y-97240D01*
X892063Y-96365D01*
X897958D01*
Y-113865D01*
X890753D01*
X889224Y-112699D01*
X888351Y-110948D01*
X887914Y-108907D01*
X888351Y-106865D01*
X889661Y-105115D01*
X891190Y-104532D01*
X897958D01*
G01X881113Y-113865D02*
Y-96365D01*
X875436Y-110948D01*
X869759Y-96365D01*
Y-113865D01*
G01X863395D02*
X857936Y-96365D01*
X852477Y-113865D01*
G01X854443Y-107740D02*
X861430D01*
G01X845021Y-111532D02*
X843274Y-112990D01*
X841309Y-113865D01*
X839563D01*
X837816Y-112990D01*
X836506Y-111532D01*
X835851Y-109490D01*
X836288Y-107449D01*
X837379Y-105698D01*
X839344Y-104532D01*
X841964Y-103948D01*
X843493Y-102782D01*
X844148Y-100740D01*
X843711Y-98698D01*
X842619Y-97240D01*
X841091Y-96365D01*
X839563D01*
X838034Y-96948D01*
X836724Y-98407D01*
G01X827739Y-113865D02*
Y-96365D01*
G01X819443D02*
X827739Y-107157D01*
G01X818133Y-113865D02*
X824028Y-102199D01*
G01X818569Y-51365D02*
Y-68865D01*
X827303D01*
G01X844366D02*
Y-57199D01*
G01Y-59240D02*
X843493Y-58074D01*
X842182Y-57490D01*
X840654Y-57199D01*
X839126Y-57782D01*
X837816Y-58948D01*
X836942Y-60698D01*
X836506Y-63032D01*
X836942Y-65365D01*
X837816Y-67115D01*
X839126Y-68282D01*
X840654Y-68865D01*
X842182Y-68573D01*
X843493Y-67699D01*
X844366Y-66532D01*
G01X853351Y-74115D02*
X854661Y-74698D01*
X856408Y-74115D01*
X857499Y-72949D01*
X858373Y-71490D01*
X859682Y-66824D01*
X862521Y-57199D01*
G01X855534D02*
X859682Y-66824D01*
G01X872161Y-60990D02*
X879148D01*
X878493Y-58948D01*
X877401Y-57782D01*
X875873Y-57199D01*
X874344Y-57490D01*
X873034Y-58365D01*
X872161Y-60407D01*
X871724Y-62157D01*
Y-63907D01*
X872161Y-65657D01*
X873253Y-67407D01*
X874563Y-68573D01*
X876091Y-68865D01*
X877619Y-68282D01*
X879148Y-66532D01*
G01X889879Y-68865D02*
Y-57199D01*
G01Y-59532D02*
X890971Y-58365D01*
X892063Y-57490D01*
X893591Y-57199D01*
X894682Y-57490D01*
X895993Y-58365D01*
G01X943619Y-110365D02*
X944711Y-112115D01*
X946021Y-113282D01*
X947549Y-113865D01*
X949296Y-113282D01*
X950606Y-112115D01*
X951916Y-110365D01*
X952353Y-108032D01*
Y-96365D01*
G01X965486Y-113865D02*
X963739Y-113573D01*
X962211Y-112407D01*
X960901Y-110657D01*
X960027Y-108615D01*
X959591Y-106282D01*
Y-103948D01*
X960027Y-101615D01*
X960901Y-99573D01*
X962211Y-97824D01*
X963739Y-96657D01*
X965486Y-96365D01*
X967232Y-96657D01*
X968761Y-97824D01*
X970071Y-99573D01*
X970945Y-101615D01*
X971381Y-103948D01*
Y-106282D01*
X970945Y-108615D01*
X970071Y-110657D01*
X968761Y-112407D01*
X967232Y-113573D01*
X965486Y-113865D01*
G01X978401Y-111532D02*
X980148Y-112990D01*
X982113Y-113865D01*
X983859D01*
X985606Y-112990D01*
X986916Y-111532D01*
X987571Y-109490D01*
X987134Y-107449D01*
X986043Y-105698D01*
X984078Y-104532D01*
X981458Y-103948D01*
X979929Y-102782D01*
X979274Y-100740D01*
X979711Y-98698D01*
X980803Y-97240D01*
X982331Y-96365D01*
X983859D01*
X985388Y-96948D01*
X986698Y-98407D01*
G01X1004853Y-113865D02*
X996119D01*
Y-96365D01*
X1004853D01*
G01X1001359Y-104823D02*
X996119D01*
G01X1013619Y-113865D02*
Y-96365D01*
X1018859D01*
X1020606Y-97240D01*
X1021916Y-99282D01*
X1022353Y-101615D01*
X1021916Y-103948D01*
X1020824Y-105698D01*
X1018859Y-106574D01*
X1013619D01*
G01X1030901Y-113865D02*
Y-96365D01*
G01X1040071D02*
Y-113865D01*
G01Y-105115D02*
X1030901D01*
G01X1066119Y-96365D02*
Y-113865D01*
X1074853D01*
G01X1082527D02*
X1087986Y-96365D01*
X1093445Y-113865D01*
G01X1091479Y-107740D02*
X1084492D01*
G01X1100683Y-96365D02*
Y-108907D01*
X1101556Y-111532D01*
X1103303Y-113282D01*
X1105486Y-113865D01*
X1107669Y-113282D01*
X1109416Y-111532D01*
X1110289Y-108907D01*
Y-96365D01*
G01X960683Y-68865D02*
Y-51365D01*
X965049D01*
X966796Y-52240D01*
X968106Y-53407D01*
X969198Y-55156D01*
X970071Y-57199D01*
X970289Y-60115D01*
X970071Y-63032D01*
X969198Y-65074D01*
X968106Y-66824D01*
X966796Y-67990D01*
X965049Y-68865D01*
X960683D01*
G01X979711Y-60990D02*
X986698D01*
X986043Y-58948D01*
X984951Y-57782D01*
X983423Y-57199D01*
X981894Y-57490D01*
X980584Y-58365D01*
X979711Y-60407D01*
X979274Y-62157D01*
Y-63907D01*
X979711Y-65657D01*
X980803Y-67407D01*
X982113Y-68573D01*
X983641Y-68865D01*
X985169Y-68282D01*
X986698Y-66532D01*
G01X997211Y-66824D02*
X998303Y-67990D01*
X999831Y-68865D01*
X1001141D01*
X1002451Y-68282D01*
X1003324Y-67407D01*
X1003761Y-66241D01*
X1003543Y-64490D01*
X1002669Y-63615D01*
X998739Y-61865D01*
X997866Y-59823D01*
X998303Y-58365D01*
X999176Y-57490D01*
X1000486Y-57199D01*
X1001796Y-57490D01*
X1003106Y-58365D01*
G01X1017986Y-57199D02*
Y-68865D01*
G01Y-52532D02*
X1017549Y-52240D01*
Y-51657D01*
X1017986Y-51365D01*
X1018423Y-51657D01*
Y-52240D01*
X1017986Y-52532D01*
G01X1032429Y-73240D02*
X1033958Y-74407D01*
X1035704Y-74698D01*
X1037232Y-74407D01*
X1038543Y-72949D01*
X1039416Y-70907D01*
Y-57199D01*
G01Y-59532D02*
X1038543Y-58365D01*
X1037232Y-57490D01*
X1035704Y-57199D01*
X1033958Y-57782D01*
X1032866Y-58948D01*
X1031992Y-60990D01*
X1031556Y-63032D01*
X1031774Y-64782D01*
X1032648Y-66824D01*
X1033958Y-68282D01*
X1035704Y-68865D01*
X1037014Y-68573D01*
X1038543Y-67407D01*
X1039416Y-66241D01*
G01X1049274Y-68865D02*
Y-57199D01*
G01Y-60115D02*
X1050148Y-58657D01*
X1051458Y-57490D01*
X1053204Y-57199D01*
X1054732Y-57490D01*
X1056043Y-58657D01*
X1056698Y-60698D01*
Y-68865D01*
G01X1067211Y-60990D02*
X1074198D01*
X1073543Y-58948D01*
X1072451Y-57782D01*
X1070923Y-57199D01*
X1069394Y-57490D01*
X1068084Y-58365D01*
X1067211Y-60407D01*
X1066774Y-62157D01*
Y-63907D01*
X1067211Y-65657D01*
X1068303Y-67407D01*
X1069613Y-68573D01*
X1071141Y-68865D01*
X1072669Y-68282D01*
X1074198Y-66532D01*
G01X1084929Y-68865D02*
Y-57199D01*
G01Y-59532D02*
X1086021Y-58365D01*
X1087113Y-57490D01*
X1088641Y-57199D01*
X1089732Y-57490D01*
X1091043Y-58365D01*
G01X1131686Y-113865D02*
Y-96365D01*
X1129066Y-99865D01*
G01Y-113865D02*
X1134306D01*
G01X1149186D02*
Y-96365D01*
X1146566Y-99865D01*
G01Y-113865D02*
X1151806D01*
G01X1162756Y-114448D02*
X1170616Y-96365D01*
G01X1184186Y-113865D02*
Y-96365D01*
X1181566Y-99865D01*
G01Y-113865D02*
X1186806D01*
G01X1196883Y-110365D02*
X1198192Y-112407D01*
X1199939Y-113573D01*
X1201904Y-113865D01*
X1203651Y-113573D01*
X1205398Y-112115D01*
X1206489Y-110365D01*
X1206708Y-108615D01*
X1206271Y-106574D01*
X1204743Y-105115D01*
X1203214Y-104532D01*
X1201249D01*
G01X1203214D02*
X1204524Y-103657D01*
X1205616Y-102199D01*
X1206053Y-100449D01*
X1205616Y-98698D01*
X1204524Y-97240D01*
X1202559Y-96365D01*
X1200594Y-96657D01*
X1198629Y-97824D01*
G01X1215256Y-114448D02*
X1223116Y-96365D01*
G01X1232538Y-99282D02*
X1233848Y-97532D01*
X1235376Y-96657D01*
X1237123Y-96365D01*
X1239306Y-96948D01*
X1240834Y-98407D01*
X1241271Y-100156D01*
X1241053Y-101907D01*
X1240179Y-103365D01*
X1235813Y-106282D01*
X1233848Y-108323D01*
X1232538Y-111241D01*
X1232101Y-113865D01*
X1241271D01*
G01X1254186Y-96365D02*
X1252439Y-96948D01*
X1251129Y-98407D01*
X1250256Y-100156D01*
X1249601Y-102490D01*
X1249383Y-105115D01*
X1249601Y-107740D01*
X1250256Y-110074D01*
X1251129Y-111824D01*
X1252439Y-113282D01*
X1254186Y-113865D01*
X1255932Y-113282D01*
X1257243Y-111824D01*
X1258116Y-110074D01*
X1258771Y-107740D01*
X1258989Y-105115D01*
X1258771Y-102490D01*
X1258116Y-100156D01*
X1257243Y-98407D01*
X1255932Y-96948D01*
X1254186Y-96365D01*
G01X1271686Y-113865D02*
Y-96365D01*
X1269066Y-99865D01*
G01Y-113865D02*
X1274306D01*
G01X1291806D02*
Y-96365D01*
X1283727Y-108907D01*
X1294645D01*
G01X1179383Y-68865D02*
Y-51365D01*
X1183749D01*
X1185496Y-52240D01*
X1186806Y-53407D01*
X1187898Y-55156D01*
X1188771Y-57199D01*
X1188989Y-60115D01*
X1188771Y-63032D01*
X1187898Y-65074D01*
X1186806Y-66824D01*
X1185496Y-67990D01*
X1183749Y-68865D01*
X1179383D01*
G01X1205616D02*
Y-57199D01*
G01Y-59240D02*
X1204743Y-58074D01*
X1203432Y-57490D01*
X1201904Y-57199D01*
X1200376Y-57782D01*
X1199066Y-58948D01*
X1198192Y-60698D01*
X1197756Y-63032D01*
X1198192Y-65365D01*
X1199066Y-67115D01*
X1200376Y-68282D01*
X1201904Y-68865D01*
X1203432Y-68573D01*
X1204743Y-67699D01*
X1205616Y-66532D01*
G01X1219186Y-51365D02*
Y-68865D01*
G01X1216129Y-57199D02*
X1222243D01*
G01X1233411Y-60990D02*
X1240398D01*
X1239743Y-58948D01*
X1238651Y-57782D01*
X1237123Y-57199D01*
X1235594Y-57490D01*
X1234284Y-58365D01*
X1233411Y-60407D01*
X1232974Y-62157D01*
Y-63907D01*
X1233411Y-65657D01*
X1234503Y-67407D01*
X1235813Y-68573D01*
X1237341Y-68865D01*
X1238869Y-68282D01*
X1240398Y-66532D01*
G54D10*
X-19686Y15748D03*
Y573228D03*
X846455Y15748D03*
Y573228D03*
G54D11*
X-11600Y33200D03*
X18400Y76200D03*
X22000Y168500D03*
X24000Y280000D03*
X130000Y72000D03*
X165000Y211500D03*
X394100Y57700D03*
X799500Y10500D03*
X833100Y564800D03*
X842500Y35000D03*
G54D20*
X26000Y124800D03*
Y128200D03*
X61500Y268900D03*
Y272300D03*
X75500Y253300D03*
Y256700D03*
X78500Y253300D03*
Y256700D03*
X120800Y128900D03*
Y132300D03*
X124000Y209300D03*
Y212700D03*
X140500Y78800D03*
Y82200D03*
X143500Y85800D03*
Y89200D03*
X160000Y60900D03*
Y64300D03*
X157000Y60900D03*
Y64300D03*
X170800Y64400D03*
Y67800D03*
X163000Y164800D03*
Y168200D03*
X186500Y60900D03*
Y64300D03*
X173800Y64400D03*
Y67800D03*
X178600Y109800D03*
Y113200D03*
X181600Y109800D03*
Y113200D03*
X189500Y60900D03*
Y64300D03*
X207400Y84500D03*
Y87900D03*
X257800Y86800D03*
Y90200D03*
Y80200D03*
Y83600D03*
X277000Y49300D03*
Y52700D03*
X271000Y180300D03*
Y183700D03*
X277500Y208800D03*
Y212200D03*
X269500Y240800D03*
Y244200D03*
X278700Y237800D03*
Y241200D03*
X283100Y88100D03*
Y91500D03*
X290200Y151000D03*
Y154400D03*
X309000Y91400D03*
Y94800D03*
X304500Y144300D03*
Y147700D03*
X298500Y241800D03*
Y245200D03*
X324500Y94800D03*
Y98200D03*
X321500Y94800D03*
Y98200D03*
X315000Y91400D03*
Y94800D03*
X312000Y91400D03*
Y94800D03*
X319000Y257300D03*
X322500D03*
X315500D03*
X319000Y260700D03*
X322500D03*
X315500D03*
X339500Y247300D03*
Y250700D03*
X344840Y100940D03*
Y104340D03*
X341840Y100940D03*
Y104340D03*
X347500Y135900D03*
X350000Y129300D03*
Y132700D03*
X347500Y139300D03*
X348000Y180300D03*
Y183700D03*
X363500Y51300D03*
Y54700D03*
X377500Y143300D03*
Y146700D03*
X393500Y84600D03*
Y88000D03*
X396496Y105863D03*
Y109263D03*
X395000Y256800D03*
Y260200D03*
X398000Y267300D03*
Y270700D03*
X403000Y263300D03*
Y266700D03*
X414500Y60800D03*
Y64200D03*
X403500Y105863D03*
Y109263D03*
X434000Y50800D03*
Y54200D03*
X479000Y269000D03*
Y272400D03*
X475500Y269000D03*
Y272400D03*
X510000Y234300D03*
Y237700D03*
X520000Y234300D03*
Y237700D03*
X701000Y165800D03*
Y169200D03*
X726200Y102100D03*
Y105500D03*
X729400Y102100D03*
Y105500D03*
X735000Y123100D03*
Y126500D03*
X751500Y108300D03*
Y111700D03*
X748500Y108300D03*
Y111700D03*
G54D21*
X23000Y138500D03*
X61000Y251500D03*
Y254500D03*
Y261700D03*
Y264800D03*
X72100Y241700D03*
X122500Y175000D03*
X129000Y172000D03*
X150500Y168000D03*
X257800Y76200D03*
X269000Y126300D03*
X278400Y153200D03*
X280000Y138500D03*
X326000Y85000D03*
X315500Y88300D03*
X353650Y131700D03*
Y134700D03*
X367000Y103000D03*
Y100000D03*
Y106000D03*
X362100Y121500D03*
X363500Y118500D03*
X371000Y146000D03*
X358400Y151900D03*
X376500Y77500D03*
X380500Y139500D03*
X383500Y152500D03*
X373280Y184610D03*
X400000Y131063D03*
X401542Y169124D03*
X405000Y134063D03*
X405012Y140238D03*
X405000Y137063D03*
X405200Y176063D03*
Y173063D03*
X411000Y208000D03*
X434000Y188500D03*
X441000Y114563D03*
Y111563D03*
X434500Y200063D03*
X463500Y24000D03*
X510000Y50507D03*
X512000Y126000D03*
Y122500D03*
X525000Y125500D03*
X541500Y179000D03*
X543000Y96000D03*
Y93000D03*
X567000Y92500D03*
X588000Y179000D03*
X596000Y142000D03*
X641500Y285000D03*
X719000Y116500D03*
X733200Y111900D03*
X733300Y108700D03*
X734900Y130900D03*
X734800Y137100D03*
X802000Y121500D03*
Y125000D03*
X802200Y155300D03*
X802900Y166700D03*
G54D12*
X11500Y68500D03*
X12000Y279000D03*
X816000Y280000D03*
G54D30*
X64370Y26342D03*
G54D22*
X26000Y138500D03*
X64000Y251500D03*
Y254500D03*
Y261700D03*
Y264800D03*
X75100Y241700D03*
X125500Y175000D03*
X132000Y172000D03*
X153500Y168000D03*
X260800Y76200D03*
X272000Y126300D03*
X283000Y138500D03*
X281400Y153200D03*
X318500Y88300D03*
X329000Y85000D03*
X356650Y131700D03*
Y134700D03*
X370000Y103000D03*
Y100000D03*
Y106000D03*
X365100Y121500D03*
X366500Y118500D03*
X361400Y151900D03*
X379500Y77500D03*
X383500Y139500D03*
X374000Y146000D03*
X386500Y152500D03*
X376280Y184610D03*
X403000Y131063D03*
X408000Y134063D03*
X408012Y140238D03*
X408000Y137063D03*
X408200Y176063D03*
Y173063D03*
X404542Y169124D03*
X414000Y208000D03*
X444000Y114563D03*
Y111563D03*
X437000Y188500D03*
X437500Y200063D03*
X466500Y24000D03*
X513000Y50507D03*
X515000Y126000D03*
Y122500D03*
X528000Y125500D03*
X546000Y96000D03*
Y93000D03*
X544500Y179000D03*
X570000Y92500D03*
X599000Y142000D03*
X591000Y179000D03*
X644500Y285000D03*
X722000Y116500D03*
X736200Y111900D03*
X736300Y108700D03*
X737900Y130900D03*
X737800Y137100D03*
X805000Y121500D03*
Y125000D03*
X805200Y155300D03*
X805900Y166700D03*
G54D31*
X60500Y120200D03*
Y126800D03*
X109500Y166200D03*
Y172800D03*
X117000Y166200D03*
Y172800D03*
X292700Y75100D03*
Y81700D03*
X339500Y56200D03*
Y62800D03*
X347000Y56200D03*
Y62800D03*
X357000Y271300D03*
Y264700D03*
X369500Y52200D03*
Y58800D03*
X377000Y52200D03*
Y58800D03*
X439900Y175700D03*
Y182300D03*
X447000Y175700D03*
Y182300D03*
X449500Y269800D03*
Y263200D03*
X589500Y230200D03*
X582000D03*
X589500Y236800D03*
X582000D03*
X615900Y47207D03*
Y53807D03*
X608800Y47207D03*
Y53807D03*
X634500Y230200D03*
Y236800D03*
X642000Y230200D03*
Y236800D03*
X676700Y47407D03*
Y54007D03*
X669600Y47407D03*
Y54007D03*
X767500Y122200D03*
Y128800D03*
X803200Y179500D03*
Y172900D03*
G54D13*
X18500Y111500D03*
X25100D03*
X25600Y149700D03*
X19000D03*
X25600Y156800D03*
X19000D03*
X103300Y174000D03*
X96700D03*
X103300Y181500D03*
X96700D03*
X275600Y60900D03*
X273100Y68000D03*
X279700D03*
X282200Y60900D03*
X305800Y64400D03*
X299200D03*
X305800Y71600D03*
X299200D03*
X365300Y247000D03*
X358700D03*
X365300Y254500D03*
X358700D03*
X426700Y85000D03*
X433300D03*
X431200Y205500D03*
X437800D03*
X787200Y101000D03*
Y108500D03*
X781700Y230600D03*
X775100D03*
X781700Y238000D03*
X775100D03*
X793800Y101000D03*
Y108500D03*
X797800Y229400D03*
X804400D03*
X797800Y222300D03*
X804400D03*
X797800Y239000D03*
X804400D03*
X797800Y246200D03*
X804400D03*
X803300Y279500D03*
X796700D03*
G54D40*
X100000Y61000D03*
X125500Y132600D03*
X221800Y48100D03*
X333270Y141240D03*
X438500Y279000D03*
G54D32*
X63000Y198900D03*
Y204100D03*
X68000Y198900D03*
Y204100D03*
X88800Y218900D03*
Y224100D03*
X109000Y124900D03*
Y130100D03*
X103500Y124900D03*
Y130100D03*
X123500Y164900D03*
Y170100D03*
X157000Y201900D03*
Y207100D03*
X343000Y115900D03*
Y121100D03*
X380500Y68463D03*
Y73663D03*
X376500Y202900D03*
Y208100D03*
X381500Y202900D03*
Y208100D03*
X512500Y56407D03*
Y61607D03*
X517500Y219400D03*
Y224600D03*
X512500Y219400D03*
Y224600D03*
X522500Y219400D03*
Y224600D03*
X622000Y46907D03*
Y52107D03*
X650500Y46907D03*
Y52107D03*
X645300Y49507D03*
Y54707D03*
X747500Y61900D03*
Y67100D03*
X762000Y144400D03*
Y149600D03*
X797000Y173400D03*
Y178600D03*
G54D14*
X19000Y174931D03*
Y180069D03*
X265500Y87931D03*
Y93069D03*
G54D23*
X21949Y194685D03*
Y196653D03*
Y198622D03*
Y200590D03*
Y202559D03*
Y212401D03*
Y214370D03*
Y216338D03*
Y218307D03*
Y220275D03*
Y222244D03*
Y224212D03*
Y226181D03*
Y228149D03*
Y230118D03*
Y232086D03*
Y234055D03*
Y236023D03*
Y237992D03*
Y239960D03*
Y241929D03*
Y243897D03*
Y249803D03*
Y251771D03*
Y253740D03*
Y255708D03*
Y245866D03*
Y247834D03*
Y257677D03*
Y259645D03*
Y261614D03*
Y263582D03*
Y265551D03*
Y267519D03*
X51674Y195669D03*
Y197637D03*
Y199606D03*
Y201574D03*
Y211417D03*
Y213385D03*
Y215354D03*
Y217322D03*
Y219291D03*
Y221259D03*
Y223228D03*
Y225196D03*
Y227165D03*
Y229133D03*
Y231102D03*
Y233071D03*
Y235039D03*
Y237008D03*
Y238976D03*
Y240945D03*
Y242913D03*
Y250787D03*
Y252756D03*
Y254724D03*
Y256693D03*
Y244882D03*
Y246850D03*
Y248819D03*
Y258661D03*
Y260630D03*
Y262598D03*
Y264567D03*
Y266535D03*
G54D41*
X110517Y196537D03*
Y193978D03*
Y191419D03*
Y188860D03*
Y186301D03*
X129003D03*
Y188860D03*
Y191419D03*
Y193978D03*
Y196537D03*
G54D50*
X171885Y181048D03*
Y203970D03*
X189207Y181048D03*
Y203970D03*
G54D33*
X58500Y191000D03*
X61500D03*
X79500Y51500D03*
X67500Y191000D03*
X64500D03*
X68000Y238000D03*
X82500Y51500D03*
X88500D03*
X85500D03*
X85200Y242000D03*
X103250Y51500D03*
X100250D03*
X105500Y195000D03*
X119000Y51500D03*
X116000D03*
X134800D03*
X131800D03*
X132700Y189600D03*
X150515Y51500D03*
X147515D03*
X166263D03*
X163263D03*
X160100Y187000D03*
X182000Y51500D03*
X179000D03*
X178000Y167500D03*
X201500Y68500D03*
X204500D03*
X237000Y60300D03*
X268000Y55000D03*
X271000D03*
X275500Y244500D03*
X272500D03*
X290000Y55000D03*
X287000D03*
X286100Y80700D03*
X305000Y54500D03*
X308000D03*
X310500Y63500D03*
X304500Y222000D03*
X302000Y245100D03*
X305000D03*
X316000Y54500D03*
X319000D03*
X334000Y58500D03*
X354000Y66000D03*
X353000Y143500D03*
X364500Y131500D03*
X370300Y134500D03*
X365000Y149500D03*
X359000Y143000D03*
Y177000D03*
X377500Y134500D03*
X374500D03*
X386500Y171500D03*
X378220Y173540D03*
X395500Y78000D03*
X392000D03*
X393496Y109063D03*
X389500Y159263D03*
X390000Y165100D03*
Y171500D03*
X398000Y256000D03*
X410000Y109063D03*
X407000D03*
X416000D03*
X413000D03*
X406000Y266500D03*
X422000Y109063D03*
X419000D03*
X421142Y184024D03*
X436000Y110563D03*
X434900Y149500D03*
X441000Y143000D03*
X601100Y236500D03*
X617800Y236400D03*
X613200Y236100D03*
X610200D03*
X620800Y236400D03*
X623800D03*
X744500Y239000D03*
G54D15*
X32500Y90700D03*
Y87300D03*
X35500Y90700D03*
Y87300D03*
X61000Y135300D03*
Y138700D03*
X64500Y87700D03*
Y84300D03*
X78000Y242200D03*
Y238800D03*
X87800Y211800D03*
Y215200D03*
X92800Y224700D03*
Y221300D03*
X88200Y242200D03*
Y238800D03*
X88000Y256700D03*
Y253300D03*
X121000Y212700D03*
Y209300D03*
X127500Y101200D03*
Y97800D03*
X143500Y82200D03*
Y78800D03*
Y96200D03*
Y92800D03*
X164900Y110100D03*
Y106700D03*
X167900Y110100D03*
Y106700D03*
X175600Y113200D03*
Y109800D03*
X184600Y113200D03*
Y109800D03*
X189000Y112700D03*
Y109300D03*
X195000Y172700D03*
Y169300D03*
X209000Y51700D03*
Y48300D03*
X212000Y51700D03*
Y48300D03*
X207400Y94500D03*
Y91100D03*
X218100Y198400D03*
Y195000D03*
X236500Y54200D03*
Y50800D03*
X239500Y54200D03*
Y50800D03*
X261300Y90200D03*
Y93600D03*
X264100Y151400D03*
Y154800D03*
X278500Y104100D03*
Y107500D03*
X278600Y149300D03*
Y145900D03*
X274000Y182800D03*
X277400Y181200D03*
Y177800D03*
X274000Y186200D03*
X293200Y151000D03*
Y154400D03*
X280500Y212200D03*
Y208800D03*
X304500Y85200D03*
Y81800D03*
X308700Y104500D03*
Y101100D03*
X297500Y146200D03*
Y142800D03*
X325100Y109900D03*
Y106500D03*
X322500Y250700D03*
Y247300D03*
X319000Y250700D03*
Y247300D03*
X315500Y250700D03*
Y247300D03*
X328100Y115500D03*
Y112100D03*
X336000Y110700D03*
Y107300D03*
X344500Y135900D03*
Y139300D03*
X353000Y156200D03*
Y152800D03*
X351000Y180300D03*
X349500Y175200D03*
Y171800D03*
X356000Y172000D03*
Y168600D03*
X351000Y183700D03*
X398300Y177500D03*
Y174100D03*
X396000Y203700D03*
Y200300D03*
Y210700D03*
Y207300D03*
X388500Y204200D03*
Y200800D03*
X395000Y253200D03*
Y249800D03*
X410000Y126763D03*
Y123363D03*
X433500Y24200D03*
Y20800D03*
X433000Y120363D03*
Y123763D03*
X472000Y258200D03*
Y254800D03*
X468500Y258200D03*
Y254800D03*
X509000Y101200D03*
Y97800D03*
X525000Y237700D03*
Y234300D03*
X538500Y238700D03*
Y235300D03*
X573500Y178700D03*
Y175300D03*
X576500Y178700D03*
Y175300D03*
X698000Y165800D03*
Y169200D03*
X725200Y119900D03*
Y116500D03*
X738300Y126600D03*
Y123200D03*
X742500Y111700D03*
Y108300D03*
X745500Y111700D03*
Y108300D03*
X749500Y126200D03*
Y122800D03*
X778000Y20100D03*
Y16700D03*
X775000Y20100D03*
Y16700D03*
G54D60*
X271795Y79984D03*
Y78016D03*
X282205D03*
Y79984D03*
G54D42*
X114642Y182176D03*
X117201D03*
X119760D03*
X122319D03*
X124878D03*
Y200662D03*
X122319D03*
X119760D03*
X117201D03*
X114642D03*
G54D51*
X173459Y181448D03*
X175034D03*
X176609D03*
X178184D03*
X179759D03*
X181333D03*
X182908D03*
X184483D03*
X186058D03*
Y203570D03*
X184483D03*
X182908D03*
X181333D03*
X179759D03*
X178184D03*
X176609D03*
X175034D03*
X173459D03*
X187633Y181448D03*
Y203570D03*
G54D24*
X25000Y190354D03*
Y271850D03*
G54D52*
X180546Y192509D03*
G54D25*
X45669Y77185D03*
Y172460D03*
G54D61*
X270000Y97750D03*
G54D70*
X331500Y244900D03*
X335500D03*
X333500Y250100D03*
G54D16*
X20000Y90500D03*
X28500Y93500D03*
X25500Y105000D03*
X25700Y135000D03*
X22300Y127700D03*
X19500Y139000D03*
X27400Y173600D03*
X24173Y178154D03*
X34100Y147300D03*
X60500Y83500D03*
X60000Y131500D03*
X62000Y142500D03*
X64500Y180500D03*
X61100Y221800D03*
X60500Y258100D03*
X68800Y58400D03*
X75500Y59500D03*
X69100Y87800D03*
X80000Y96500D03*
X65700Y98100D03*
X79000Y106400D03*
X72700Y101400D03*
X66000Y114000D03*
X71300Y132500D03*
X70000Y127500D03*
X73900Y138500D03*
X73500Y198500D03*
X74500Y213500D03*
X74611Y221550D03*
X71633Y235000D03*
X76600Y235130D03*
X68400Y241600D03*
X71500Y256500D03*
X73500Y249800D03*
X93867Y57700D03*
X87000Y61500D03*
X85300Y91500D03*
X85200Y103500D03*
X81500Y194500D03*
X84722Y184222D03*
X93500Y208000D03*
X82000Y202000D03*
X86000Y206000D03*
X84200Y211800D03*
X81600Y241112D03*
X84200Y255500D03*
X80900Y250100D03*
X88000Y249700D03*
X107300Y53200D03*
X107000Y75000D03*
X106000Y61200D03*
X96000Y98000D03*
X102000Y119500D03*
X107700Y143000D03*
X102500Y165500D03*
X108000Y214000D03*
X104500Y199500D03*
X96200Y219100D03*
X101491Y230420D03*
X109200Y246700D03*
X112017Y56988D03*
X124100Y53300D03*
X124700Y75400D03*
X119940Y74779D03*
X124084Y84009D03*
X115991Y82591D03*
X113500Y102000D03*
X121500Y93000D03*
X113500Y177500D03*
X124300Y205600D03*
X114900Y207300D03*
X122500Y224000D03*
X117200Y216400D03*
X139722Y54301D03*
X140031Y47317D03*
X138400Y70700D03*
X132836Y83507D03*
X128348Y81804D03*
X133300Y77100D03*
X137005Y80930D03*
X132900Y103700D03*
X133200Y110800D03*
X134800Y161800D03*
X130200Y178600D03*
X132700Y183100D03*
X134100Y197400D03*
X129500Y255800D03*
X153300Y61100D03*
X142000Y60500D03*
X147900Y73300D03*
X147329Y100907D03*
X154600Y111200D03*
X150700Y106800D03*
X149819Y155225D03*
X147018Y161747D03*
X153997Y175975D03*
X151600Y187200D03*
X146000Y228100D03*
X148551Y238551D03*
X157493Y124795D03*
X165500Y157500D03*
X160000Y171700D03*
X163900Y174700D03*
X163600Y184597D03*
X161897Y197859D03*
X159000Y193600D03*
X163226Y190126D03*
X171300Y209000D03*
X163200Y241000D03*
X161900Y253300D03*
X182500Y63000D03*
X185200Y159100D03*
X186700Y175500D03*
X181300Y209500D03*
X180500Y223500D03*
X195500Y49500D03*
X193100Y64900D03*
X188750Y119937D03*
X202122Y107429D03*
X193672Y176556D03*
X202000Y183068D03*
X192000Y234000D03*
X215000Y44500D03*
X209000D03*
X205100Y50900D03*
X216000Y49200D03*
X214000Y223000D03*
X219200Y202400D03*
X222500Y227500D03*
X220500Y221000D03*
X242016Y47325D03*
X247500Y49000D03*
X235000Y47000D03*
X243000Y55000D03*
X260500Y206000D03*
X262300Y232500D03*
X251500Y253500D03*
X266200Y48731D03*
X270900Y61700D03*
X275500Y101200D03*
X277700Y96900D03*
X271200Y104300D03*
X278811Y121089D03*
X276600Y128700D03*
X276800Y158700D03*
X266320Y164180D03*
X279900Y168000D03*
X274500Y215000D03*
X279046Y222063D03*
X269500Y216659D03*
X266000Y244200D03*
X277800Y249400D03*
X265425Y260000D03*
X289000Y66000D03*
X286700Y86600D03*
X291400Y134686D03*
X282130Y147600D03*
X286600Y163600D03*
X282500Y177300D03*
X290100Y190900D03*
X288500Y195802D03*
X286500Y184000D03*
X284300Y214225D03*
X285200Y233000D03*
X310310Y68000D03*
X304694Y101956D03*
X297600Y113025D03*
X297200Y123600D03*
X299600Y135800D03*
X302700Y140600D03*
X300600Y149400D03*
X309350Y147840D03*
X299065Y154064D03*
X310300Y163300D03*
X303492Y162375D03*
X298500Y167100D03*
X308559Y174807D03*
X298000Y181500D03*
X297797Y173997D03*
X303639Y171201D03*
X305800Y191000D03*
X303500Y228000D03*
X309010Y228490D03*
X299600Y238200D03*
X301100Y248600D03*
X309300Y249700D03*
X312100Y84800D03*
X317000Y84900D03*
X320500Y103000D03*
X317352Y116648D03*
X322500Y114500D03*
X320600Y126100D03*
X315000Y144550D03*
X320300Y146700D03*
X314800Y151661D03*
X316259Y163771D03*
X315900Y156921D03*
X312070Y179296D03*
X318324Y176724D03*
X313260Y193500D03*
X317060Y202500D03*
X319423Y228577D03*
X322192Y234136D03*
X335000Y46575D03*
X340200Y71400D03*
X337300Y88000D03*
X332400Y85400D03*
X340500Y95500D03*
X327026Y102576D03*
X336300Y103700D03*
X339547Y108043D03*
X338400Y113800D03*
X336300Y118200D03*
X330500Y109000D03*
X329523Y128134D03*
X333800Y148700D03*
X339150Y159000D03*
X336500Y183000D03*
X330155Y183655D03*
X334500Y207500D03*
X330500Y240800D03*
X354800Y50200D03*
X356000Y121000D03*
X345040Y107960D03*
X343890Y131430D03*
X346600Y125600D03*
X342300Y143400D03*
X345500Y166500D03*
X347476Y153210D03*
X354899Y164998D03*
X344600Y173066D03*
X342692Y177534D03*
X354500Y203763D03*
X342200Y200100D03*
X355000Y260200D03*
X347000Y260000D03*
X359646Y50000D03*
X365500Y76000D03*
X372500Y151700D03*
X370000Y183000D03*
X363600Y196000D03*
X365700Y240300D03*
X384921Y50782D03*
X377850Y63500D03*
X384500Y62000D03*
X373800Y80600D03*
X385300Y94300D03*
X387100Y103100D03*
X376900Y128100D03*
X376800Y138500D03*
X373700Y171100D03*
X379561Y197939D03*
X387400Y184700D03*
X402820Y54500D03*
X400296Y78300D03*
X400000Y106100D03*
X401800Y177800D03*
X389480Y197040D03*
X392300Y203000D03*
X397800Y222600D03*
X392500Y245000D03*
X391508Y257969D03*
X391499Y253169D03*
X396000Y274092D03*
X394650Y263940D03*
X399300Y262400D03*
X414790Y52110D03*
X412350Y175550D03*
X414827Y238668D03*
X416128Y268872D03*
X410000Y266500D03*
X419565Y233465D03*
X428272Y237872D03*
X430200Y248400D03*
X439300Y39600D03*
X439000Y54000D03*
X444500Y71500D03*
X441500Y62500D03*
X435500Y156500D03*
X445500Y215500D03*
X443500Y235500D03*
X452000Y107000D03*
X458700Y255600D03*
X451500Y251150D03*
X455500Y269500D03*
X472256Y29500D03*
X469195Y268805D03*
X487000Y138400D03*
X526200Y96600D03*
X516500Y92600D03*
X521000Y96500D03*
X517000Y110000D03*
X521261Y162739D03*
X518500Y230500D03*
X541000Y119500D03*
X541757Y158048D03*
X536634Y169866D03*
X534700Y187450D03*
X541100Y187500D03*
X538400Y209500D03*
X536500Y231500D03*
X552178Y205822D03*
X547600Y227300D03*
X568900Y196900D03*
X576700Y96100D03*
X582100Y140000D03*
X584702Y173402D03*
X602650Y177250D03*
X594965Y207175D03*
X607900Y97900D03*
X612000Y172250D03*
X627500Y174300D03*
X626100Y186400D03*
X634600Y189300D03*
X638000Y103000D03*
X641000Y161500D03*
X655300Y100900D03*
X660397Y191100D03*
X658800Y200100D03*
X670500Y111900D03*
X679871Y179371D03*
X692500Y106000D03*
X694000Y175000D03*
X693600Y219300D03*
X699858Y131908D03*
X703000Y139900D03*
X726500Y111600D03*
X718700Y112500D03*
X722900Y127400D03*
X727100Y123500D03*
X718847Y143500D03*
X718300Y159300D03*
X718900Y166200D03*
X714038Y175162D03*
X736000Y62000D03*
X731000Y88000D03*
X731500Y98600D03*
X739900Y101400D03*
X740000Y96000D03*
X728900Y116100D03*
X731200Y129600D03*
X742000Y124200D03*
X731200Y138500D03*
X729700Y146900D03*
X733000Y185100D03*
X744600Y99600D03*
X744100Y104700D03*
X745140Y120480D03*
X758003Y141303D03*
X757000Y149000D03*
X772547Y135627D03*
X762200Y135200D03*
X770600Y153700D03*
X784369Y18484D03*
X785297Y128876D03*
X785324Y133676D03*
X785100Y139900D03*
X785831Y164500D03*
X785453Y154214D03*
X785831Y159000D03*
X786000Y171856D03*
X786500Y276000D03*
X788955Y265773D03*
X783078Y266246D03*
X790500Y14500D03*
X804000Y86500D03*
Y97500D03*
X792000Y119465D03*
X792123Y177595D03*
X789000Y245500D03*
X791366Y270866D03*
X792000Y280800D03*
X808900Y179500D03*
G54D43*
G01X10636Y-27865D02*
G02I-12000J0D01*
G01X14636D02*
X-17364D01*
G01X5486D02*
G02I-6850J0D01*
G01X-1364Y-43865D02*
Y-11865D01*
G01X14636Y-43865D02*
Y-123865D01*
G01D02*
X1309236D01*
G01X14636Y-79365D02*
X1309236D01*
G01X14636Y-43865D02*
X1309236D01*
G01X521736D02*
Y-123865D01*
G01X659236Y-43865D02*
Y-123865D01*
G01X774236Y-43865D02*
Y-123865D01*
G01X941736Y-43865D02*
Y-123865D01*
G01X1111736Y-43865D02*
Y-123865D01*
G01X1309236Y-43865D02*
Y-123865D01*
G01X1341236Y-27865D02*
X1309236D01*
G01X1337236D02*
G02I-12000J0D01*
G01X1332086D02*
G02I-6850J0D01*
G01X1325236Y-43865D02*
Y-11865D01*
X119760Y191419D03*
X115760D03*
X123760D03*
X185546Y192509D03*
X180546D03*
X175546D03*
X323882Y71643D03*
X318882D03*
X328882D03*
G54D34*
X58500Y188000D03*
X61500D03*
X79500Y48500D03*
X67500Y188000D03*
X64500D03*
X68000Y235000D03*
X82500Y48500D03*
X88500D03*
X85500D03*
X85200Y239000D03*
X103250Y48500D03*
X100250D03*
X105500Y192000D03*
X119000Y48500D03*
X116000D03*
X134800D03*
X131800D03*
X132700Y186600D03*
X150515Y48500D03*
X147515D03*
X166263D03*
X163263D03*
X160100Y184000D03*
X182000Y48500D03*
X179000D03*
X178000Y164500D03*
X201500Y65500D03*
X204500D03*
X237000Y57300D03*
X268000Y52000D03*
X271000D03*
X275500Y241500D03*
X272500D03*
X290000Y52000D03*
X287000D03*
X286100Y77700D03*
X305000Y51500D03*
X308000D03*
X310500Y60500D03*
X304500Y219000D03*
X302000Y242100D03*
X305000D03*
X316000Y51500D03*
X319000D03*
X334000Y55500D03*
X354000Y63000D03*
X353000Y140500D03*
X364500Y128500D03*
X370300Y131500D03*
X365000Y146500D03*
X359000Y140000D03*
Y174000D03*
X377500Y131500D03*
X374500D03*
X386500Y168500D03*
X378220Y170540D03*
X395500Y75000D03*
X392000D03*
X393496Y106063D03*
X389500Y156263D03*
X390000Y162100D03*
Y168500D03*
X398000Y253000D03*
X410000Y106063D03*
X407000D03*
X416000D03*
X413000D03*
X406000Y263500D03*
X422000Y106063D03*
X419000D03*
X421142Y181024D03*
X436000Y107563D03*
X434900Y146500D03*
X441000Y140000D03*
X601100Y233500D03*
X617800Y233400D03*
X613200Y233100D03*
X610200D03*
X620800Y233400D03*
X623800D03*
X744500Y236000D03*
G54D62*
X270000Y100250D03*
G54D80*
X449150Y143900D03*
X444350Y162800D03*
X467650D03*
X472450Y143900D03*
X780650Y195800D03*
X803950D03*
G54D44*
X119760Y191419D03*
X323882Y71643D03*
G54D53*
X198100Y110200D03*
X192900D03*
X198100Y120200D03*
X192900D03*
X276700Y92200D03*
X271500D03*
X290900Y86600D03*
X296100D03*
X364196Y203763D03*
X358996D03*
X387900Y178300D03*
X393100D03*
X426600Y78500D03*
X421400D03*
X472600Y238500D03*
X467400D03*
X472600Y233000D03*
X467400D03*
X780000Y244300D03*
X774800D03*
X780000Y254300D03*
X774800D03*
X780000Y249300D03*
X774800D03*
G54D71*
X339200Y269500D03*
X349800D03*
G54D17*
X32000Y99000D03*
X72500Y91500D03*
X64500Y132500D03*
X68000Y222000D03*
X85500Y110000D03*
X133000Y201000D03*
X144000Y106000D03*
X209000Y74000D03*
Y68000D03*
Y71000D03*
Y77000D03*
X263000Y108500D03*
Y111500D03*
Y120200D03*
Y117200D03*
X307500Y88300D03*
X308000Y144200D03*
X337500Y78500D03*
X344500Y88500D03*
X349500Y103500D03*
Y100500D03*
X347000Y97500D03*
Y94500D03*
X344500Y91500D03*
X349500Y106500D03*
X359450Y134700D03*
X363500Y182700D03*
Y179700D03*
X392496Y131063D03*
X393342Y143124D03*
X388000Y210500D03*
X434000Y17500D03*
X431500Y170000D03*
X468500Y242500D03*
X525000Y122500D03*
Y148500D03*
Y151500D03*
X527500Y179000D03*
Y176000D03*
X547500Y179000D03*
X560500D03*
X602000Y142000D03*
X607000Y211000D03*
G54D35*
X70760Y174791D03*
X78240D03*
X74500Y183209D03*
X268260Y168291D03*
X275740D03*
X272000Y176709D03*
X456760Y259791D03*
X464240D03*
X460500Y268209D03*
G54D26*
X35000Y99000D03*
X75500Y91500D03*
X67500Y132500D03*
X71000Y222000D03*
X88500Y110000D03*
X136000Y201000D03*
X147000Y106000D03*
X212000Y74000D03*
Y68000D03*
Y71000D03*
Y77000D03*
X266000Y108500D03*
Y111500D03*
Y120200D03*
Y117200D03*
X310500Y88300D03*
X311000Y144200D03*
X340500Y78500D03*
X347500Y88500D03*
X352500Y103500D03*
Y100500D03*
X350000Y97500D03*
Y94500D03*
X347500Y91500D03*
X352500Y106500D03*
X362450Y134700D03*
X366500Y182700D03*
Y179700D03*
X395496Y131063D03*
X396342Y143124D03*
X391000Y210500D03*
X437000Y17500D03*
X434500Y170000D03*
X471500Y242500D03*
X528000Y122500D03*
Y148500D03*
Y151500D03*
X530500Y179000D03*
Y176000D03*
X550500Y179000D03*
X563500D03*
X605000Y142000D03*
X610000Y211000D03*
G54D45*
X141500Y167976D03*
Y183024D03*
G54D54*
X200197Y282677D03*
X298622D03*
G54D72*
X346500Y67700D03*
Y78300D03*
X365000Y260700D03*
Y271300D03*
X777000Y146900D03*
Y157500D03*
G54D18*
X31800Y96000D03*
X35200D03*
X60800Y91000D03*
X64200D03*
X60800Y218000D03*
X64200D03*
X72800Y88000D03*
X76200D03*
X72800Y84500D03*
X76200D03*
X72300Y97500D03*
X75700D03*
X72300Y94500D03*
X75700D03*
X105800Y255000D03*
X109200D03*
X128800Y175000D03*
X132200D03*
X139300Y201000D03*
X153300Y57500D03*
X156700D03*
X146800Y89500D03*
X150200D03*
X146800Y92500D03*
X150200D03*
X143800Y109000D03*
X147200D03*
X150800Y162000D03*
X154200D03*
X150800Y171500D03*
X154200D03*
X151800Y192000D03*
X155200D03*
X142700Y201000D03*
X167300Y61300D03*
X170700D03*
X161400Y113200D03*
X164800D03*
X162300Y257000D03*
X165700D03*
X182800Y57500D03*
X186200D03*
X178300Y213000D03*
X181700D03*
X195300Y230500D03*
X198700D03*
X211800Y206500D03*
X215200D03*
X226800Y60000D03*
X230200D03*
X279800Y135500D03*
X271500Y141400D03*
X274900D03*
X278700Y244400D03*
X283000Y132500D03*
X286400D03*
X283200Y135500D03*
X289800Y141500D03*
X293200D03*
X290300Y157500D03*
X293700D03*
X283700Y168000D03*
X287100D03*
X293300Y199500D03*
X286300D03*
X289700D03*
X282100Y244400D03*
X297300Y157500D03*
X300700D03*
X296700Y199500D03*
X295800Y228000D03*
X299200D03*
X295800Y231000D03*
X299200D03*
X313300Y103500D03*
X316700D03*
X313300Y148000D03*
X316700D03*
X337300Y81500D03*
X340700D03*
X349400Y159400D03*
X352800D03*
X369900Y128100D03*
X361396Y199563D03*
X364796D03*
X373300Y128100D03*
X387800Y207500D03*
X393170Y197103D03*
X396570D03*
X391200Y207500D03*
X406800Y55500D03*
X410200D03*
X404300Y208000D03*
X407700D03*
X409200Y262800D03*
X412600D03*
X440300Y36000D03*
X443700D03*
X522800Y93000D03*
X526200D03*
X520800Y110500D03*
X524200D03*
X520800Y107500D03*
X524200D03*
X545800Y119500D03*
X549200D03*
X551300Y187500D03*
X554700D03*
X566800Y179000D03*
X570200D03*
X566800Y176000D03*
X570200D03*
X560300Y187000D03*
X563700D03*
X566900Y190000D03*
X570300D03*
X573300Y92500D03*
X576700D03*
X718682Y119685D03*
X722082D03*
X741500Y46507D03*
X734800D03*
X738200D03*
X732800Y102500D03*
X736200D03*
X744900Y46507D03*
X775800Y133000D03*
X779200D03*
X775800Y129500D03*
X779200D03*
X775800Y126000D03*
X779200D03*
X775800Y122500D03*
X779200D03*
X777800Y162000D03*
X781200D03*
X777800Y165000D03*
X781200D03*
X777800Y168000D03*
X781200D03*
X777800Y171000D03*
X781200D03*
G54D81*
X439441Y260531D03*
Y264469D03*
G54D63*
X268520Y132540D03*
X275880D03*
Y135100D03*
Y137660D03*
X268520D03*
X402820Y59440D03*
Y64560D03*
Y62000D03*
X410180Y59440D03*
Y64560D03*
X461520Y20060D03*
Y14940D03*
X468880Y20060D03*
Y14940D03*
Y17500D03*
G36*
G01X499410Y282290D02*
X499285Y282280D01*
X499160Y282240D01*
X499050Y282180D01*
X498950Y282100D01*
X498870Y282000D01*
X498810Y281890D01*
X498770Y281765D01*
X498760Y281640D01*
Y279210D01*
X498730Y279180D01*
X498630Y279040D01*
X498610Y279000D01*
X498595Y278965D01*
X498575Y278925D01*
X498560Y278885D01*
X498550Y278845D01*
X498535Y278800D01*
X498530Y278760D01*
X498520Y278720D01*
X498515Y278675D01*
Y278635D01*
X498510Y278590D01*
X498515Y278545D01*
Y278505D01*
X498520Y278460D01*
X498530Y278420D01*
X498535Y278380D01*
X498550Y278335D01*
X498560Y278295D01*
X498575Y278255D01*
X498595Y278215D01*
X498610Y278180D01*
X498630Y278140D01*
X498730Y278000D01*
X498760Y277970D01*
Y275840D01*
X498770Y275715D01*
X498810Y275590D01*
X498870Y275480D01*
X498950Y275380D01*
X499050Y275300D01*
X499160Y275240D01*
X499285Y275200D01*
X499410Y275190D01*
X499535Y275200D01*
X499660Y275240D01*
X499770Y275300D01*
X499870Y275380D01*
X499950Y275480D01*
X500010Y275590D01*
X500050Y275715D01*
X500060Y275840D01*
Y277965D01*
X500090Y277995D01*
X500115Y278030D01*
X500145Y278065D01*
X500165Y278100D01*
X500190Y278135D01*
X500230Y278215D01*
X500275Y278335D01*
X500285Y278375D01*
X500295Y278420D01*
X500300Y278460D01*
X500310Y278505D01*
Y278675D01*
X500300Y278720D01*
X500295Y278760D01*
X500285Y278805D01*
X500275Y278845D01*
X500230Y278965D01*
X500190Y279045D01*
X500165Y279080D01*
X500145Y279115D01*
X500115Y279150D01*
X500090Y279185D01*
X500060Y279215D01*
Y281640D01*
X500050Y281765D01*
X500010Y281890D01*
X499950Y282000D01*
X499870Y282100D01*
X499770Y282180D01*
X499660Y282240D01*
X499535Y282280D01*
X499410Y282290D01*
G37*
G36*
G01X504134D02*
X504009Y282280D01*
X503884Y282240D01*
X503774Y282180D01*
X503674Y282100D01*
X503594Y282000D01*
X503534Y281890D01*
X503494Y281765D01*
X503484Y281640D01*
Y279210D01*
X503454Y279180D01*
X503354Y279040D01*
X503334Y279000D01*
X503319Y278965D01*
X503299Y278925D01*
X503284Y278885D01*
X503274Y278845D01*
X503259Y278800D01*
X503254Y278760D01*
X503244Y278720D01*
X503239Y278675D01*
Y278635D01*
X503234Y278590D01*
X503239Y278545D01*
Y278505D01*
X503244Y278460D01*
X503254Y278420D01*
X503259Y278380D01*
X503274Y278335D01*
X503284Y278295D01*
X503299Y278255D01*
X503319Y278215D01*
X503334Y278180D01*
X503354Y278140D01*
X503454Y278000D01*
X503484Y277970D01*
Y275840D01*
X503494Y275715D01*
X503534Y275590D01*
X503594Y275480D01*
X503674Y275380D01*
X503774Y275300D01*
X503884Y275240D01*
X504009Y275200D01*
X504134Y275190D01*
X504259Y275200D01*
X504384Y275240D01*
X504494Y275300D01*
X504594Y275380D01*
X504674Y275480D01*
X504734Y275590D01*
X504774Y275715D01*
X504784Y275840D01*
Y277965D01*
X504814Y277995D01*
X504839Y278030D01*
X504869Y278065D01*
X504889Y278100D01*
X504914Y278135D01*
X504954Y278215D01*
X504999Y278335D01*
X505009Y278375D01*
X505019Y278420D01*
X505024Y278460D01*
X505034Y278505D01*
Y278675D01*
X505024Y278720D01*
X505019Y278760D01*
X505009Y278805D01*
X504999Y278845D01*
X504954Y278965D01*
X504914Y279045D01*
X504889Y279080D01*
X504869Y279115D01*
X504839Y279150D01*
X504814Y279185D01*
X504784Y279215D01*
Y281640D01*
X504774Y281765D01*
X504734Y281890D01*
X504674Y282000D01*
X504594Y282100D01*
X504494Y282180D01*
X504384Y282240D01*
X504259Y282280D01*
X504134Y282290D01*
G37*
G36*
G01X508859D02*
X508734Y282280D01*
X508609Y282240D01*
X508499Y282180D01*
X508399Y282100D01*
X508319Y282000D01*
X508259Y281890D01*
X508219Y281765D01*
X508209Y281640D01*
Y279210D01*
X508179Y279180D01*
X508079Y279040D01*
X508059Y279000D01*
X508044Y278965D01*
X508024Y278925D01*
X508009Y278885D01*
X507999Y278845D01*
X507984Y278800D01*
X507979Y278760D01*
X507969Y278720D01*
X507964Y278675D01*
Y278635D01*
X507959Y278590D01*
X507964Y278545D01*
Y278505D01*
X507969Y278460D01*
X507979Y278420D01*
X507984Y278380D01*
X507999Y278335D01*
X508009Y278295D01*
X508024Y278255D01*
X508044Y278215D01*
X508059Y278180D01*
X508079Y278140D01*
X508179Y278000D01*
X508209Y277970D01*
Y275840D01*
X508219Y275715D01*
X508259Y275590D01*
X508319Y275480D01*
X508399Y275380D01*
X508499Y275300D01*
X508609Y275240D01*
X508734Y275200D01*
X508859Y275190D01*
X508984Y275200D01*
X509109Y275240D01*
X509219Y275300D01*
X509319Y275380D01*
X509399Y275480D01*
X509459Y275590D01*
X509499Y275715D01*
X509509Y275840D01*
Y277965D01*
X509539Y277995D01*
X509564Y278030D01*
X509594Y278065D01*
X509614Y278100D01*
X509639Y278135D01*
X509679Y278215D01*
X509724Y278335D01*
X509734Y278375D01*
X509744Y278420D01*
X509749Y278460D01*
X509759Y278505D01*
Y278675D01*
X509749Y278720D01*
X509744Y278760D01*
X509734Y278805D01*
X509724Y278845D01*
X509679Y278965D01*
X509639Y279045D01*
X509614Y279080D01*
X509594Y279115D01*
X509564Y279150D01*
X509539Y279185D01*
X509509Y279215D01*
Y281640D01*
X509499Y281765D01*
X509459Y281890D01*
X509399Y282000D01*
X509319Y282100D01*
X509219Y282180D01*
X509109Y282240D01*
X508984Y282280D01*
X508859Y282290D01*
G37*
G36*
G01X513583D02*
X513458Y282280D01*
X513333Y282240D01*
X513223Y282180D01*
X513123Y282100D01*
X513043Y282000D01*
X512983Y281890D01*
X512943Y281765D01*
X512933Y281640D01*
Y279210D01*
X512903Y279180D01*
X512803Y279040D01*
X512783Y279000D01*
X512768Y278965D01*
X512748Y278925D01*
X512733Y278885D01*
X512723Y278845D01*
X512708Y278800D01*
X512703Y278760D01*
X512693Y278720D01*
X512688Y278675D01*
Y278635D01*
X512683Y278590D01*
X512688Y278545D01*
Y278505D01*
X512693Y278460D01*
X512703Y278420D01*
X512708Y278380D01*
X512723Y278335D01*
X512733Y278295D01*
X512748Y278255D01*
X512768Y278215D01*
X512783Y278180D01*
X512803Y278140D01*
X512903Y278000D01*
X512933Y277970D01*
Y275840D01*
X512943Y275715D01*
X512983Y275590D01*
X513043Y275480D01*
X513123Y275380D01*
X513223Y275300D01*
X513333Y275240D01*
X513458Y275200D01*
X513583Y275190D01*
X513708Y275200D01*
X513833Y275240D01*
X513943Y275300D01*
X514043Y275380D01*
X514123Y275480D01*
X514183Y275590D01*
X514223Y275715D01*
X514233Y275840D01*
Y277965D01*
X514263Y277995D01*
X514288Y278030D01*
X514318Y278065D01*
X514338Y278100D01*
X514363Y278135D01*
X514403Y278215D01*
X514448Y278335D01*
X514458Y278375D01*
X514468Y278420D01*
X514473Y278460D01*
X514483Y278505D01*
Y278675D01*
X514473Y278720D01*
X514468Y278760D01*
X514458Y278805D01*
X514448Y278845D01*
X514403Y278965D01*
X514363Y279045D01*
X514338Y279080D01*
X514318Y279115D01*
X514288Y279150D01*
X514263Y279185D01*
X514233Y279215D01*
Y281640D01*
X514223Y281765D01*
X514183Y281890D01*
X514123Y282000D01*
X514043Y282100D01*
X513943Y282180D01*
X513833Y282240D01*
X513708Y282280D01*
X513583Y282290D01*
G37*
G36*
G01X518307D02*
X518182Y282280D01*
X518057Y282240D01*
X517947Y282180D01*
X517847Y282100D01*
X517767Y282000D01*
X517707Y281890D01*
X517667Y281765D01*
X517657Y281640D01*
Y279210D01*
X517627Y279180D01*
X517527Y279040D01*
X517507Y279000D01*
X517492Y278965D01*
X517472Y278925D01*
X517457Y278885D01*
X517447Y278845D01*
X517432Y278800D01*
X517427Y278760D01*
X517417Y278720D01*
X517412Y278675D01*
Y278635D01*
X517407Y278590D01*
X517412Y278545D01*
Y278505D01*
X517417Y278460D01*
X517427Y278420D01*
X517432Y278380D01*
X517447Y278335D01*
X517457Y278295D01*
X517472Y278255D01*
X517492Y278215D01*
X517507Y278180D01*
X517527Y278140D01*
X517627Y278000D01*
X517657Y277970D01*
Y275840D01*
X517667Y275715D01*
X517707Y275590D01*
X517767Y275480D01*
X517847Y275380D01*
X517947Y275300D01*
X518057Y275240D01*
X518182Y275200D01*
X518307Y275190D01*
X518432Y275200D01*
X518557Y275240D01*
X518667Y275300D01*
X518767Y275380D01*
X518847Y275480D01*
X518907Y275590D01*
X518947Y275715D01*
X518957Y275840D01*
Y277965D01*
X518987Y277995D01*
X519012Y278030D01*
X519042Y278065D01*
X519062Y278100D01*
X519087Y278135D01*
X519127Y278215D01*
X519172Y278335D01*
X519182Y278375D01*
X519192Y278420D01*
X519197Y278460D01*
X519207Y278505D01*
Y278675D01*
X519197Y278720D01*
X519192Y278760D01*
X519182Y278805D01*
X519172Y278845D01*
X519127Y278965D01*
X519087Y279045D01*
X519062Y279080D01*
X519042Y279115D01*
X519012Y279150D01*
X518987Y279185D01*
X518957Y279215D01*
Y281640D01*
X518947Y281765D01*
X518907Y281890D01*
X518847Y282000D01*
X518767Y282100D01*
X518667Y282180D01*
X518557Y282240D01*
X518432Y282280D01*
X518307Y282290D01*
G37*
G36*
G01X523032D02*
X522907Y282280D01*
X522782Y282240D01*
X522672Y282180D01*
X522572Y282100D01*
X522492Y282000D01*
X522432Y281890D01*
X522392Y281765D01*
X522382Y281640D01*
Y279210D01*
X522352Y279180D01*
X522252Y279040D01*
X522232Y279000D01*
X522217Y278965D01*
X522197Y278925D01*
X522182Y278885D01*
X522172Y278845D01*
X522157Y278800D01*
X522152Y278760D01*
X522142Y278720D01*
X522137Y278675D01*
Y278635D01*
X522132Y278590D01*
X522137Y278545D01*
Y278505D01*
X522142Y278460D01*
X522152Y278420D01*
X522157Y278380D01*
X522172Y278335D01*
X522182Y278295D01*
X522197Y278255D01*
X522217Y278215D01*
X522232Y278180D01*
X522252Y278140D01*
X522352Y278000D01*
X522382Y277970D01*
Y275840D01*
X522392Y275715D01*
X522432Y275590D01*
X522492Y275480D01*
X522572Y275380D01*
X522672Y275300D01*
X522782Y275240D01*
X522907Y275200D01*
X523032Y275190D01*
X523157Y275200D01*
X523282Y275240D01*
X523392Y275300D01*
X523492Y275380D01*
X523572Y275480D01*
X523632Y275590D01*
X523672Y275715D01*
X523682Y275840D01*
Y277965D01*
X523712Y277995D01*
X523737Y278030D01*
X523767Y278065D01*
X523787Y278100D01*
X523812Y278135D01*
X523852Y278215D01*
X523897Y278335D01*
X523907Y278375D01*
X523917Y278420D01*
X523922Y278460D01*
X523932Y278505D01*
Y278675D01*
X523922Y278720D01*
X523917Y278760D01*
X523907Y278805D01*
X523897Y278845D01*
X523852Y278965D01*
X523812Y279045D01*
X523787Y279080D01*
X523767Y279115D01*
X523737Y279150D01*
X523712Y279185D01*
X523682Y279215D01*
Y281640D01*
X523672Y281765D01*
X523632Y281890D01*
X523572Y282000D01*
X523492Y282100D01*
X523392Y282180D01*
X523282Y282240D01*
X523157Y282280D01*
X523032Y282290D01*
G37*
G36*
G01X527756D02*
X527631Y282280D01*
X527506Y282240D01*
X527396Y282180D01*
X527296Y282100D01*
X527216Y282000D01*
X527156Y281890D01*
X527116Y281765D01*
X527106Y281640D01*
Y279210D01*
X527076Y279180D01*
X526976Y279040D01*
X526956Y279000D01*
X526941Y278965D01*
X526921Y278925D01*
X526906Y278885D01*
X526896Y278845D01*
X526881Y278800D01*
X526876Y278760D01*
X526866Y278720D01*
X526861Y278675D01*
Y278635D01*
X526856Y278590D01*
X526861Y278545D01*
Y278505D01*
X526866Y278460D01*
X526876Y278420D01*
X526881Y278380D01*
X526896Y278335D01*
X526906Y278295D01*
X526921Y278255D01*
X526941Y278215D01*
X526956Y278180D01*
X526976Y278140D01*
X527076Y278000D01*
X527106Y277970D01*
Y275840D01*
X527116Y275715D01*
X527156Y275590D01*
X527216Y275480D01*
X527296Y275380D01*
X527396Y275300D01*
X527506Y275240D01*
X527631Y275200D01*
X527756Y275190D01*
X527881Y275200D01*
X528006Y275240D01*
X528116Y275300D01*
X528216Y275380D01*
X528296Y275480D01*
X528356Y275590D01*
X528396Y275715D01*
X528406Y275840D01*
Y277965D01*
X528436Y277995D01*
X528461Y278030D01*
X528491Y278065D01*
X528511Y278100D01*
X528536Y278135D01*
X528576Y278215D01*
X528621Y278335D01*
X528631Y278375D01*
X528641Y278420D01*
X528646Y278460D01*
X528656Y278505D01*
Y278675D01*
X528646Y278720D01*
X528641Y278760D01*
X528631Y278805D01*
X528621Y278845D01*
X528576Y278965D01*
X528536Y279045D01*
X528511Y279080D01*
X528491Y279115D01*
X528461Y279150D01*
X528436Y279185D01*
X528406Y279215D01*
Y281640D01*
X528396Y281765D01*
X528356Y281890D01*
X528296Y282000D01*
X528216Y282100D01*
X528116Y282180D01*
X528006Y282240D01*
X527881Y282280D01*
X527756Y282290D01*
G37*
G36*
G01X532481D02*
X532356Y282280D01*
X532231Y282240D01*
X532121Y282180D01*
X532021Y282100D01*
X531941Y282000D01*
X531881Y281890D01*
X531841Y281765D01*
X531831Y281640D01*
Y279210D01*
X531801Y279180D01*
X531701Y279040D01*
X531681Y279000D01*
X531666Y278965D01*
X531646Y278925D01*
X531631Y278885D01*
X531621Y278845D01*
X531606Y278800D01*
X531601Y278760D01*
X531591Y278720D01*
X531586Y278675D01*
Y278635D01*
X531581Y278590D01*
X531586Y278545D01*
Y278505D01*
X531591Y278460D01*
X531601Y278420D01*
X531606Y278380D01*
X531621Y278335D01*
X531631Y278295D01*
X531646Y278255D01*
X531666Y278215D01*
X531681Y278180D01*
X531701Y278140D01*
X531801Y278000D01*
X531831Y277970D01*
Y275840D01*
X531841Y275715D01*
X531881Y275590D01*
X531941Y275480D01*
X532021Y275380D01*
X532121Y275300D01*
X532231Y275240D01*
X532356Y275200D01*
X532481Y275190D01*
X532606Y275200D01*
X532731Y275240D01*
X532841Y275300D01*
X532941Y275380D01*
X533021Y275480D01*
X533081Y275590D01*
X533121Y275715D01*
X533131Y275840D01*
Y277965D01*
X533161Y277995D01*
X533186Y278030D01*
X533216Y278065D01*
X533236Y278100D01*
X533261Y278135D01*
X533301Y278215D01*
X533346Y278335D01*
X533356Y278375D01*
X533366Y278420D01*
X533371Y278460D01*
X533381Y278505D01*
Y278675D01*
X533371Y278720D01*
X533366Y278760D01*
X533356Y278805D01*
X533346Y278845D01*
X533301Y278965D01*
X533261Y279045D01*
X533236Y279080D01*
X533216Y279115D01*
X533186Y279150D01*
X533161Y279185D01*
X533131Y279215D01*
Y281640D01*
X533121Y281765D01*
X533081Y281890D01*
X533021Y282000D01*
X532941Y282100D01*
X532841Y282180D01*
X532731Y282240D01*
X532606Y282280D01*
X532481Y282290D01*
G37*
G36*
G01X537205D02*
X537080Y282280D01*
X536955Y282240D01*
X536845Y282180D01*
X536745Y282100D01*
X536665Y282000D01*
X536605Y281890D01*
X536565Y281765D01*
X536555Y281640D01*
Y279210D01*
X536525Y279180D01*
X536425Y279040D01*
X536405Y279000D01*
X536390Y278965D01*
X536370Y278925D01*
X536355Y278885D01*
X536345Y278845D01*
X536330Y278800D01*
X536325Y278760D01*
X536315Y278720D01*
X536310Y278675D01*
Y278635D01*
X536305Y278590D01*
X536310Y278545D01*
Y278505D01*
X536315Y278460D01*
X536325Y278420D01*
X536330Y278380D01*
X536345Y278335D01*
X536355Y278295D01*
X536370Y278255D01*
X536390Y278215D01*
X536405Y278180D01*
X536425Y278140D01*
X536525Y278000D01*
X536555Y277970D01*
Y275840D01*
X536565Y275715D01*
X536605Y275590D01*
X536665Y275480D01*
X536745Y275380D01*
X536845Y275300D01*
X536955Y275240D01*
X537080Y275200D01*
X537205Y275190D01*
X537330Y275200D01*
X537455Y275240D01*
X537565Y275300D01*
X537665Y275380D01*
X537745Y275480D01*
X537805Y275590D01*
X537845Y275715D01*
X537855Y275840D01*
Y277965D01*
X537885Y277995D01*
X537910Y278030D01*
X537940Y278065D01*
X537960Y278100D01*
X537985Y278135D01*
X538025Y278215D01*
X538070Y278335D01*
X538080Y278375D01*
X538090Y278420D01*
X538095Y278460D01*
X538105Y278505D01*
Y278675D01*
X538095Y278720D01*
X538090Y278760D01*
X538080Y278805D01*
X538070Y278845D01*
X538025Y278965D01*
X537985Y279045D01*
X537960Y279080D01*
X537940Y279115D01*
X537910Y279150D01*
X537885Y279185D01*
X537855Y279215D01*
Y281640D01*
X537845Y281765D01*
X537805Y281890D01*
X537745Y282000D01*
X537665Y282100D01*
X537565Y282180D01*
X537455Y282240D01*
X537330Y282280D01*
X537205Y282290D01*
G37*
G36*
G01X541929D02*
X541804Y282280D01*
X541679Y282240D01*
X541569Y282180D01*
X541469Y282100D01*
X541389Y282000D01*
X541329Y281890D01*
X541289Y281765D01*
X541279Y281640D01*
Y279210D01*
X541249Y279180D01*
X541149Y279040D01*
X541129Y279000D01*
X541114Y278965D01*
X541094Y278925D01*
X541079Y278885D01*
X541069Y278845D01*
X541054Y278800D01*
X541049Y278760D01*
X541039Y278720D01*
X541034Y278675D01*
Y278635D01*
X541029Y278590D01*
X541034Y278545D01*
Y278505D01*
X541039Y278460D01*
X541049Y278420D01*
X541054Y278380D01*
X541069Y278335D01*
X541079Y278295D01*
X541094Y278255D01*
X541114Y278215D01*
X541129Y278180D01*
X541149Y278140D01*
X541249Y278000D01*
X541279Y277970D01*
Y275840D01*
X541289Y275715D01*
X541329Y275590D01*
X541389Y275480D01*
X541469Y275380D01*
X541569Y275300D01*
X541679Y275240D01*
X541804Y275200D01*
X541929Y275190D01*
X542054Y275200D01*
X542179Y275240D01*
X542289Y275300D01*
X542389Y275380D01*
X542469Y275480D01*
X542529Y275590D01*
X542569Y275715D01*
X542579Y275840D01*
Y277965D01*
X542609Y277995D01*
X542634Y278030D01*
X542664Y278065D01*
X542684Y278100D01*
X542709Y278135D01*
X542749Y278215D01*
X542794Y278335D01*
X542804Y278375D01*
X542814Y278420D01*
X542819Y278460D01*
X542829Y278505D01*
Y278675D01*
X542819Y278720D01*
X542814Y278760D01*
X542804Y278805D01*
X542794Y278845D01*
X542749Y278965D01*
X542709Y279045D01*
X542684Y279080D01*
X542664Y279115D01*
X542634Y279150D01*
X542609Y279185D01*
X542579Y279215D01*
Y281640D01*
X542569Y281765D01*
X542529Y281890D01*
X542469Y282000D01*
X542389Y282100D01*
X542289Y282180D01*
X542179Y282240D01*
X542054Y282280D01*
X541929Y282290D01*
G37*
G36*
G01X546654D02*
X546529Y282280D01*
X546404Y282240D01*
X546294Y282180D01*
X546194Y282100D01*
X546114Y282000D01*
X546054Y281890D01*
X546014Y281765D01*
X546004Y281640D01*
Y279210D01*
X545974Y279180D01*
X545874Y279040D01*
X545854Y279000D01*
X545839Y278965D01*
X545819Y278925D01*
X545804Y278885D01*
X545794Y278845D01*
X545779Y278800D01*
X545774Y278760D01*
X545764Y278720D01*
X545759Y278675D01*
Y278635D01*
X545754Y278590D01*
X545759Y278545D01*
Y278505D01*
X545764Y278460D01*
X545774Y278420D01*
X545779Y278380D01*
X545794Y278335D01*
X545804Y278295D01*
X545819Y278255D01*
X545839Y278215D01*
X545854Y278180D01*
X545874Y278140D01*
X545974Y278000D01*
X546004Y277970D01*
Y275840D01*
X546014Y275715D01*
X546054Y275590D01*
X546114Y275480D01*
X546194Y275380D01*
X546294Y275300D01*
X546404Y275240D01*
X546529Y275200D01*
X546654Y275190D01*
X546779Y275200D01*
X546904Y275240D01*
X547014Y275300D01*
X547114Y275380D01*
X547194Y275480D01*
X547254Y275590D01*
X547294Y275715D01*
X547304Y275840D01*
Y277965D01*
X547334Y277995D01*
X547359Y278030D01*
X547389Y278065D01*
X547409Y278100D01*
X547434Y278135D01*
X547474Y278215D01*
X547519Y278335D01*
X547529Y278375D01*
X547539Y278420D01*
X547544Y278460D01*
X547554Y278505D01*
Y278675D01*
X547544Y278720D01*
X547539Y278760D01*
X547529Y278805D01*
X547519Y278845D01*
X547474Y278965D01*
X547434Y279045D01*
X547409Y279080D01*
X547389Y279115D01*
X547359Y279150D01*
X547334Y279185D01*
X547304Y279215D01*
Y281640D01*
X547294Y281765D01*
X547254Y281890D01*
X547194Y282000D01*
X547114Y282100D01*
X547014Y282180D01*
X546904Y282240D01*
X546779Y282280D01*
X546654Y282290D01*
G37*
G36*
G01X551378D02*
X551253Y282280D01*
X551128Y282240D01*
X551018Y282180D01*
X550918Y282100D01*
X550838Y282000D01*
X550778Y281890D01*
X550738Y281765D01*
X550728Y281640D01*
Y279210D01*
X550698Y279180D01*
X550598Y279040D01*
X550578Y279000D01*
X550563Y278965D01*
X550543Y278925D01*
X550528Y278885D01*
X550518Y278845D01*
X550503Y278800D01*
X550498Y278760D01*
X550488Y278720D01*
X550483Y278675D01*
Y278635D01*
X550478Y278590D01*
X550483Y278545D01*
Y278505D01*
X550488Y278460D01*
X550498Y278420D01*
X550503Y278380D01*
X550518Y278335D01*
X550528Y278295D01*
X550543Y278255D01*
X550563Y278215D01*
X550578Y278180D01*
X550598Y278140D01*
X550698Y278000D01*
X550728Y277970D01*
Y275840D01*
X550738Y275715D01*
X550778Y275590D01*
X550838Y275480D01*
X550918Y275380D01*
X551018Y275300D01*
X551128Y275240D01*
X551253Y275200D01*
X551378Y275190D01*
X551503Y275200D01*
X551628Y275240D01*
X551738Y275300D01*
X551838Y275380D01*
X551918Y275480D01*
X551978Y275590D01*
X552018Y275715D01*
X552028Y275840D01*
Y277965D01*
X552058Y277995D01*
X552083Y278030D01*
X552113Y278065D01*
X552133Y278100D01*
X552158Y278135D01*
X552198Y278215D01*
X552243Y278335D01*
X552253Y278375D01*
X552263Y278420D01*
X552268Y278460D01*
X552278Y278505D01*
Y278675D01*
X552268Y278720D01*
X552263Y278760D01*
X552253Y278805D01*
X552243Y278845D01*
X552198Y278965D01*
X552158Y279045D01*
X552133Y279080D01*
X552113Y279115D01*
X552083Y279150D01*
X552058Y279185D01*
X552028Y279215D01*
Y281640D01*
X552018Y281765D01*
X551978Y281890D01*
X551918Y282000D01*
X551838Y282100D01*
X551738Y282180D01*
X551628Y282240D01*
X551503Y282280D01*
X551378Y282290D01*
G37*
G36*
G01X556103D02*
X555978Y282280D01*
X555853Y282240D01*
X555743Y282180D01*
X555643Y282100D01*
X555563Y282000D01*
X555503Y281890D01*
X555463Y281765D01*
X555453Y281640D01*
Y279210D01*
X555423Y279180D01*
X555323Y279040D01*
X555303Y279000D01*
X555288Y278965D01*
X555268Y278925D01*
X555253Y278885D01*
X555243Y278845D01*
X555228Y278800D01*
X555223Y278760D01*
X555213Y278720D01*
X555208Y278675D01*
Y278635D01*
X555203Y278590D01*
X555208Y278545D01*
Y278505D01*
X555213Y278460D01*
X555223Y278420D01*
X555228Y278380D01*
X555243Y278335D01*
X555253Y278295D01*
X555268Y278255D01*
X555288Y278215D01*
X555303Y278180D01*
X555323Y278140D01*
X555423Y278000D01*
X555453Y277970D01*
Y275840D01*
X555463Y275715D01*
X555503Y275590D01*
X555563Y275480D01*
X555643Y275380D01*
X555743Y275300D01*
X555853Y275240D01*
X555978Y275200D01*
X556103Y275190D01*
X556228Y275200D01*
X556353Y275240D01*
X556463Y275300D01*
X556563Y275380D01*
X556643Y275480D01*
X556703Y275590D01*
X556743Y275715D01*
X556753Y275840D01*
Y277965D01*
X556783Y277995D01*
X556808Y278030D01*
X556838Y278065D01*
X556858Y278100D01*
X556883Y278135D01*
X556923Y278215D01*
X556968Y278335D01*
X556978Y278375D01*
X556988Y278420D01*
X556993Y278460D01*
X557003Y278505D01*
Y278675D01*
X556993Y278720D01*
X556988Y278760D01*
X556978Y278805D01*
X556968Y278845D01*
X556923Y278965D01*
X556883Y279045D01*
X556858Y279080D01*
X556838Y279115D01*
X556808Y279150D01*
X556783Y279185D01*
X556753Y279215D01*
Y281640D01*
X556743Y281765D01*
X556703Y281890D01*
X556643Y282000D01*
X556563Y282100D01*
X556463Y282180D01*
X556353Y282240D01*
X556228Y282280D01*
X556103Y282290D01*
G37*
G36*
G01X560827D02*
X560702Y282280D01*
X560577Y282240D01*
X560467Y282180D01*
X560367Y282100D01*
X560287Y282000D01*
X560227Y281890D01*
X560187Y281765D01*
X560177Y281640D01*
Y279210D01*
X560147Y279180D01*
X560047Y279040D01*
X560027Y279000D01*
X560012Y278965D01*
X559992Y278925D01*
X559977Y278885D01*
X559967Y278845D01*
X559952Y278800D01*
X559947Y278760D01*
X559937Y278720D01*
X559932Y278675D01*
Y278635D01*
X559927Y278590D01*
X559932Y278545D01*
Y278505D01*
X559937Y278460D01*
X559947Y278420D01*
X559952Y278380D01*
X559967Y278335D01*
X559977Y278295D01*
X559992Y278255D01*
X560012Y278215D01*
X560027Y278180D01*
X560047Y278140D01*
X560147Y278000D01*
X560177Y277970D01*
Y275840D01*
X560187Y275715D01*
X560227Y275590D01*
X560287Y275480D01*
X560367Y275380D01*
X560467Y275300D01*
X560577Y275240D01*
X560702Y275200D01*
X560827Y275190D01*
X560952Y275200D01*
X561077Y275240D01*
X561187Y275300D01*
X561287Y275380D01*
X561367Y275480D01*
X561427Y275590D01*
X561467Y275715D01*
X561477Y275840D01*
Y277965D01*
X561507Y277995D01*
X561532Y278030D01*
X561562Y278065D01*
X561582Y278100D01*
X561607Y278135D01*
X561647Y278215D01*
X561692Y278335D01*
X561702Y278375D01*
X561712Y278420D01*
X561717Y278460D01*
X561727Y278505D01*
Y278675D01*
X561717Y278720D01*
X561712Y278760D01*
X561702Y278805D01*
X561692Y278845D01*
X561647Y278965D01*
X561607Y279045D01*
X561582Y279080D01*
X561562Y279115D01*
X561532Y279150D01*
X561507Y279185D01*
X561477Y279215D01*
Y281640D01*
X561467Y281765D01*
X561427Y281890D01*
X561367Y282000D01*
X561287Y282100D01*
X561187Y282180D01*
X561077Y282240D01*
X560952Y282280D01*
X560827Y282290D01*
G37*
G36*
G01X565551D02*
X565426Y282280D01*
X565301Y282240D01*
X565191Y282180D01*
X565091Y282100D01*
X565011Y282000D01*
X564951Y281890D01*
X564911Y281765D01*
X564901Y281640D01*
Y279210D01*
X564871Y279180D01*
X564771Y279040D01*
X564751Y279000D01*
X564736Y278965D01*
X564716Y278925D01*
X564701Y278885D01*
X564691Y278845D01*
X564676Y278800D01*
X564671Y278760D01*
X564661Y278720D01*
X564656Y278675D01*
Y278635D01*
X564651Y278590D01*
X564656Y278545D01*
Y278505D01*
X564661Y278460D01*
X564671Y278420D01*
X564676Y278380D01*
X564691Y278335D01*
X564701Y278295D01*
X564716Y278255D01*
X564736Y278215D01*
X564751Y278180D01*
X564771Y278140D01*
X564871Y278000D01*
X564901Y277970D01*
Y275840D01*
X564911Y275715D01*
X564951Y275590D01*
X565011Y275480D01*
X565091Y275380D01*
X565191Y275300D01*
X565301Y275240D01*
X565426Y275200D01*
X565551Y275190D01*
X565676Y275200D01*
X565801Y275240D01*
X565911Y275300D01*
X566011Y275380D01*
X566091Y275480D01*
X566151Y275590D01*
X566191Y275715D01*
X566201Y275840D01*
Y277965D01*
X566231Y277995D01*
X566256Y278030D01*
X566286Y278065D01*
X566306Y278100D01*
X566331Y278135D01*
X566371Y278215D01*
X566416Y278335D01*
X566426Y278375D01*
X566436Y278420D01*
X566441Y278460D01*
X566451Y278505D01*
Y278675D01*
X566441Y278720D01*
X566436Y278760D01*
X566426Y278805D01*
X566416Y278845D01*
X566371Y278965D01*
X566331Y279045D01*
X566306Y279080D01*
X566286Y279115D01*
X566256Y279150D01*
X566231Y279185D01*
X566201Y279215D01*
Y281640D01*
X566191Y281765D01*
X566151Y281890D01*
X566091Y282000D01*
X566011Y282100D01*
X565911Y282180D01*
X565801Y282240D01*
X565676Y282280D01*
X565551Y282290D01*
G37*
G36*
G01X570276D02*
X570151Y282280D01*
X570026Y282240D01*
X569916Y282180D01*
X569816Y282100D01*
X569736Y282000D01*
X569676Y281890D01*
X569636Y281765D01*
X569626Y281640D01*
Y279210D01*
X569596Y279180D01*
X569496Y279040D01*
X569476Y279000D01*
X569461Y278965D01*
X569441Y278925D01*
X569426Y278885D01*
X569416Y278845D01*
X569401Y278800D01*
X569396Y278760D01*
X569386Y278720D01*
X569381Y278675D01*
Y278635D01*
X569376Y278590D01*
X569381Y278545D01*
Y278505D01*
X569386Y278460D01*
X569396Y278420D01*
X569401Y278380D01*
X569416Y278335D01*
X569426Y278295D01*
X569441Y278255D01*
X569461Y278215D01*
X569476Y278180D01*
X569496Y278140D01*
X569596Y278000D01*
X569626Y277970D01*
Y275840D01*
X569636Y275715D01*
X569676Y275590D01*
X569736Y275480D01*
X569816Y275380D01*
X569916Y275300D01*
X570026Y275240D01*
X570151Y275200D01*
X570276Y275190D01*
X570401Y275200D01*
X570526Y275240D01*
X570636Y275300D01*
X570736Y275380D01*
X570816Y275480D01*
X570876Y275590D01*
X570916Y275715D01*
X570926Y275840D01*
Y277965D01*
X570956Y277995D01*
X570981Y278030D01*
X571011Y278065D01*
X571031Y278100D01*
X571056Y278135D01*
X571096Y278215D01*
X571141Y278335D01*
X571151Y278375D01*
X571161Y278420D01*
X571166Y278460D01*
X571176Y278505D01*
Y278675D01*
X571166Y278720D01*
X571161Y278760D01*
X571151Y278805D01*
X571141Y278845D01*
X571096Y278965D01*
X571056Y279045D01*
X571031Y279080D01*
X571011Y279115D01*
X570981Y279150D01*
X570956Y279185D01*
X570926Y279215D01*
Y281640D01*
X570916Y281765D01*
X570876Y281890D01*
X570816Y282000D01*
X570736Y282100D01*
X570636Y282180D01*
X570526Y282240D01*
X570401Y282280D01*
X570276Y282290D01*
G37*
G36*
G01X575000D02*
X574875Y282280D01*
X574750Y282240D01*
X574640Y282180D01*
X574540Y282100D01*
X574460Y282000D01*
X574400Y281890D01*
X574360Y281765D01*
X574350Y281640D01*
Y279210D01*
X574320Y279180D01*
X574220Y279040D01*
X574200Y279000D01*
X574185Y278965D01*
X574165Y278925D01*
X574150Y278885D01*
X574140Y278845D01*
X574125Y278800D01*
X574120Y278760D01*
X574110Y278720D01*
X574105Y278675D01*
Y278635D01*
X574100Y278590D01*
X574105Y278545D01*
Y278505D01*
X574110Y278460D01*
X574120Y278420D01*
X574125Y278380D01*
X574140Y278335D01*
X574150Y278295D01*
X574165Y278255D01*
X574185Y278215D01*
X574200Y278180D01*
X574220Y278140D01*
X574320Y278000D01*
X574350Y277970D01*
Y275840D01*
X574360Y275715D01*
X574400Y275590D01*
X574460Y275480D01*
X574540Y275380D01*
X574640Y275300D01*
X574750Y275240D01*
X574875Y275200D01*
X575000Y275190D01*
X575125Y275200D01*
X575250Y275240D01*
X575360Y275300D01*
X575460Y275380D01*
X575540Y275480D01*
X575600Y275590D01*
X575640Y275715D01*
X575650Y275840D01*
Y277965D01*
X575680Y277995D01*
X575705Y278030D01*
X575735Y278065D01*
X575755Y278100D01*
X575780Y278135D01*
X575820Y278215D01*
X575865Y278335D01*
X575875Y278375D01*
X575885Y278420D01*
X575890Y278460D01*
X575900Y278505D01*
Y278675D01*
X575890Y278720D01*
X575885Y278760D01*
X575875Y278805D01*
X575865Y278845D01*
X575820Y278965D01*
X575780Y279045D01*
X575755Y279080D01*
X575735Y279115D01*
X575705Y279150D01*
X575680Y279185D01*
X575650Y279215D01*
Y281640D01*
X575640Y281765D01*
X575600Y281890D01*
X575540Y282000D01*
X575460Y282100D01*
X575360Y282180D01*
X575250Y282240D01*
X575125Y282280D01*
X575000Y282290D01*
G37*
G36*
G01X579725D02*
X579600Y282280D01*
X579475Y282240D01*
X579365Y282180D01*
X579265Y282100D01*
X579185Y282000D01*
X579125Y281890D01*
X579085Y281765D01*
X579075Y281640D01*
Y279210D01*
X579045Y279180D01*
X578945Y279040D01*
X578925Y279000D01*
X578910Y278965D01*
X578890Y278925D01*
X578875Y278885D01*
X578865Y278845D01*
X578850Y278800D01*
X578845Y278760D01*
X578835Y278720D01*
X578830Y278675D01*
Y278635D01*
X578825Y278590D01*
X578830Y278545D01*
Y278505D01*
X578835Y278460D01*
X578845Y278420D01*
X578850Y278380D01*
X578865Y278335D01*
X578875Y278295D01*
X578890Y278255D01*
X578910Y278215D01*
X578925Y278180D01*
X578945Y278140D01*
X579045Y278000D01*
X579075Y277970D01*
Y275840D01*
X579085Y275715D01*
X579125Y275590D01*
X579185Y275480D01*
X579265Y275380D01*
X579365Y275300D01*
X579475Y275240D01*
X579600Y275200D01*
X579725Y275190D01*
X579850Y275200D01*
X579975Y275240D01*
X580085Y275300D01*
X580185Y275380D01*
X580265Y275480D01*
X580325Y275590D01*
X580365Y275715D01*
X580375Y275840D01*
Y277965D01*
X580405Y277995D01*
X580430Y278030D01*
X580460Y278065D01*
X580480Y278100D01*
X580505Y278135D01*
X580545Y278215D01*
X580590Y278335D01*
X580600Y278375D01*
X580610Y278420D01*
X580615Y278460D01*
X580625Y278505D01*
Y278675D01*
X580615Y278720D01*
X580610Y278760D01*
X580600Y278805D01*
X580590Y278845D01*
X580545Y278965D01*
X580505Y279045D01*
X580480Y279080D01*
X580460Y279115D01*
X580430Y279150D01*
X580405Y279185D01*
X580375Y279215D01*
Y281640D01*
X580365Y281765D01*
X580325Y281890D01*
X580265Y282000D01*
X580185Y282100D01*
X580085Y282180D01*
X579975Y282240D01*
X579850Y282280D01*
X579725Y282290D01*
G37*
G36*
G01X584449D02*
X584324Y282280D01*
X584199Y282240D01*
X584089Y282180D01*
X583989Y282100D01*
X583909Y282000D01*
X583849Y281890D01*
X583809Y281765D01*
X583799Y281640D01*
Y279210D01*
X583769Y279180D01*
X583669Y279040D01*
X583649Y279000D01*
X583634Y278965D01*
X583614Y278925D01*
X583599Y278885D01*
X583589Y278845D01*
X583574Y278800D01*
X583569Y278760D01*
X583559Y278720D01*
X583554Y278675D01*
Y278635D01*
X583549Y278590D01*
X583554Y278545D01*
Y278505D01*
X583559Y278460D01*
X583569Y278420D01*
X583574Y278380D01*
X583589Y278335D01*
X583599Y278295D01*
X583614Y278255D01*
X583634Y278215D01*
X583649Y278180D01*
X583669Y278140D01*
X583769Y278000D01*
X583799Y277970D01*
Y275840D01*
X583809Y275715D01*
X583849Y275590D01*
X583909Y275480D01*
X583989Y275380D01*
X584089Y275300D01*
X584199Y275240D01*
X584324Y275200D01*
X584449Y275190D01*
X584574Y275200D01*
X584699Y275240D01*
X584809Y275300D01*
X584909Y275380D01*
X584989Y275480D01*
X585049Y275590D01*
X585089Y275715D01*
X585099Y275840D01*
Y277965D01*
X585129Y277995D01*
X585154Y278030D01*
X585184Y278065D01*
X585204Y278100D01*
X585229Y278135D01*
X585269Y278215D01*
X585314Y278335D01*
X585324Y278375D01*
X585334Y278420D01*
X585339Y278460D01*
X585349Y278505D01*
Y278675D01*
X585339Y278720D01*
X585334Y278760D01*
X585324Y278805D01*
X585314Y278845D01*
X585269Y278965D01*
X585229Y279045D01*
X585204Y279080D01*
X585184Y279115D01*
X585154Y279150D01*
X585129Y279185D01*
X585099Y279215D01*
Y281640D01*
X585089Y281765D01*
X585049Y281890D01*
X584989Y282000D01*
X584909Y282100D01*
X584809Y282180D01*
X584699Y282240D01*
X584574Y282280D01*
X584449Y282290D01*
G37*
G36*
G01X589173D02*
X589048Y282280D01*
X588923Y282240D01*
X588813Y282180D01*
X588713Y282100D01*
X588633Y282000D01*
X588573Y281890D01*
X588533Y281765D01*
X588523Y281640D01*
Y279210D01*
X588493Y279180D01*
X588393Y279040D01*
X588373Y279000D01*
X588358Y278965D01*
X588338Y278925D01*
X588323Y278885D01*
X588313Y278845D01*
X588298Y278800D01*
X588293Y278760D01*
X588283Y278720D01*
X588278Y278675D01*
Y278635D01*
X588273Y278590D01*
X588278Y278545D01*
Y278505D01*
X588283Y278460D01*
X588293Y278420D01*
X588298Y278380D01*
X588313Y278335D01*
X588323Y278295D01*
X588338Y278255D01*
X588358Y278215D01*
X588373Y278180D01*
X588393Y278140D01*
X588493Y278000D01*
X588523Y277970D01*
Y275840D01*
X588533Y275715D01*
X588573Y275590D01*
X588633Y275480D01*
X588713Y275380D01*
X588813Y275300D01*
X588923Y275240D01*
X589048Y275200D01*
X589173Y275190D01*
X589298Y275200D01*
X589423Y275240D01*
X589533Y275300D01*
X589633Y275380D01*
X589713Y275480D01*
X589773Y275590D01*
X589813Y275715D01*
X589823Y275840D01*
Y277965D01*
X589853Y277995D01*
X589878Y278030D01*
X589908Y278065D01*
X589928Y278100D01*
X589953Y278135D01*
X589993Y278215D01*
X590038Y278335D01*
X590048Y278375D01*
X590058Y278420D01*
X590063Y278460D01*
X590073Y278505D01*
Y278675D01*
X590063Y278720D01*
X590058Y278760D01*
X590048Y278805D01*
X590038Y278845D01*
X589993Y278965D01*
X589953Y279045D01*
X589928Y279080D01*
X589908Y279115D01*
X589878Y279150D01*
X589853Y279185D01*
X589823Y279215D01*
Y281640D01*
X589813Y281765D01*
X589773Y281890D01*
X589713Y282000D01*
X589633Y282100D01*
X589533Y282180D01*
X589423Y282240D01*
X589298Y282280D01*
X589173Y282290D01*
G37*
G36*
G01X593898D02*
X593773Y282280D01*
X593648Y282240D01*
X593538Y282180D01*
X593438Y282100D01*
X593358Y282000D01*
X593298Y281890D01*
X593258Y281765D01*
X593248Y281640D01*
Y279210D01*
X593218Y279180D01*
X593118Y279040D01*
X593098Y279000D01*
X593083Y278965D01*
X593063Y278925D01*
X593048Y278885D01*
X593038Y278845D01*
X593023Y278800D01*
X593018Y278760D01*
X593008Y278720D01*
X593003Y278675D01*
Y278635D01*
X592998Y278590D01*
X593003Y278545D01*
Y278505D01*
X593008Y278460D01*
X593018Y278420D01*
X593023Y278380D01*
X593038Y278335D01*
X593048Y278295D01*
X593063Y278255D01*
X593083Y278215D01*
X593098Y278180D01*
X593118Y278140D01*
X593218Y278000D01*
X593248Y277970D01*
Y275840D01*
X593258Y275715D01*
X593298Y275590D01*
X593358Y275480D01*
X593438Y275380D01*
X593538Y275300D01*
X593648Y275240D01*
X593773Y275200D01*
X593898Y275190D01*
X594023Y275200D01*
X594148Y275240D01*
X594258Y275300D01*
X594358Y275380D01*
X594438Y275480D01*
X594498Y275590D01*
X594538Y275715D01*
X594548Y275840D01*
Y277965D01*
X594578Y277995D01*
X594603Y278030D01*
X594633Y278065D01*
X594653Y278100D01*
X594678Y278135D01*
X594718Y278215D01*
X594763Y278335D01*
X594773Y278375D01*
X594783Y278420D01*
X594788Y278460D01*
X594798Y278505D01*
Y278675D01*
X594788Y278720D01*
X594783Y278760D01*
X594773Y278805D01*
X594763Y278845D01*
X594718Y278965D01*
X594678Y279045D01*
X594653Y279080D01*
X594633Y279115D01*
X594603Y279150D01*
X594578Y279185D01*
X594548Y279215D01*
Y281640D01*
X594538Y281765D01*
X594498Y281890D01*
X594438Y282000D01*
X594358Y282100D01*
X594258Y282180D01*
X594148Y282240D01*
X594023Y282280D01*
X593898Y282290D01*
G37*
G36*
G01X598622D02*
X598497Y282280D01*
X598372Y282240D01*
X598262Y282180D01*
X598162Y282100D01*
X598082Y282000D01*
X598022Y281890D01*
X597982Y281765D01*
X597972Y281640D01*
Y279210D01*
X597942Y279180D01*
X597842Y279040D01*
X597822Y279000D01*
X597807Y278965D01*
X597787Y278925D01*
X597772Y278885D01*
X597762Y278845D01*
X597747Y278800D01*
X597742Y278760D01*
X597732Y278720D01*
X597727Y278675D01*
Y278635D01*
X597722Y278590D01*
X597727Y278545D01*
Y278505D01*
X597732Y278460D01*
X597742Y278420D01*
X597747Y278380D01*
X597762Y278335D01*
X597772Y278295D01*
X597787Y278255D01*
X597807Y278215D01*
X597822Y278180D01*
X597842Y278140D01*
X597942Y278000D01*
X597972Y277970D01*
Y275840D01*
X597982Y275715D01*
X598022Y275590D01*
X598082Y275480D01*
X598162Y275380D01*
X598262Y275300D01*
X598372Y275240D01*
X598497Y275200D01*
X598622Y275190D01*
X598747Y275200D01*
X598872Y275240D01*
X598982Y275300D01*
X599082Y275380D01*
X599162Y275480D01*
X599222Y275590D01*
X599262Y275715D01*
X599272Y275840D01*
Y277965D01*
X599302Y277995D01*
X599327Y278030D01*
X599357Y278065D01*
X599377Y278100D01*
X599402Y278135D01*
X599442Y278215D01*
X599487Y278335D01*
X599497Y278375D01*
X599507Y278420D01*
X599512Y278460D01*
X599522Y278505D01*
Y278675D01*
X599512Y278720D01*
X599507Y278760D01*
X599497Y278805D01*
X599487Y278845D01*
X599442Y278965D01*
X599402Y279045D01*
X599377Y279080D01*
X599357Y279115D01*
X599327Y279150D01*
X599302Y279185D01*
X599272Y279215D01*
Y281640D01*
X599262Y281765D01*
X599222Y281890D01*
X599162Y282000D01*
X599082Y282100D01*
X598982Y282180D01*
X598872Y282240D01*
X598747Y282280D01*
X598622Y282290D01*
G37*
G36*
G01X603347D02*
X603222Y282280D01*
X603097Y282240D01*
X602987Y282180D01*
X602887Y282100D01*
X602807Y282000D01*
X602747Y281890D01*
X602707Y281765D01*
X602697Y281640D01*
Y279210D01*
X602667Y279180D01*
X602567Y279040D01*
X602547Y279000D01*
X602532Y278965D01*
X602512Y278925D01*
X602497Y278885D01*
X602487Y278845D01*
X602472Y278800D01*
X602467Y278760D01*
X602457Y278720D01*
X602452Y278675D01*
Y278635D01*
X602447Y278590D01*
X602452Y278545D01*
Y278505D01*
X602457Y278460D01*
X602467Y278420D01*
X602472Y278380D01*
X602487Y278335D01*
X602497Y278295D01*
X602512Y278255D01*
X602532Y278215D01*
X602547Y278180D01*
X602567Y278140D01*
X602667Y278000D01*
X602697Y277970D01*
Y275840D01*
X602707Y275715D01*
X602747Y275590D01*
X602807Y275480D01*
X602887Y275380D01*
X602987Y275300D01*
X603097Y275240D01*
X603222Y275200D01*
X603347Y275190D01*
X603472Y275200D01*
X603597Y275240D01*
X603707Y275300D01*
X603807Y275380D01*
X603887Y275480D01*
X603947Y275590D01*
X603987Y275715D01*
X603997Y275840D01*
Y277965D01*
X604027Y277995D01*
X604052Y278030D01*
X604082Y278065D01*
X604102Y278100D01*
X604127Y278135D01*
X604167Y278215D01*
X604212Y278335D01*
X604222Y278375D01*
X604232Y278420D01*
X604237Y278460D01*
X604247Y278505D01*
Y278675D01*
X604237Y278720D01*
X604232Y278760D01*
X604222Y278805D01*
X604212Y278845D01*
X604167Y278965D01*
X604127Y279045D01*
X604102Y279080D01*
X604082Y279115D01*
X604052Y279150D01*
X604027Y279185D01*
X603997Y279215D01*
Y281640D01*
X603987Y281765D01*
X603947Y281890D01*
X603887Y282000D01*
X603807Y282100D01*
X603707Y282180D01*
X603597Y282240D01*
X603472Y282280D01*
X603347Y282290D01*
G37*
G36*
G01X608071D02*
X607946Y282280D01*
X607821Y282240D01*
X607711Y282180D01*
X607611Y282100D01*
X607531Y282000D01*
X607471Y281890D01*
X607431Y281765D01*
X607421Y281640D01*
Y279210D01*
X607391Y279180D01*
X607291Y279040D01*
X607271Y279000D01*
X607256Y278965D01*
X607236Y278925D01*
X607221Y278885D01*
X607211Y278845D01*
X607196Y278800D01*
X607191Y278760D01*
X607181Y278720D01*
X607176Y278675D01*
Y278635D01*
X607171Y278590D01*
X607176Y278545D01*
Y278505D01*
X607181Y278460D01*
X607191Y278420D01*
X607196Y278380D01*
X607211Y278335D01*
X607221Y278295D01*
X607236Y278255D01*
X607256Y278215D01*
X607271Y278180D01*
X607291Y278140D01*
X607391Y278000D01*
X607421Y277970D01*
Y275840D01*
X607431Y275715D01*
X607471Y275590D01*
X607531Y275480D01*
X607611Y275380D01*
X607711Y275300D01*
X607821Y275240D01*
X607946Y275200D01*
X608071Y275190D01*
X608196Y275200D01*
X608321Y275240D01*
X608431Y275300D01*
X608531Y275380D01*
X608611Y275480D01*
X608671Y275590D01*
X608711Y275715D01*
X608721Y275840D01*
Y277965D01*
X608751Y277995D01*
X608776Y278030D01*
X608806Y278065D01*
X608826Y278100D01*
X608851Y278135D01*
X608891Y278215D01*
X608936Y278335D01*
X608946Y278375D01*
X608956Y278420D01*
X608961Y278460D01*
X608971Y278505D01*
Y278675D01*
X608961Y278720D01*
X608956Y278760D01*
X608946Y278805D01*
X608936Y278845D01*
X608891Y278965D01*
X608851Y279045D01*
X608826Y279080D01*
X608806Y279115D01*
X608776Y279150D01*
X608751Y279185D01*
X608721Y279215D01*
Y281640D01*
X608711Y281765D01*
X608671Y281890D01*
X608611Y282000D01*
X608531Y282100D01*
X608431Y282180D01*
X608321Y282240D01*
X608196Y282280D01*
X608071Y282290D01*
G37*
G36*
G01X612796D02*
X612671Y282280D01*
X612546Y282240D01*
X612436Y282180D01*
X612336Y282100D01*
X612256Y282000D01*
X612196Y281890D01*
X612156Y281765D01*
X612146Y281640D01*
Y279210D01*
X612116Y279180D01*
X612016Y279040D01*
X611996Y279000D01*
X611981Y278965D01*
X611961Y278925D01*
X611946Y278885D01*
X611936Y278845D01*
X611921Y278800D01*
X611916Y278760D01*
X611906Y278720D01*
X611901Y278675D01*
Y278635D01*
X611896Y278590D01*
X611901Y278545D01*
Y278505D01*
X611906Y278460D01*
X611916Y278420D01*
X611921Y278380D01*
X611936Y278335D01*
X611946Y278295D01*
X611961Y278255D01*
X611981Y278215D01*
X611996Y278180D01*
X612016Y278140D01*
X612116Y278000D01*
X612146Y277970D01*
Y275840D01*
X612156Y275715D01*
X612196Y275590D01*
X612256Y275480D01*
X612336Y275380D01*
X612436Y275300D01*
X612546Y275240D01*
X612671Y275200D01*
X612796Y275190D01*
X612921Y275200D01*
X613046Y275240D01*
X613156Y275300D01*
X613256Y275380D01*
X613336Y275480D01*
X613396Y275590D01*
X613436Y275715D01*
X613446Y275840D01*
Y277965D01*
X613476Y277995D01*
X613501Y278030D01*
X613531Y278065D01*
X613551Y278100D01*
X613576Y278135D01*
X613616Y278215D01*
X613661Y278335D01*
X613671Y278375D01*
X613681Y278420D01*
X613686Y278460D01*
X613696Y278505D01*
Y278675D01*
X613686Y278720D01*
X613681Y278760D01*
X613671Y278805D01*
X613661Y278845D01*
X613616Y278965D01*
X613576Y279045D01*
X613551Y279080D01*
X613531Y279115D01*
X613501Y279150D01*
X613476Y279185D01*
X613446Y279215D01*
Y281640D01*
X613436Y281765D01*
X613396Y281890D01*
X613336Y282000D01*
X613256Y282100D01*
X613156Y282180D01*
X613046Y282240D01*
X612921Y282280D01*
X612796Y282290D01*
G37*
G36*
G01X617520D02*
X617395Y282280D01*
X617270Y282240D01*
X617160Y282180D01*
X617060Y282100D01*
X616980Y282000D01*
X616920Y281890D01*
X616880Y281765D01*
X616870Y281640D01*
Y279210D01*
X616840Y279180D01*
X616740Y279040D01*
X616720Y279000D01*
X616705Y278965D01*
X616685Y278925D01*
X616670Y278885D01*
X616660Y278845D01*
X616645Y278800D01*
X616640Y278760D01*
X616630Y278720D01*
X616625Y278675D01*
Y278635D01*
X616620Y278590D01*
X616625Y278545D01*
Y278505D01*
X616630Y278460D01*
X616640Y278420D01*
X616645Y278380D01*
X616660Y278335D01*
X616670Y278295D01*
X616685Y278255D01*
X616705Y278215D01*
X616720Y278180D01*
X616740Y278140D01*
X616840Y278000D01*
X616870Y277970D01*
Y275840D01*
X616880Y275715D01*
X616920Y275590D01*
X616980Y275480D01*
X617060Y275380D01*
X617160Y275300D01*
X617270Y275240D01*
X617395Y275200D01*
X617520Y275190D01*
X617645Y275200D01*
X617770Y275240D01*
X617880Y275300D01*
X617980Y275380D01*
X618060Y275480D01*
X618120Y275590D01*
X618160Y275715D01*
X618170Y275840D01*
Y277965D01*
X618200Y277995D01*
X618225Y278030D01*
X618255Y278065D01*
X618275Y278100D01*
X618300Y278135D01*
X618340Y278215D01*
X618385Y278335D01*
X618395Y278375D01*
X618405Y278420D01*
X618410Y278460D01*
X618420Y278505D01*
Y278675D01*
X618410Y278720D01*
X618405Y278760D01*
X618395Y278805D01*
X618385Y278845D01*
X618340Y278965D01*
X618300Y279045D01*
X618275Y279080D01*
X618255Y279115D01*
X618225Y279150D01*
X618200Y279185D01*
X618170Y279215D01*
Y281640D01*
X618160Y281765D01*
X618120Y281890D01*
X618060Y282000D01*
X617980Y282100D01*
X617880Y282180D01*
X617770Y282240D01*
X617645Y282280D01*
X617520Y282290D01*
G37*
G36*
G01X622244D02*
X622119Y282280D01*
X621994Y282240D01*
X621884Y282180D01*
X621784Y282100D01*
X621704Y282000D01*
X621644Y281890D01*
X621604Y281765D01*
X621594Y281640D01*
Y279210D01*
X621564Y279180D01*
X621464Y279040D01*
X621444Y279000D01*
X621429Y278965D01*
X621409Y278925D01*
X621394Y278885D01*
X621384Y278845D01*
X621369Y278800D01*
X621364Y278760D01*
X621354Y278720D01*
X621349Y278675D01*
Y278635D01*
X621344Y278590D01*
X621349Y278545D01*
Y278505D01*
X621354Y278460D01*
X621364Y278420D01*
X621369Y278380D01*
X621384Y278335D01*
X621394Y278295D01*
X621409Y278255D01*
X621429Y278215D01*
X621444Y278180D01*
X621464Y278140D01*
X621564Y278000D01*
X621594Y277970D01*
Y275840D01*
X621604Y275715D01*
X621644Y275590D01*
X621704Y275480D01*
X621784Y275380D01*
X621884Y275300D01*
X621994Y275240D01*
X622119Y275200D01*
X622244Y275190D01*
X622369Y275200D01*
X622494Y275240D01*
X622604Y275300D01*
X622704Y275380D01*
X622784Y275480D01*
X622844Y275590D01*
X622884Y275715D01*
X622894Y275840D01*
Y277965D01*
X622924Y277995D01*
X622949Y278030D01*
X622979Y278065D01*
X622999Y278100D01*
X623024Y278135D01*
X623064Y278215D01*
X623109Y278335D01*
X623119Y278375D01*
X623129Y278420D01*
X623134Y278460D01*
X623144Y278505D01*
Y278675D01*
X623134Y278720D01*
X623129Y278760D01*
X623119Y278805D01*
X623109Y278845D01*
X623064Y278965D01*
X623024Y279045D01*
X622999Y279080D01*
X622979Y279115D01*
X622949Y279150D01*
X622924Y279185D01*
X622894Y279215D01*
Y281640D01*
X622884Y281765D01*
X622844Y281890D01*
X622784Y282000D01*
X622704Y282100D01*
X622604Y282180D01*
X622494Y282240D01*
X622369Y282280D01*
X622244Y282290D01*
G37*
G36*
G01X626969D02*
X626844Y282280D01*
X626719Y282240D01*
X626609Y282180D01*
X626509Y282100D01*
X626429Y282000D01*
X626369Y281890D01*
X626329Y281765D01*
X626319Y281640D01*
Y279210D01*
X626289Y279180D01*
X626189Y279040D01*
X626169Y279000D01*
X626154Y278965D01*
X626134Y278925D01*
X626119Y278885D01*
X626109Y278845D01*
X626094Y278800D01*
X626089Y278760D01*
X626079Y278720D01*
X626074Y278675D01*
Y278635D01*
X626069Y278590D01*
X626074Y278545D01*
Y278505D01*
X626079Y278460D01*
X626089Y278420D01*
X626094Y278380D01*
X626109Y278335D01*
X626119Y278295D01*
X626134Y278255D01*
X626154Y278215D01*
X626169Y278180D01*
X626189Y278140D01*
X626289Y278000D01*
X626319Y277970D01*
Y275840D01*
X626329Y275715D01*
X626369Y275590D01*
X626429Y275480D01*
X626509Y275380D01*
X626609Y275300D01*
X626719Y275240D01*
X626844Y275200D01*
X626969Y275190D01*
X627094Y275200D01*
X627219Y275240D01*
X627329Y275300D01*
X627429Y275380D01*
X627509Y275480D01*
X627569Y275590D01*
X627609Y275715D01*
X627619Y275840D01*
Y277965D01*
X627649Y277995D01*
X627674Y278030D01*
X627704Y278065D01*
X627724Y278100D01*
X627749Y278135D01*
X627789Y278215D01*
X627834Y278335D01*
X627844Y278375D01*
X627854Y278420D01*
X627859Y278460D01*
X627869Y278505D01*
Y278675D01*
X627859Y278720D01*
X627854Y278760D01*
X627844Y278805D01*
X627834Y278845D01*
X627789Y278965D01*
X627749Y279045D01*
X627724Y279080D01*
X627704Y279115D01*
X627674Y279150D01*
X627649Y279185D01*
X627619Y279215D01*
Y281640D01*
X627609Y281765D01*
X627569Y281890D01*
X627509Y282000D01*
X627429Y282100D01*
X627329Y282180D01*
X627219Y282240D01*
X627094Y282280D01*
X626969Y282290D01*
G37*
G36*
G01X631693D02*
X631568Y282280D01*
X631443Y282240D01*
X631333Y282180D01*
X631233Y282100D01*
X631153Y282000D01*
X631093Y281890D01*
X631053Y281765D01*
X631043Y281640D01*
Y279210D01*
X631013Y279180D01*
X630913Y279040D01*
X630893Y279000D01*
X630878Y278965D01*
X630858Y278925D01*
X630843Y278885D01*
X630833Y278845D01*
X630818Y278800D01*
X630813Y278760D01*
X630803Y278720D01*
X630798Y278675D01*
Y278635D01*
X630793Y278590D01*
X630798Y278545D01*
Y278505D01*
X630803Y278460D01*
X630813Y278420D01*
X630818Y278380D01*
X630833Y278335D01*
X630843Y278295D01*
X630858Y278255D01*
X630878Y278215D01*
X630893Y278180D01*
X630913Y278140D01*
X631013Y278000D01*
X631043Y277970D01*
Y275840D01*
X631053Y275715D01*
X631093Y275590D01*
X631153Y275480D01*
X631233Y275380D01*
X631333Y275300D01*
X631443Y275240D01*
X631568Y275200D01*
X631693Y275190D01*
X631818Y275200D01*
X631943Y275240D01*
X632053Y275300D01*
X632153Y275380D01*
X632233Y275480D01*
X632293Y275590D01*
X632333Y275715D01*
X632343Y275840D01*
Y277965D01*
X632373Y277995D01*
X632398Y278030D01*
X632428Y278065D01*
X632448Y278100D01*
X632473Y278135D01*
X632513Y278215D01*
X632558Y278335D01*
X632568Y278375D01*
X632578Y278420D01*
X632583Y278460D01*
X632593Y278505D01*
Y278675D01*
X632583Y278720D01*
X632578Y278760D01*
X632568Y278805D01*
X632558Y278845D01*
X632513Y278965D01*
X632473Y279045D01*
X632448Y279080D01*
X632428Y279115D01*
X632398Y279150D01*
X632373Y279185D01*
X632343Y279215D01*
Y281640D01*
X632333Y281765D01*
X632293Y281890D01*
X632233Y282000D01*
X632153Y282100D01*
X632053Y282180D01*
X631943Y282240D01*
X631818Y282280D01*
X631693Y282290D01*
G37*
G36*
G01X636418D02*
X636293Y282280D01*
X636168Y282240D01*
X636058Y282180D01*
X635958Y282100D01*
X635878Y282000D01*
X635818Y281890D01*
X635778Y281765D01*
X635768Y281640D01*
Y279210D01*
X635738Y279180D01*
X635638Y279040D01*
X635618Y279000D01*
X635603Y278965D01*
X635583Y278925D01*
X635568Y278885D01*
X635558Y278845D01*
X635543Y278800D01*
X635538Y278760D01*
X635528Y278720D01*
X635523Y278675D01*
Y278635D01*
X635518Y278590D01*
X635523Y278545D01*
Y278505D01*
X635528Y278460D01*
X635538Y278420D01*
X635543Y278380D01*
X635558Y278335D01*
X635568Y278295D01*
X635583Y278255D01*
X635603Y278215D01*
X635618Y278180D01*
X635638Y278140D01*
X635738Y278000D01*
X635768Y277970D01*
Y275840D01*
X635778Y275715D01*
X635818Y275590D01*
X635878Y275480D01*
X635958Y275380D01*
X636058Y275300D01*
X636168Y275240D01*
X636293Y275200D01*
X636418Y275190D01*
X636543Y275200D01*
X636668Y275240D01*
X636778Y275300D01*
X636878Y275380D01*
X636958Y275480D01*
X637018Y275590D01*
X637058Y275715D01*
X637068Y275840D01*
Y277965D01*
X637098Y277995D01*
X637123Y278030D01*
X637153Y278065D01*
X637173Y278100D01*
X637198Y278135D01*
X637238Y278215D01*
X637283Y278335D01*
X637293Y278375D01*
X637303Y278420D01*
X637308Y278460D01*
X637318Y278505D01*
Y278675D01*
X637308Y278720D01*
X637303Y278760D01*
X637293Y278805D01*
X637283Y278845D01*
X637238Y278965D01*
X637198Y279045D01*
X637173Y279080D01*
X637153Y279115D01*
X637123Y279150D01*
X637098Y279185D01*
X637068Y279215D01*
Y281640D01*
X637058Y281765D01*
X637018Y281890D01*
X636958Y282000D01*
X636878Y282100D01*
X636778Y282180D01*
X636668Y282240D01*
X636543Y282280D01*
X636418Y282290D01*
G37*
G36*
G01X641142D02*
X641017Y282280D01*
X640892Y282240D01*
X640782Y282180D01*
X640682Y282100D01*
X640602Y282000D01*
X640542Y281890D01*
X640502Y281765D01*
X640492Y281640D01*
Y279210D01*
X640462Y279180D01*
X640362Y279040D01*
X640342Y279000D01*
X640327Y278965D01*
X640307Y278925D01*
X640292Y278885D01*
X640282Y278845D01*
X640267Y278800D01*
X640262Y278760D01*
X640252Y278720D01*
X640247Y278675D01*
Y278635D01*
X640242Y278590D01*
X640247Y278545D01*
Y278505D01*
X640252Y278460D01*
X640262Y278420D01*
X640267Y278380D01*
X640282Y278335D01*
X640292Y278295D01*
X640307Y278255D01*
X640327Y278215D01*
X640342Y278180D01*
X640362Y278140D01*
X640462Y278000D01*
X640492Y277970D01*
Y275840D01*
X640502Y275715D01*
X640542Y275590D01*
X640602Y275480D01*
X640682Y275380D01*
X640782Y275300D01*
X640892Y275240D01*
X641017Y275200D01*
X641142Y275190D01*
X641267Y275200D01*
X641392Y275240D01*
X641502Y275300D01*
X641602Y275380D01*
X641682Y275480D01*
X641742Y275590D01*
X641782Y275715D01*
X641792Y275840D01*
Y277965D01*
X641822Y277995D01*
X641847Y278030D01*
X641877Y278065D01*
X641897Y278100D01*
X641922Y278135D01*
X641962Y278215D01*
X642007Y278335D01*
X642017Y278375D01*
X642027Y278420D01*
X642032Y278460D01*
X642042Y278505D01*
Y278675D01*
X642032Y278720D01*
X642027Y278760D01*
X642017Y278805D01*
X642007Y278845D01*
X641962Y278965D01*
X641922Y279045D01*
X641897Y279080D01*
X641877Y279115D01*
X641847Y279150D01*
X641822Y279185D01*
X641792Y279215D01*
Y281640D01*
X641782Y281765D01*
X641742Y281890D01*
X641682Y282000D01*
X641602Y282100D01*
X641502Y282180D01*
X641392Y282240D01*
X641267Y282280D01*
X641142Y282290D01*
G37*
G36*
G01X645866D02*
X645741Y282280D01*
X645616Y282240D01*
X645506Y282180D01*
X645406Y282100D01*
X645326Y282000D01*
X645266Y281890D01*
X645226Y281765D01*
X645216Y281640D01*
Y279210D01*
X645186Y279180D01*
X645086Y279040D01*
X645066Y279000D01*
X645051Y278965D01*
X645031Y278925D01*
X645016Y278885D01*
X645006Y278845D01*
X644991Y278800D01*
X644986Y278760D01*
X644976Y278720D01*
X644971Y278675D01*
Y278635D01*
X644966Y278590D01*
X644971Y278545D01*
Y278505D01*
X644976Y278460D01*
X644986Y278420D01*
X644991Y278380D01*
X645006Y278335D01*
X645016Y278295D01*
X645031Y278255D01*
X645051Y278215D01*
X645066Y278180D01*
X645086Y278140D01*
X645186Y278000D01*
X645216Y277970D01*
Y275840D01*
X645226Y275715D01*
X645266Y275590D01*
X645326Y275480D01*
X645406Y275380D01*
X645506Y275300D01*
X645616Y275240D01*
X645741Y275200D01*
X645866Y275190D01*
X645991Y275200D01*
X646116Y275240D01*
X646226Y275300D01*
X646326Y275380D01*
X646406Y275480D01*
X646466Y275590D01*
X646506Y275715D01*
X646516Y275840D01*
Y277965D01*
X646546Y277995D01*
X646571Y278030D01*
X646601Y278065D01*
X646621Y278100D01*
X646646Y278135D01*
X646686Y278215D01*
X646731Y278335D01*
X646741Y278375D01*
X646751Y278420D01*
X646756Y278460D01*
X646766Y278505D01*
Y278675D01*
X646756Y278720D01*
X646751Y278760D01*
X646741Y278805D01*
X646731Y278845D01*
X646686Y278965D01*
X646646Y279045D01*
X646621Y279080D01*
X646601Y279115D01*
X646571Y279150D01*
X646546Y279185D01*
X646516Y279215D01*
Y281640D01*
X646506Y281765D01*
X646466Y281890D01*
X646406Y282000D01*
X646326Y282100D01*
X646226Y282180D01*
X646116Y282240D01*
X645991Y282280D01*
X645866Y282290D01*
G37*
G36*
G01X650591D02*
X650466Y282280D01*
X650341Y282240D01*
X650231Y282180D01*
X650131Y282100D01*
X650051Y282000D01*
X649991Y281890D01*
X649951Y281765D01*
X649941Y281640D01*
Y279210D01*
X649911Y279180D01*
X649811Y279040D01*
X649791Y279000D01*
X649776Y278965D01*
X649756Y278925D01*
X649741Y278885D01*
X649731Y278845D01*
X649716Y278800D01*
X649711Y278760D01*
X649701Y278720D01*
X649696Y278675D01*
Y278635D01*
X649691Y278590D01*
X649696Y278545D01*
Y278505D01*
X649701Y278460D01*
X649711Y278420D01*
X649716Y278380D01*
X649731Y278335D01*
X649741Y278295D01*
X649756Y278255D01*
X649776Y278215D01*
X649791Y278180D01*
X649811Y278140D01*
X649911Y278000D01*
X649941Y277970D01*
Y275840D01*
X649951Y275715D01*
X649991Y275590D01*
X650051Y275480D01*
X650131Y275380D01*
X650231Y275300D01*
X650341Y275240D01*
X650466Y275200D01*
X650591Y275190D01*
X650716Y275200D01*
X650841Y275240D01*
X650951Y275300D01*
X651051Y275380D01*
X651131Y275480D01*
X651191Y275590D01*
X651231Y275715D01*
X651241Y275840D01*
Y277965D01*
X651271Y277995D01*
X651296Y278030D01*
X651326Y278065D01*
X651346Y278100D01*
X651371Y278135D01*
X651411Y278215D01*
X651456Y278335D01*
X651466Y278375D01*
X651476Y278420D01*
X651481Y278460D01*
X651491Y278505D01*
Y278675D01*
X651481Y278720D01*
X651476Y278760D01*
X651466Y278805D01*
X651456Y278845D01*
X651411Y278965D01*
X651371Y279045D01*
X651346Y279080D01*
X651326Y279115D01*
X651296Y279150D01*
X651271Y279185D01*
X651241Y279215D01*
Y281640D01*
X651231Y281765D01*
X651191Y281890D01*
X651131Y282000D01*
X651051Y282100D01*
X650951Y282180D01*
X650841Y282240D01*
X650716Y282280D01*
X650591Y282290D01*
G37*
G36*
G01X664764D02*
X664639Y282280D01*
X664514Y282240D01*
X664404Y282180D01*
X664304Y282100D01*
X664224Y282000D01*
X664164Y281890D01*
X664124Y281765D01*
X664114Y281640D01*
Y279210D01*
X664084Y279180D01*
X663984Y279040D01*
X663964Y279000D01*
X663949Y278965D01*
X663929Y278925D01*
X663914Y278885D01*
X663904Y278845D01*
X663889Y278800D01*
X663884Y278760D01*
X663874Y278720D01*
X663869Y278675D01*
Y278635D01*
X663864Y278590D01*
X663869Y278545D01*
Y278505D01*
X663874Y278460D01*
X663884Y278420D01*
X663889Y278380D01*
X663904Y278335D01*
X663914Y278295D01*
X663929Y278255D01*
X663949Y278215D01*
X663964Y278180D01*
X663984Y278140D01*
X664084Y278000D01*
X664114Y277970D01*
Y275840D01*
X664124Y275715D01*
X664164Y275590D01*
X664224Y275480D01*
X664304Y275380D01*
X664404Y275300D01*
X664514Y275240D01*
X664639Y275200D01*
X664764Y275190D01*
X664889Y275200D01*
X665014Y275240D01*
X665124Y275300D01*
X665224Y275380D01*
X665304Y275480D01*
X665364Y275590D01*
X665404Y275715D01*
X665414Y275840D01*
Y277965D01*
X665444Y277995D01*
X665469Y278030D01*
X665499Y278065D01*
X665519Y278100D01*
X665544Y278135D01*
X665584Y278215D01*
X665629Y278335D01*
X665639Y278375D01*
X665649Y278420D01*
X665654Y278460D01*
X665664Y278505D01*
Y278675D01*
X665654Y278720D01*
X665649Y278760D01*
X665639Y278805D01*
X665629Y278845D01*
X665584Y278965D01*
X665544Y279045D01*
X665519Y279080D01*
X665499Y279115D01*
X665469Y279150D01*
X665444Y279185D01*
X665414Y279215D01*
Y281640D01*
X665404Y281765D01*
X665364Y281890D01*
X665304Y282000D01*
X665224Y282100D01*
X665124Y282180D01*
X665014Y282240D01*
X664889Y282280D01*
X664764Y282290D01*
G37*
G36*
G01X669488D02*
X669363Y282280D01*
X669238Y282240D01*
X669128Y282180D01*
X669028Y282100D01*
X668948Y282000D01*
X668888Y281890D01*
X668848Y281765D01*
X668838Y281640D01*
Y279210D01*
X668808Y279180D01*
X668708Y279040D01*
X668688Y279000D01*
X668673Y278965D01*
X668653Y278925D01*
X668638Y278885D01*
X668628Y278845D01*
X668613Y278800D01*
X668608Y278760D01*
X668598Y278720D01*
X668593Y278675D01*
Y278635D01*
X668588Y278590D01*
X668593Y278545D01*
Y278505D01*
X668598Y278460D01*
X668608Y278420D01*
X668613Y278380D01*
X668628Y278335D01*
X668638Y278295D01*
X668653Y278255D01*
X668673Y278215D01*
X668688Y278180D01*
X668708Y278140D01*
X668808Y278000D01*
X668838Y277970D01*
Y275840D01*
X668848Y275715D01*
X668888Y275590D01*
X668948Y275480D01*
X669028Y275380D01*
X669128Y275300D01*
X669238Y275240D01*
X669363Y275200D01*
X669488Y275190D01*
X669613Y275200D01*
X669738Y275240D01*
X669848Y275300D01*
X669948Y275380D01*
X670028Y275480D01*
X670088Y275590D01*
X670128Y275715D01*
X670138Y275840D01*
Y277965D01*
X670168Y277995D01*
X670193Y278030D01*
X670223Y278065D01*
X670243Y278100D01*
X670268Y278135D01*
X670308Y278215D01*
X670353Y278335D01*
X670363Y278375D01*
X670373Y278420D01*
X670378Y278460D01*
X670388Y278505D01*
Y278675D01*
X670378Y278720D01*
X670373Y278760D01*
X670363Y278805D01*
X670353Y278845D01*
X670308Y278965D01*
X670268Y279045D01*
X670243Y279080D01*
X670223Y279115D01*
X670193Y279150D01*
X670168Y279185D01*
X670138Y279215D01*
Y281640D01*
X670128Y281765D01*
X670088Y281890D01*
X670028Y282000D01*
X669948Y282100D01*
X669848Y282180D01*
X669738Y282240D01*
X669613Y282280D01*
X669488Y282290D01*
G37*
G36*
G01X674213D02*
X674088Y282280D01*
X673963Y282240D01*
X673853Y282180D01*
X673753Y282100D01*
X673673Y282000D01*
X673613Y281890D01*
X673573Y281765D01*
X673563Y281640D01*
Y279210D01*
X673533Y279180D01*
X673433Y279040D01*
X673413Y279000D01*
X673398Y278965D01*
X673378Y278925D01*
X673363Y278885D01*
X673353Y278845D01*
X673338Y278800D01*
X673333Y278760D01*
X673323Y278720D01*
X673318Y278675D01*
Y278635D01*
X673313Y278590D01*
X673318Y278545D01*
Y278505D01*
X673323Y278460D01*
X673333Y278420D01*
X673338Y278380D01*
X673353Y278335D01*
X673363Y278295D01*
X673378Y278255D01*
X673398Y278215D01*
X673413Y278180D01*
X673433Y278140D01*
X673533Y278000D01*
X673563Y277970D01*
Y275840D01*
X673573Y275715D01*
X673613Y275590D01*
X673673Y275480D01*
X673753Y275380D01*
X673853Y275300D01*
X673963Y275240D01*
X674088Y275200D01*
X674213Y275190D01*
X674338Y275200D01*
X674463Y275240D01*
X674573Y275300D01*
X674673Y275380D01*
X674753Y275480D01*
X674813Y275590D01*
X674853Y275715D01*
X674863Y275840D01*
Y277965D01*
X674893Y277995D01*
X674918Y278030D01*
X674948Y278065D01*
X674968Y278100D01*
X674993Y278135D01*
X675033Y278215D01*
X675078Y278335D01*
X675088Y278375D01*
X675098Y278420D01*
X675103Y278460D01*
X675113Y278505D01*
Y278675D01*
X675103Y278720D01*
X675098Y278760D01*
X675088Y278805D01*
X675078Y278845D01*
X675033Y278965D01*
X674993Y279045D01*
X674968Y279080D01*
X674948Y279115D01*
X674918Y279150D01*
X674893Y279185D01*
X674863Y279215D01*
Y281640D01*
X674853Y281765D01*
X674813Y281890D01*
X674753Y282000D01*
X674673Y282100D01*
X674573Y282180D01*
X674463Y282240D01*
X674338Y282280D01*
X674213Y282290D01*
G37*
G36*
G01X678937D02*
X678812Y282280D01*
X678687Y282240D01*
X678577Y282180D01*
X678477Y282100D01*
X678397Y282000D01*
X678337Y281890D01*
X678297Y281765D01*
X678287Y281640D01*
Y279210D01*
X678257Y279180D01*
X678157Y279040D01*
X678137Y279000D01*
X678122Y278965D01*
X678102Y278925D01*
X678087Y278885D01*
X678077Y278845D01*
X678062Y278800D01*
X678057Y278760D01*
X678047Y278720D01*
X678042Y278675D01*
Y278635D01*
X678037Y278590D01*
X678042Y278545D01*
Y278505D01*
X678047Y278460D01*
X678057Y278420D01*
X678062Y278380D01*
X678077Y278335D01*
X678087Y278295D01*
X678102Y278255D01*
X678122Y278215D01*
X678137Y278180D01*
X678157Y278140D01*
X678257Y278000D01*
X678287Y277970D01*
Y275840D01*
X678297Y275715D01*
X678337Y275590D01*
X678397Y275480D01*
X678477Y275380D01*
X678577Y275300D01*
X678687Y275240D01*
X678812Y275200D01*
X678937Y275190D01*
X679062Y275200D01*
X679187Y275240D01*
X679297Y275300D01*
X679397Y275380D01*
X679477Y275480D01*
X679537Y275590D01*
X679577Y275715D01*
X679587Y275840D01*
Y277965D01*
X679617Y277995D01*
X679642Y278030D01*
X679672Y278065D01*
X679692Y278100D01*
X679717Y278135D01*
X679757Y278215D01*
X679802Y278335D01*
X679812Y278375D01*
X679822Y278420D01*
X679827Y278460D01*
X679837Y278505D01*
Y278675D01*
X679827Y278720D01*
X679822Y278760D01*
X679812Y278805D01*
X679802Y278845D01*
X679757Y278965D01*
X679717Y279045D01*
X679692Y279080D01*
X679672Y279115D01*
X679642Y279150D01*
X679617Y279185D01*
X679587Y279215D01*
Y281640D01*
X679577Y281765D01*
X679537Y281890D01*
X679477Y282000D01*
X679397Y282100D01*
X679297Y282180D01*
X679187Y282240D01*
X679062Y282280D01*
X678937Y282290D01*
G37*
G36*
G01X683662D02*
X683537Y282280D01*
X683412Y282240D01*
X683302Y282180D01*
X683202Y282100D01*
X683122Y282000D01*
X683062Y281890D01*
X683022Y281765D01*
X683012Y281640D01*
Y279210D01*
X682982Y279180D01*
X682882Y279040D01*
X682862Y279000D01*
X682847Y278965D01*
X682827Y278925D01*
X682812Y278885D01*
X682802Y278845D01*
X682787Y278800D01*
X682782Y278760D01*
X682772Y278720D01*
X682767Y278675D01*
Y278635D01*
X682762Y278590D01*
X682767Y278545D01*
Y278505D01*
X682772Y278460D01*
X682782Y278420D01*
X682787Y278380D01*
X682802Y278335D01*
X682812Y278295D01*
X682827Y278255D01*
X682847Y278215D01*
X682862Y278180D01*
X682882Y278140D01*
X682982Y278000D01*
X683012Y277970D01*
Y275840D01*
X683022Y275715D01*
X683062Y275590D01*
X683122Y275480D01*
X683202Y275380D01*
X683302Y275300D01*
X683412Y275240D01*
X683537Y275200D01*
X683662Y275190D01*
X683787Y275200D01*
X683912Y275240D01*
X684022Y275300D01*
X684122Y275380D01*
X684202Y275480D01*
X684262Y275590D01*
X684302Y275715D01*
X684312Y275840D01*
Y277965D01*
X684342Y277995D01*
X684367Y278030D01*
X684397Y278065D01*
X684417Y278100D01*
X684442Y278135D01*
X684482Y278215D01*
X684527Y278335D01*
X684537Y278375D01*
X684547Y278420D01*
X684552Y278460D01*
X684562Y278505D01*
Y278675D01*
X684552Y278720D01*
X684547Y278760D01*
X684537Y278805D01*
X684527Y278845D01*
X684482Y278965D01*
X684442Y279045D01*
X684417Y279080D01*
X684397Y279115D01*
X684367Y279150D01*
X684342Y279185D01*
X684312Y279215D01*
Y281640D01*
X684302Y281765D01*
X684262Y281890D01*
X684202Y282000D01*
X684122Y282100D01*
X684022Y282180D01*
X683912Y282240D01*
X683787Y282280D01*
X683662Y282290D01*
G37*
G36*
G01X688386D02*
X688261Y282280D01*
X688136Y282240D01*
X688026Y282180D01*
X687926Y282100D01*
X687846Y282000D01*
X687786Y281890D01*
X687746Y281765D01*
X687736Y281640D01*
Y279210D01*
X687706Y279180D01*
X687606Y279040D01*
X687586Y279000D01*
X687571Y278965D01*
X687551Y278925D01*
X687536Y278885D01*
X687526Y278845D01*
X687511Y278800D01*
X687506Y278760D01*
X687496Y278720D01*
X687491Y278675D01*
Y278635D01*
X687486Y278590D01*
X687491Y278545D01*
Y278505D01*
X687496Y278460D01*
X687506Y278420D01*
X687511Y278380D01*
X687526Y278335D01*
X687536Y278295D01*
X687551Y278255D01*
X687571Y278215D01*
X687586Y278180D01*
X687606Y278140D01*
X687706Y278000D01*
X687736Y277970D01*
Y275840D01*
X687746Y275715D01*
X687786Y275590D01*
X687846Y275480D01*
X687926Y275380D01*
X688026Y275300D01*
X688136Y275240D01*
X688261Y275200D01*
X688386Y275190D01*
X688511Y275200D01*
X688636Y275240D01*
X688746Y275300D01*
X688846Y275380D01*
X688926Y275480D01*
X688986Y275590D01*
X689026Y275715D01*
X689036Y275840D01*
Y277965D01*
X689066Y277995D01*
X689091Y278030D01*
X689121Y278065D01*
X689141Y278100D01*
X689166Y278135D01*
X689206Y278215D01*
X689251Y278335D01*
X689261Y278375D01*
X689271Y278420D01*
X689276Y278460D01*
X689286Y278505D01*
Y278675D01*
X689276Y278720D01*
X689271Y278760D01*
X689261Y278805D01*
X689251Y278845D01*
X689206Y278965D01*
X689166Y279045D01*
X689141Y279080D01*
X689121Y279115D01*
X689091Y279150D01*
X689066Y279185D01*
X689036Y279215D01*
Y281640D01*
X689026Y281765D01*
X688986Y281890D01*
X688926Y282000D01*
X688846Y282100D01*
X688746Y282180D01*
X688636Y282240D01*
X688511Y282280D01*
X688386Y282290D01*
G37*
G36*
G01X693110D02*
X692985Y282280D01*
X692860Y282240D01*
X692750Y282180D01*
X692650Y282100D01*
X692570Y282000D01*
X692510Y281890D01*
X692470Y281765D01*
X692460Y281640D01*
Y279210D01*
X692430Y279180D01*
X692330Y279040D01*
X692310Y279000D01*
X692295Y278965D01*
X692275Y278925D01*
X692260Y278885D01*
X692250Y278845D01*
X692235Y278800D01*
X692230Y278760D01*
X692220Y278720D01*
X692215Y278675D01*
Y278635D01*
X692210Y278590D01*
X692215Y278545D01*
Y278505D01*
X692220Y278460D01*
X692230Y278420D01*
X692235Y278380D01*
X692250Y278335D01*
X692260Y278295D01*
X692275Y278255D01*
X692295Y278215D01*
X692310Y278180D01*
X692330Y278140D01*
X692430Y278000D01*
X692460Y277970D01*
Y275840D01*
X692470Y275715D01*
X692510Y275590D01*
X692570Y275480D01*
X692650Y275380D01*
X692750Y275300D01*
X692860Y275240D01*
X692985Y275200D01*
X693110Y275190D01*
X693235Y275200D01*
X693360Y275240D01*
X693470Y275300D01*
X693570Y275380D01*
X693650Y275480D01*
X693710Y275590D01*
X693750Y275715D01*
X693760Y275840D01*
Y277965D01*
X693790Y277995D01*
X693815Y278030D01*
X693845Y278065D01*
X693865Y278100D01*
X693890Y278135D01*
X693930Y278215D01*
X693975Y278335D01*
X693985Y278375D01*
X693995Y278420D01*
X694000Y278460D01*
X694010Y278505D01*
Y278675D01*
X694000Y278720D01*
X693995Y278760D01*
X693985Y278805D01*
X693975Y278845D01*
X693930Y278965D01*
X693890Y279045D01*
X693865Y279080D01*
X693845Y279115D01*
X693815Y279150D01*
X693790Y279185D01*
X693760Y279215D01*
Y281640D01*
X693750Y281765D01*
X693710Y281890D01*
X693650Y282000D01*
X693570Y282100D01*
X693470Y282180D01*
X693360Y282240D01*
X693235Y282280D01*
X693110Y282290D01*
G37*
G36*
G01X697835D02*
X697710Y282280D01*
X697585Y282240D01*
X697475Y282180D01*
X697375Y282100D01*
X697295Y282000D01*
X697235Y281890D01*
X697195Y281765D01*
X697185Y281640D01*
Y279210D01*
X697155Y279180D01*
X697055Y279040D01*
X697035Y279000D01*
X697020Y278965D01*
X697000Y278925D01*
X696985Y278885D01*
X696975Y278845D01*
X696960Y278800D01*
X696955Y278760D01*
X696945Y278720D01*
X696940Y278675D01*
Y278635D01*
X696935Y278590D01*
X696940Y278545D01*
Y278505D01*
X696945Y278460D01*
X696955Y278420D01*
X696960Y278380D01*
X696975Y278335D01*
X696985Y278295D01*
X697000Y278255D01*
X697020Y278215D01*
X697035Y278180D01*
X697055Y278140D01*
X697155Y278000D01*
X697185Y277970D01*
Y275840D01*
X697195Y275715D01*
X697235Y275590D01*
X697295Y275480D01*
X697375Y275380D01*
X697475Y275300D01*
X697585Y275240D01*
X697710Y275200D01*
X697835Y275190D01*
X697960Y275200D01*
X698085Y275240D01*
X698195Y275300D01*
X698295Y275380D01*
X698375Y275480D01*
X698435Y275590D01*
X698475Y275715D01*
X698485Y275840D01*
Y277965D01*
X698515Y277995D01*
X698540Y278030D01*
X698570Y278065D01*
X698590Y278100D01*
X698615Y278135D01*
X698655Y278215D01*
X698700Y278335D01*
X698710Y278375D01*
X698720Y278420D01*
X698725Y278460D01*
X698735Y278505D01*
Y278675D01*
X698725Y278720D01*
X698720Y278760D01*
X698710Y278805D01*
X698700Y278845D01*
X698655Y278965D01*
X698615Y279045D01*
X698590Y279080D01*
X698570Y279115D01*
X698540Y279150D01*
X698515Y279185D01*
X698485Y279215D01*
Y281640D01*
X698475Y281765D01*
X698435Y281890D01*
X698375Y282000D01*
X698295Y282100D01*
X698195Y282180D01*
X698085Y282240D01*
X697960Y282280D01*
X697835Y282290D01*
G37*
G36*
G01X702559D02*
X702434Y282280D01*
X702309Y282240D01*
X702199Y282180D01*
X702099Y282100D01*
X702019Y282000D01*
X701959Y281890D01*
X701919Y281765D01*
X701909Y281640D01*
Y279210D01*
X701879Y279180D01*
X701779Y279040D01*
X701759Y279000D01*
X701744Y278965D01*
X701724Y278925D01*
X701709Y278885D01*
X701699Y278845D01*
X701684Y278800D01*
X701679Y278760D01*
X701669Y278720D01*
X701664Y278675D01*
Y278635D01*
X701659Y278590D01*
X701664Y278545D01*
Y278505D01*
X701669Y278460D01*
X701679Y278420D01*
X701684Y278380D01*
X701699Y278335D01*
X701709Y278295D01*
X701724Y278255D01*
X701744Y278215D01*
X701759Y278180D01*
X701779Y278140D01*
X701879Y278000D01*
X701909Y277970D01*
Y275840D01*
X701919Y275715D01*
X701959Y275590D01*
X702019Y275480D01*
X702099Y275380D01*
X702199Y275300D01*
X702309Y275240D01*
X702434Y275200D01*
X702559Y275190D01*
X702684Y275200D01*
X702809Y275240D01*
X702919Y275300D01*
X703019Y275380D01*
X703099Y275480D01*
X703159Y275590D01*
X703199Y275715D01*
X703209Y275840D01*
Y277965D01*
X703239Y277995D01*
X703264Y278030D01*
X703294Y278065D01*
X703314Y278100D01*
X703339Y278135D01*
X703379Y278215D01*
X703424Y278335D01*
X703434Y278375D01*
X703444Y278420D01*
X703449Y278460D01*
X703459Y278505D01*
Y278675D01*
X703449Y278720D01*
X703444Y278760D01*
X703434Y278805D01*
X703424Y278845D01*
X703379Y278965D01*
X703339Y279045D01*
X703314Y279080D01*
X703294Y279115D01*
X703264Y279150D01*
X703239Y279185D01*
X703209Y279215D01*
Y281640D01*
X703199Y281765D01*
X703159Y281890D01*
X703099Y282000D01*
X703019Y282100D01*
X702919Y282180D01*
X702809Y282240D01*
X702684Y282280D01*
X702559Y282290D01*
G37*
G36*
G01X707284D02*
X707159Y282280D01*
X707034Y282240D01*
X706924Y282180D01*
X706824Y282100D01*
X706744Y282000D01*
X706684Y281890D01*
X706644Y281765D01*
X706634Y281640D01*
Y279210D01*
X706604Y279180D01*
X706504Y279040D01*
X706484Y279000D01*
X706469Y278965D01*
X706449Y278925D01*
X706434Y278885D01*
X706424Y278845D01*
X706409Y278800D01*
X706404Y278760D01*
X706394Y278720D01*
X706389Y278675D01*
Y278635D01*
X706384Y278590D01*
X706389Y278545D01*
Y278505D01*
X706394Y278460D01*
X706404Y278420D01*
X706409Y278380D01*
X706424Y278335D01*
X706434Y278295D01*
X706449Y278255D01*
X706469Y278215D01*
X706484Y278180D01*
X706504Y278140D01*
X706604Y278000D01*
X706634Y277970D01*
Y275840D01*
X706644Y275715D01*
X706684Y275590D01*
X706744Y275480D01*
X706824Y275380D01*
X706924Y275300D01*
X707034Y275240D01*
X707159Y275200D01*
X707284Y275190D01*
X707409Y275200D01*
X707534Y275240D01*
X707644Y275300D01*
X707744Y275380D01*
X707824Y275480D01*
X707884Y275590D01*
X707924Y275715D01*
X707934Y275840D01*
Y277965D01*
X707964Y277995D01*
X707989Y278030D01*
X708019Y278065D01*
X708039Y278100D01*
X708064Y278135D01*
X708104Y278215D01*
X708149Y278335D01*
X708159Y278375D01*
X708169Y278420D01*
X708174Y278460D01*
X708184Y278505D01*
Y278675D01*
X708174Y278720D01*
X708169Y278760D01*
X708159Y278805D01*
X708149Y278845D01*
X708104Y278965D01*
X708064Y279045D01*
X708039Y279080D01*
X708019Y279115D01*
X707989Y279150D01*
X707964Y279185D01*
X707934Y279215D01*
Y281640D01*
X707924Y281765D01*
X707884Y281890D01*
X707824Y282000D01*
X707744Y282100D01*
X707644Y282180D01*
X707534Y282240D01*
X707409Y282280D01*
X707284Y282290D01*
G37*
G36*
G01X712008D02*
X711883Y282280D01*
X711758Y282240D01*
X711648Y282180D01*
X711548Y282100D01*
X711468Y282000D01*
X711408Y281890D01*
X711368Y281765D01*
X711358Y281640D01*
Y279210D01*
X711328Y279180D01*
X711228Y279040D01*
X711208Y279000D01*
X711193Y278965D01*
X711173Y278925D01*
X711158Y278885D01*
X711148Y278845D01*
X711133Y278800D01*
X711128Y278760D01*
X711118Y278720D01*
X711113Y278675D01*
Y278635D01*
X711108Y278590D01*
X711113Y278545D01*
Y278505D01*
X711118Y278460D01*
X711128Y278420D01*
X711133Y278380D01*
X711148Y278335D01*
X711158Y278295D01*
X711173Y278255D01*
X711193Y278215D01*
X711208Y278180D01*
X711228Y278140D01*
X711328Y278000D01*
X711358Y277970D01*
Y275840D01*
X711368Y275715D01*
X711408Y275590D01*
X711468Y275480D01*
X711548Y275380D01*
X711648Y275300D01*
X711758Y275240D01*
X711883Y275200D01*
X712008Y275190D01*
X712133Y275200D01*
X712258Y275240D01*
X712368Y275300D01*
X712468Y275380D01*
X712548Y275480D01*
X712608Y275590D01*
X712648Y275715D01*
X712658Y275840D01*
Y277965D01*
X712688Y277995D01*
X712713Y278030D01*
X712743Y278065D01*
X712763Y278100D01*
X712788Y278135D01*
X712828Y278215D01*
X712873Y278335D01*
X712883Y278375D01*
X712893Y278420D01*
X712898Y278460D01*
X712908Y278505D01*
Y278675D01*
X712898Y278720D01*
X712893Y278760D01*
X712883Y278805D01*
X712873Y278845D01*
X712828Y278965D01*
X712788Y279045D01*
X712763Y279080D01*
X712743Y279115D01*
X712713Y279150D01*
X712688Y279185D01*
X712658Y279215D01*
Y281640D01*
X712648Y281765D01*
X712608Y281890D01*
X712548Y282000D01*
X712468Y282100D01*
X712368Y282180D01*
X712258Y282240D01*
X712133Y282280D01*
X712008Y282290D01*
G37*
G36*
G01X716733D02*
X716608Y282280D01*
X716483Y282240D01*
X716373Y282180D01*
X716273Y282100D01*
X716193Y282000D01*
X716133Y281890D01*
X716093Y281765D01*
X716083Y281640D01*
Y279210D01*
X716053Y279180D01*
X715953Y279040D01*
X715933Y279000D01*
X715918Y278965D01*
X715898Y278925D01*
X715883Y278885D01*
X715873Y278845D01*
X715858Y278800D01*
X715853Y278760D01*
X715843Y278720D01*
X715838Y278675D01*
Y278635D01*
X715833Y278590D01*
X715838Y278545D01*
Y278505D01*
X715843Y278460D01*
X715853Y278420D01*
X715858Y278380D01*
X715873Y278335D01*
X715883Y278295D01*
X715898Y278255D01*
X715918Y278215D01*
X715933Y278180D01*
X715953Y278140D01*
X716053Y278000D01*
X716083Y277970D01*
Y275840D01*
X716093Y275715D01*
X716133Y275590D01*
X716193Y275480D01*
X716273Y275380D01*
X716373Y275300D01*
X716483Y275240D01*
X716608Y275200D01*
X716733Y275190D01*
X716858Y275200D01*
X716983Y275240D01*
X717093Y275300D01*
X717193Y275380D01*
X717273Y275480D01*
X717333Y275590D01*
X717373Y275715D01*
X717383Y275840D01*
Y277965D01*
X717413Y277995D01*
X717438Y278030D01*
X717468Y278065D01*
X717488Y278100D01*
X717513Y278135D01*
X717553Y278215D01*
X717598Y278335D01*
X717608Y278375D01*
X717618Y278420D01*
X717623Y278460D01*
X717633Y278505D01*
Y278675D01*
X717623Y278720D01*
X717618Y278760D01*
X717608Y278805D01*
X717598Y278845D01*
X717553Y278965D01*
X717513Y279045D01*
X717488Y279080D01*
X717468Y279115D01*
X717438Y279150D01*
X717413Y279185D01*
X717383Y279215D01*
Y281640D01*
X717373Y281765D01*
X717333Y281890D01*
X717273Y282000D01*
X717193Y282100D01*
X717093Y282180D01*
X716983Y282240D01*
X716858Y282280D01*
X716733Y282290D01*
G37*
G36*
G01X721457D02*
X721332Y282280D01*
X721207Y282240D01*
X721097Y282180D01*
X720997Y282100D01*
X720917Y282000D01*
X720857Y281890D01*
X720817Y281765D01*
X720807Y281640D01*
Y279210D01*
X720777Y279180D01*
X720677Y279040D01*
X720657Y279000D01*
X720642Y278965D01*
X720622Y278925D01*
X720607Y278885D01*
X720597Y278845D01*
X720582Y278800D01*
X720577Y278760D01*
X720567Y278720D01*
X720562Y278675D01*
Y278635D01*
X720557Y278590D01*
X720562Y278545D01*
Y278505D01*
X720567Y278460D01*
X720577Y278420D01*
X720582Y278380D01*
X720597Y278335D01*
X720607Y278295D01*
X720622Y278255D01*
X720642Y278215D01*
X720657Y278180D01*
X720677Y278140D01*
X720777Y278000D01*
X720807Y277970D01*
Y275840D01*
X720817Y275715D01*
X720857Y275590D01*
X720917Y275480D01*
X720997Y275380D01*
X721097Y275300D01*
X721207Y275240D01*
X721332Y275200D01*
X721457Y275190D01*
X721582Y275200D01*
X721707Y275240D01*
X721817Y275300D01*
X721917Y275380D01*
X721997Y275480D01*
X722057Y275590D01*
X722097Y275715D01*
X722107Y275840D01*
Y277965D01*
X722137Y277995D01*
X722162Y278030D01*
X722192Y278065D01*
X722212Y278100D01*
X722237Y278135D01*
X722277Y278215D01*
X722322Y278335D01*
X722332Y278375D01*
X722342Y278420D01*
X722347Y278460D01*
X722357Y278505D01*
Y278675D01*
X722347Y278720D01*
X722342Y278760D01*
X722332Y278805D01*
X722322Y278845D01*
X722277Y278965D01*
X722237Y279045D01*
X722212Y279080D01*
X722192Y279115D01*
X722162Y279150D01*
X722137Y279185D01*
X722107Y279215D01*
Y281640D01*
X722097Y281765D01*
X722057Y281890D01*
X721997Y282000D01*
X721917Y282100D01*
X721817Y282180D01*
X721707Y282240D01*
X721582Y282280D01*
X721457Y282290D01*
G37*
G36*
G01X726181D02*
X726056Y282280D01*
X725931Y282240D01*
X725821Y282180D01*
X725721Y282100D01*
X725641Y282000D01*
X725581Y281890D01*
X725541Y281765D01*
X725531Y281640D01*
Y279210D01*
X725501Y279180D01*
X725401Y279040D01*
X725381Y279000D01*
X725366Y278965D01*
X725346Y278925D01*
X725331Y278885D01*
X725321Y278845D01*
X725306Y278800D01*
X725301Y278760D01*
X725291Y278720D01*
X725286Y278675D01*
Y278635D01*
X725281Y278590D01*
X725286Y278545D01*
Y278505D01*
X725291Y278460D01*
X725301Y278420D01*
X725306Y278380D01*
X725321Y278335D01*
X725331Y278295D01*
X725346Y278255D01*
X725366Y278215D01*
X725381Y278180D01*
X725401Y278140D01*
X725501Y278000D01*
X725531Y277970D01*
Y275840D01*
X725541Y275715D01*
X725581Y275590D01*
X725641Y275480D01*
X725721Y275380D01*
X725821Y275300D01*
X725931Y275240D01*
X726056Y275200D01*
X726181Y275190D01*
X726306Y275200D01*
X726431Y275240D01*
X726541Y275300D01*
X726641Y275380D01*
X726721Y275480D01*
X726781Y275590D01*
X726821Y275715D01*
X726831Y275840D01*
Y277965D01*
X726861Y277995D01*
X726886Y278030D01*
X726916Y278065D01*
X726936Y278100D01*
X726961Y278135D01*
X727001Y278215D01*
X727046Y278335D01*
X727056Y278375D01*
X727066Y278420D01*
X727071Y278460D01*
X727081Y278505D01*
Y278675D01*
X727071Y278720D01*
X727066Y278760D01*
X727056Y278805D01*
X727046Y278845D01*
X727001Y278965D01*
X726961Y279045D01*
X726936Y279080D01*
X726916Y279115D01*
X726886Y279150D01*
X726861Y279185D01*
X726831Y279215D01*
Y281640D01*
X726821Y281765D01*
X726781Y281890D01*
X726721Y282000D01*
X726641Y282100D01*
X726541Y282180D01*
X726431Y282240D01*
X726306Y282280D01*
X726181Y282290D01*
G37*
G36*
G01X730906D02*
X730781Y282280D01*
X730656Y282240D01*
X730546Y282180D01*
X730446Y282100D01*
X730366Y282000D01*
X730306Y281890D01*
X730266Y281765D01*
X730256Y281640D01*
Y279210D01*
X730226Y279180D01*
X730126Y279040D01*
X730106Y279000D01*
X730091Y278965D01*
X730071Y278925D01*
X730056Y278885D01*
X730046Y278845D01*
X730031Y278800D01*
X730026Y278760D01*
X730016Y278720D01*
X730011Y278675D01*
Y278635D01*
X730006Y278590D01*
X730011Y278545D01*
Y278505D01*
X730016Y278460D01*
X730026Y278420D01*
X730031Y278380D01*
X730046Y278335D01*
X730056Y278295D01*
X730071Y278255D01*
X730091Y278215D01*
X730106Y278180D01*
X730126Y278140D01*
X730226Y278000D01*
X730256Y277970D01*
Y275840D01*
X730266Y275715D01*
X730306Y275590D01*
X730366Y275480D01*
X730446Y275380D01*
X730546Y275300D01*
X730656Y275240D01*
X730781Y275200D01*
X730906Y275190D01*
X731031Y275200D01*
X731156Y275240D01*
X731266Y275300D01*
X731366Y275380D01*
X731446Y275480D01*
X731506Y275590D01*
X731546Y275715D01*
X731556Y275840D01*
Y277965D01*
X731586Y277995D01*
X731611Y278030D01*
X731641Y278065D01*
X731661Y278100D01*
X731686Y278135D01*
X731726Y278215D01*
X731771Y278335D01*
X731781Y278375D01*
X731791Y278420D01*
X731796Y278460D01*
X731806Y278505D01*
Y278675D01*
X731796Y278720D01*
X731791Y278760D01*
X731781Y278805D01*
X731771Y278845D01*
X731726Y278965D01*
X731686Y279045D01*
X731661Y279080D01*
X731641Y279115D01*
X731611Y279150D01*
X731586Y279185D01*
X731556Y279215D01*
Y281640D01*
X731546Y281765D01*
X731506Y281890D01*
X731446Y282000D01*
X731366Y282100D01*
X731266Y282180D01*
X731156Y282240D01*
X731031Y282280D01*
X730906Y282290D01*
G37*
G36*
G01X735630D02*
X735505Y282280D01*
X735380Y282240D01*
X735270Y282180D01*
X735170Y282100D01*
X735090Y282000D01*
X735030Y281890D01*
X734990Y281765D01*
X734980Y281640D01*
Y279210D01*
X734950Y279180D01*
X734850Y279040D01*
X734830Y279000D01*
X734815Y278965D01*
X734795Y278925D01*
X734780Y278885D01*
X734770Y278845D01*
X734755Y278800D01*
X734750Y278760D01*
X734740Y278720D01*
X734735Y278675D01*
Y278635D01*
X734730Y278590D01*
X734735Y278545D01*
Y278505D01*
X734740Y278460D01*
X734750Y278420D01*
X734755Y278380D01*
X734770Y278335D01*
X734780Y278295D01*
X734795Y278255D01*
X734815Y278215D01*
X734830Y278180D01*
X734850Y278140D01*
X734950Y278000D01*
X734980Y277970D01*
Y275840D01*
X734990Y275715D01*
X735030Y275590D01*
X735090Y275480D01*
X735170Y275380D01*
X735270Y275300D01*
X735380Y275240D01*
X735505Y275200D01*
X735630Y275190D01*
X735755Y275200D01*
X735880Y275240D01*
X735990Y275300D01*
X736090Y275380D01*
X736170Y275480D01*
X736230Y275590D01*
X736270Y275715D01*
X736280Y275840D01*
Y277965D01*
X736310Y277995D01*
X736335Y278030D01*
X736365Y278065D01*
X736385Y278100D01*
X736410Y278135D01*
X736450Y278215D01*
X736495Y278335D01*
X736505Y278375D01*
X736515Y278420D01*
X736520Y278460D01*
X736530Y278505D01*
Y278675D01*
X736520Y278720D01*
X736515Y278760D01*
X736505Y278805D01*
X736495Y278845D01*
X736450Y278965D01*
X736410Y279045D01*
X736385Y279080D01*
X736365Y279115D01*
X736335Y279150D01*
X736310Y279185D01*
X736280Y279215D01*
Y281640D01*
X736270Y281765D01*
X736230Y281890D01*
X736170Y282000D01*
X736090Y282100D01*
X735990Y282180D01*
X735880Y282240D01*
X735755Y282280D01*
X735630Y282290D01*
G37*
G36*
G01X740355D02*
X740230Y282280D01*
X740105Y282240D01*
X739995Y282180D01*
X739895Y282100D01*
X739815Y282000D01*
X739755Y281890D01*
X739715Y281765D01*
X739705Y281640D01*
Y279210D01*
X739675Y279180D01*
X739575Y279040D01*
X739555Y279000D01*
X739540Y278965D01*
X739520Y278925D01*
X739505Y278885D01*
X739495Y278845D01*
X739480Y278800D01*
X739475Y278760D01*
X739465Y278720D01*
X739460Y278675D01*
Y278635D01*
X739455Y278590D01*
X739460Y278545D01*
Y278505D01*
X739465Y278460D01*
X739475Y278420D01*
X739480Y278380D01*
X739495Y278335D01*
X739505Y278295D01*
X739520Y278255D01*
X739540Y278215D01*
X739555Y278180D01*
X739575Y278140D01*
X739675Y278000D01*
X739705Y277970D01*
Y275840D01*
X739715Y275715D01*
X739755Y275590D01*
X739815Y275480D01*
X739895Y275380D01*
X739995Y275300D01*
X740105Y275240D01*
X740230Y275200D01*
X740355Y275190D01*
X740480Y275200D01*
X740605Y275240D01*
X740715Y275300D01*
X740815Y275380D01*
X740895Y275480D01*
X740955Y275590D01*
X740995Y275715D01*
X741005Y275840D01*
Y277965D01*
X741035Y277995D01*
X741060Y278030D01*
X741090Y278065D01*
X741110Y278100D01*
X741135Y278135D01*
X741175Y278215D01*
X741220Y278335D01*
X741230Y278375D01*
X741240Y278420D01*
X741245Y278460D01*
X741255Y278505D01*
Y278675D01*
X741245Y278720D01*
X741240Y278760D01*
X741230Y278805D01*
X741220Y278845D01*
X741175Y278965D01*
X741135Y279045D01*
X741110Y279080D01*
X741090Y279115D01*
X741060Y279150D01*
X741035Y279185D01*
X741005Y279215D01*
Y281640D01*
X740995Y281765D01*
X740955Y281890D01*
X740895Y282000D01*
X740815Y282100D01*
X740715Y282180D01*
X740605Y282240D01*
X740480Y282280D01*
X740355Y282290D01*
G37*
G36*
G01X745079D02*
X744954Y282280D01*
X744829Y282240D01*
X744719Y282180D01*
X744619Y282100D01*
X744539Y282000D01*
X744479Y281890D01*
X744439Y281765D01*
X744429Y281640D01*
Y279210D01*
X744399Y279180D01*
X744299Y279040D01*
X744279Y279000D01*
X744264Y278965D01*
X744244Y278925D01*
X744229Y278885D01*
X744219Y278845D01*
X744204Y278800D01*
X744199Y278760D01*
X744189Y278720D01*
X744184Y278675D01*
Y278635D01*
X744179Y278590D01*
X744184Y278545D01*
Y278505D01*
X744189Y278460D01*
X744199Y278420D01*
X744204Y278380D01*
X744219Y278335D01*
X744229Y278295D01*
X744244Y278255D01*
X744264Y278215D01*
X744279Y278180D01*
X744299Y278140D01*
X744399Y278000D01*
X744429Y277970D01*
Y275840D01*
X744439Y275715D01*
X744479Y275590D01*
X744539Y275480D01*
X744619Y275380D01*
X744719Y275300D01*
X744829Y275240D01*
X744954Y275200D01*
X745079Y275190D01*
X745204Y275200D01*
X745329Y275240D01*
X745439Y275300D01*
X745539Y275380D01*
X745619Y275480D01*
X745679Y275590D01*
X745719Y275715D01*
X745729Y275840D01*
Y277965D01*
X745759Y277995D01*
X745784Y278030D01*
X745814Y278065D01*
X745834Y278100D01*
X745859Y278135D01*
X745899Y278215D01*
X745944Y278335D01*
X745954Y278375D01*
X745964Y278420D01*
X745969Y278460D01*
X745979Y278505D01*
Y278675D01*
X745969Y278720D01*
X745964Y278760D01*
X745954Y278805D01*
X745944Y278845D01*
X745899Y278965D01*
X745859Y279045D01*
X745834Y279080D01*
X745814Y279115D01*
X745784Y279150D01*
X745759Y279185D01*
X745729Y279215D01*
Y281640D01*
X745719Y281765D01*
X745679Y281890D01*
X745619Y282000D01*
X745539Y282100D01*
X745439Y282180D01*
X745329Y282240D01*
X745204Y282280D01*
X745079Y282290D01*
G37*
G54D27*
X42717Y191732D03*
G54D36*
X69000Y225700D03*
X74000D03*
X69000Y230900D03*
X74000D03*
X156100Y181900D03*
Y187100D03*
X185000Y163400D03*
X174000Y163900D03*
X185000Y168600D03*
X174000Y169100D03*
X297000Y208600D03*
Y203400D03*
X326500Y244900D03*
Y250100D03*
X371500Y208100D03*
Y202900D03*
X414000Y72900D03*
Y78100D03*
X507000Y224600D03*
Y219400D03*
X596000Y236100D03*
Y230900D03*
X606000Y236100D03*
Y230900D03*
X628000Y236100D03*
Y230900D03*
X694000Y163900D03*
Y169100D03*
X742000Y67100D03*
Y61900D03*
X740000Y238600D03*
Y233400D03*
G54D82*
X482480Y70042D03*
X476575Y215354D03*
X777362Y70042D03*
X771457Y215354D03*
G54D55*
X219502Y78346D03*
Y81496D03*
Y84646D03*
Y87795D03*
Y90945D03*
Y94094D03*
Y97244D03*
Y100394D03*
Y103543D03*
Y106693D03*
Y109842D03*
Y112992D03*
Y116142D03*
Y119291D03*
Y122441D03*
Y125590D03*
Y128740D03*
Y131890D03*
Y147638D03*
Y150787D03*
Y153937D03*
Y157086D03*
Y160236D03*
Y163386D03*
Y166535D03*
Y169685D03*
X251758Y79921D03*
Y83071D03*
Y86220D03*
Y89370D03*
Y92520D03*
Y95669D03*
Y98819D03*
Y101968D03*
Y105118D03*
Y108268D03*
Y111417D03*
Y114567D03*
Y117716D03*
Y120866D03*
Y124016D03*
Y127165D03*
Y130315D03*
Y133464D03*
Y149212D03*
Y152362D03*
Y155512D03*
Y158661D03*
Y161811D03*
Y164960D03*
Y168110D03*
Y171260D03*
G54D73*
X372376Y246689D03*
Y270311D03*
X387624Y246689D03*
Y270311D03*
G36*
G01X501772Y282290D02*
X501647Y282280D01*
X501522Y282240D01*
X501412Y282180D01*
X501312Y282100D01*
X501232Y282000D01*
X501172Y281890D01*
X501132Y281765D01*
X501122Y281640D01*
Y278210D01*
X501092Y278180D01*
X500992Y278040D01*
X500972Y278000D01*
X500957Y277965D01*
X500937Y277925D01*
X500922Y277885D01*
X500912Y277845D01*
X500897Y277800D01*
X500892Y277760D01*
X500882Y277720D01*
X500877Y277675D01*
Y277635D01*
X500872Y277590D01*
X500877Y277545D01*
Y277505D01*
X500882Y277460D01*
X500892Y277420D01*
X500897Y277380D01*
X500912Y277335D01*
X500922Y277295D01*
X500937Y277255D01*
X500957Y277215D01*
X500972Y277180D01*
X500992Y277140D01*
X501092Y277000D01*
X501122Y276970D01*
Y275840D01*
X501132Y275715D01*
X501172Y275590D01*
X501232Y275480D01*
X501312Y275380D01*
X501412Y275300D01*
X501522Y275240D01*
X501647Y275200D01*
X501772Y275190D01*
X501897Y275200D01*
X502022Y275240D01*
X502132Y275300D01*
X502232Y275380D01*
X502312Y275480D01*
X502372Y275590D01*
X502412Y275715D01*
X502422Y275840D01*
Y276970D01*
X502452Y277000D01*
X502552Y277140D01*
X502572Y277180D01*
X502587Y277215D01*
X502607Y277255D01*
X502622Y277295D01*
X502632Y277335D01*
X502647Y277380D01*
X502652Y277420D01*
X502662Y277460D01*
X502667Y277505D01*
Y277545D01*
X502672Y277590D01*
X502667Y277635D01*
Y277675D01*
X502662Y277720D01*
X502652Y277760D01*
X502647Y277800D01*
X502632Y277845D01*
X502622Y277885D01*
X502607Y277925D01*
X502587Y277965D01*
X502572Y278000D01*
X502552Y278040D01*
X502452Y278180D01*
X502422Y278210D01*
Y281640D01*
X502412Y281765D01*
X502372Y281890D01*
X502312Y282000D01*
X502232Y282100D01*
X502132Y282180D01*
X502022Y282240D01*
X501897Y282280D01*
X501772Y282290D01*
G37*
G36*
G01X506496D02*
X506371Y282280D01*
X506246Y282240D01*
X506136Y282180D01*
X506036Y282100D01*
X505956Y282000D01*
X505896Y281890D01*
X505856Y281765D01*
X505846Y281640D01*
Y278210D01*
X505816Y278180D01*
X505716Y278040D01*
X505696Y278000D01*
X505681Y277965D01*
X505661Y277925D01*
X505646Y277885D01*
X505636Y277845D01*
X505621Y277800D01*
X505616Y277760D01*
X505606Y277720D01*
X505601Y277675D01*
Y277635D01*
X505596Y277590D01*
X505601Y277545D01*
Y277505D01*
X505606Y277460D01*
X505616Y277420D01*
X505621Y277380D01*
X505636Y277335D01*
X505646Y277295D01*
X505661Y277255D01*
X505681Y277215D01*
X505696Y277180D01*
X505716Y277140D01*
X505816Y277000D01*
X505846Y276970D01*
Y275840D01*
X505856Y275715D01*
X505896Y275590D01*
X505956Y275480D01*
X506036Y275380D01*
X506136Y275300D01*
X506246Y275240D01*
X506371Y275200D01*
X506496Y275190D01*
X506621Y275200D01*
X506746Y275240D01*
X506856Y275300D01*
X506956Y275380D01*
X507036Y275480D01*
X507096Y275590D01*
X507136Y275715D01*
X507146Y275840D01*
Y276970D01*
X507176Y277000D01*
X507276Y277140D01*
X507296Y277180D01*
X507311Y277215D01*
X507331Y277255D01*
X507346Y277295D01*
X507356Y277335D01*
X507371Y277380D01*
X507376Y277420D01*
X507386Y277460D01*
X507391Y277505D01*
Y277545D01*
X507396Y277590D01*
X507391Y277635D01*
Y277675D01*
X507386Y277720D01*
X507376Y277760D01*
X507371Y277800D01*
X507356Y277845D01*
X507346Y277885D01*
X507331Y277925D01*
X507311Y277965D01*
X507296Y278000D01*
X507276Y278040D01*
X507176Y278180D01*
X507146Y278210D01*
Y281640D01*
X507136Y281765D01*
X507096Y281890D01*
X507036Y282000D01*
X506956Y282100D01*
X506856Y282180D01*
X506746Y282240D01*
X506621Y282280D01*
X506496Y282290D01*
G37*
G36*
G01X511221D02*
X511096Y282280D01*
X510971Y282240D01*
X510861Y282180D01*
X510761Y282100D01*
X510681Y282000D01*
X510621Y281890D01*
X510581Y281765D01*
X510571Y281640D01*
Y278210D01*
X510541Y278180D01*
X510441Y278040D01*
X510421Y278000D01*
X510406Y277965D01*
X510386Y277925D01*
X510371Y277885D01*
X510361Y277845D01*
X510346Y277800D01*
X510341Y277760D01*
X510331Y277720D01*
X510326Y277675D01*
Y277635D01*
X510321Y277590D01*
X510326Y277545D01*
Y277505D01*
X510331Y277460D01*
X510341Y277420D01*
X510346Y277380D01*
X510361Y277335D01*
X510371Y277295D01*
X510386Y277255D01*
X510406Y277215D01*
X510421Y277180D01*
X510441Y277140D01*
X510541Y277000D01*
X510571Y276970D01*
Y275840D01*
X510581Y275715D01*
X510621Y275590D01*
X510681Y275480D01*
X510761Y275380D01*
X510861Y275300D01*
X510971Y275240D01*
X511096Y275200D01*
X511221Y275190D01*
X511346Y275200D01*
X511471Y275240D01*
X511581Y275300D01*
X511681Y275380D01*
X511761Y275480D01*
X511821Y275590D01*
X511861Y275715D01*
X511871Y275840D01*
Y276970D01*
X511901Y277000D01*
X512001Y277140D01*
X512021Y277180D01*
X512036Y277215D01*
X512056Y277255D01*
X512071Y277295D01*
X512081Y277335D01*
X512096Y277380D01*
X512101Y277420D01*
X512111Y277460D01*
X512116Y277505D01*
Y277545D01*
X512121Y277590D01*
X512116Y277635D01*
Y277675D01*
X512111Y277720D01*
X512101Y277760D01*
X512096Y277800D01*
X512081Y277845D01*
X512071Y277885D01*
X512056Y277925D01*
X512036Y277965D01*
X512021Y278000D01*
X512001Y278040D01*
X511901Y278180D01*
X511871Y278210D01*
Y281640D01*
X511861Y281765D01*
X511821Y281890D01*
X511761Y282000D01*
X511681Y282100D01*
X511581Y282180D01*
X511471Y282240D01*
X511346Y282280D01*
X511221Y282290D01*
G37*
G36*
G01X515945D02*
X515820Y282280D01*
X515695Y282240D01*
X515585Y282180D01*
X515485Y282100D01*
X515405Y282000D01*
X515345Y281890D01*
X515305Y281765D01*
X515295Y281640D01*
Y278210D01*
X515265Y278180D01*
X515165Y278040D01*
X515145Y278000D01*
X515130Y277965D01*
X515110Y277925D01*
X515095Y277885D01*
X515085Y277845D01*
X515070Y277800D01*
X515065Y277760D01*
X515055Y277720D01*
X515050Y277675D01*
Y277635D01*
X515045Y277590D01*
X515050Y277545D01*
Y277505D01*
X515055Y277460D01*
X515065Y277420D01*
X515070Y277380D01*
X515085Y277335D01*
X515095Y277295D01*
X515110Y277255D01*
X515130Y277215D01*
X515145Y277180D01*
X515165Y277140D01*
X515265Y277000D01*
X515295Y276970D01*
Y275840D01*
X515305Y275715D01*
X515345Y275590D01*
X515405Y275480D01*
X515485Y275380D01*
X515585Y275300D01*
X515695Y275240D01*
X515820Y275200D01*
X515945Y275190D01*
X516070Y275200D01*
X516195Y275240D01*
X516305Y275300D01*
X516405Y275380D01*
X516485Y275480D01*
X516545Y275590D01*
X516585Y275715D01*
X516595Y275840D01*
Y276970D01*
X516625Y277000D01*
X516725Y277140D01*
X516745Y277180D01*
X516760Y277215D01*
X516780Y277255D01*
X516795Y277295D01*
X516805Y277335D01*
X516820Y277380D01*
X516825Y277420D01*
X516835Y277460D01*
X516840Y277505D01*
Y277545D01*
X516845Y277590D01*
X516840Y277635D01*
Y277675D01*
X516835Y277720D01*
X516825Y277760D01*
X516820Y277800D01*
X516805Y277845D01*
X516795Y277885D01*
X516780Y277925D01*
X516760Y277965D01*
X516745Y278000D01*
X516725Y278040D01*
X516625Y278180D01*
X516595Y278210D01*
Y281640D01*
X516585Y281765D01*
X516545Y281890D01*
X516485Y282000D01*
X516405Y282100D01*
X516305Y282180D01*
X516195Y282240D01*
X516070Y282280D01*
X515945Y282290D01*
G37*
G36*
G01X520670D02*
X520545Y282280D01*
X520420Y282240D01*
X520310Y282180D01*
X520210Y282100D01*
X520130Y282000D01*
X520070Y281890D01*
X520030Y281765D01*
X520020Y281640D01*
Y278210D01*
X519990Y278180D01*
X519890Y278040D01*
X519870Y278000D01*
X519855Y277965D01*
X519835Y277925D01*
X519820Y277885D01*
X519810Y277845D01*
X519795Y277800D01*
X519790Y277760D01*
X519780Y277720D01*
X519775Y277675D01*
Y277635D01*
X519770Y277590D01*
X519775Y277545D01*
Y277505D01*
X519780Y277460D01*
X519790Y277420D01*
X519795Y277380D01*
X519810Y277335D01*
X519820Y277295D01*
X519835Y277255D01*
X519855Y277215D01*
X519870Y277180D01*
X519890Y277140D01*
X519990Y277000D01*
X520020Y276970D01*
Y275840D01*
X520030Y275715D01*
X520070Y275590D01*
X520130Y275480D01*
X520210Y275380D01*
X520310Y275300D01*
X520420Y275240D01*
X520545Y275200D01*
X520670Y275190D01*
X520795Y275200D01*
X520920Y275240D01*
X521030Y275300D01*
X521130Y275380D01*
X521210Y275480D01*
X521270Y275590D01*
X521310Y275715D01*
X521320Y275840D01*
Y276970D01*
X521350Y277000D01*
X521450Y277140D01*
X521470Y277180D01*
X521485Y277215D01*
X521505Y277255D01*
X521520Y277295D01*
X521530Y277335D01*
X521545Y277380D01*
X521550Y277420D01*
X521560Y277460D01*
X521565Y277505D01*
Y277545D01*
X521570Y277590D01*
X521565Y277635D01*
Y277675D01*
X521560Y277720D01*
X521550Y277760D01*
X521545Y277800D01*
X521530Y277845D01*
X521520Y277885D01*
X521505Y277925D01*
X521485Y277965D01*
X521470Y278000D01*
X521450Y278040D01*
X521350Y278180D01*
X521320Y278210D01*
Y281640D01*
X521310Y281765D01*
X521270Y281890D01*
X521210Y282000D01*
X521130Y282100D01*
X521030Y282180D01*
X520920Y282240D01*
X520795Y282280D01*
X520670Y282290D01*
G37*
G36*
G01X525394D02*
X525269Y282280D01*
X525144Y282240D01*
X525034Y282180D01*
X524934Y282100D01*
X524854Y282000D01*
X524794Y281890D01*
X524754Y281765D01*
X524744Y281640D01*
Y278210D01*
X524714Y278180D01*
X524614Y278040D01*
X524594Y278000D01*
X524579Y277965D01*
X524559Y277925D01*
X524544Y277885D01*
X524534Y277845D01*
X524519Y277800D01*
X524514Y277760D01*
X524504Y277720D01*
X524499Y277675D01*
Y277635D01*
X524494Y277590D01*
X524499Y277545D01*
Y277505D01*
X524504Y277460D01*
X524514Y277420D01*
X524519Y277380D01*
X524534Y277335D01*
X524544Y277295D01*
X524559Y277255D01*
X524579Y277215D01*
X524594Y277180D01*
X524614Y277140D01*
X524714Y277000D01*
X524744Y276970D01*
Y275840D01*
X524754Y275715D01*
X524794Y275590D01*
X524854Y275480D01*
X524934Y275380D01*
X525034Y275300D01*
X525144Y275240D01*
X525269Y275200D01*
X525394Y275190D01*
X525519Y275200D01*
X525644Y275240D01*
X525754Y275300D01*
X525854Y275380D01*
X525934Y275480D01*
X525994Y275590D01*
X526034Y275715D01*
X526044Y275840D01*
Y276970D01*
X526074Y277000D01*
X526174Y277140D01*
X526194Y277180D01*
X526209Y277215D01*
X526229Y277255D01*
X526244Y277295D01*
X526254Y277335D01*
X526269Y277380D01*
X526274Y277420D01*
X526284Y277460D01*
X526289Y277505D01*
Y277545D01*
X526294Y277590D01*
X526289Y277635D01*
Y277675D01*
X526284Y277720D01*
X526274Y277760D01*
X526269Y277800D01*
X526254Y277845D01*
X526244Y277885D01*
X526229Y277925D01*
X526209Y277965D01*
X526194Y278000D01*
X526174Y278040D01*
X526074Y278180D01*
X526044Y278210D01*
Y281640D01*
X526034Y281765D01*
X525994Y281890D01*
X525934Y282000D01*
X525854Y282100D01*
X525754Y282180D01*
X525644Y282240D01*
X525519Y282280D01*
X525394Y282290D01*
G37*
G36*
G01X530118D02*
X529993Y282280D01*
X529868Y282240D01*
X529758Y282180D01*
X529658Y282100D01*
X529578Y282000D01*
X529518Y281890D01*
X529478Y281765D01*
X529468Y281640D01*
Y278210D01*
X529438Y278180D01*
X529338Y278040D01*
X529318Y278000D01*
X529303Y277965D01*
X529283Y277925D01*
X529268Y277885D01*
X529258Y277845D01*
X529243Y277800D01*
X529238Y277760D01*
X529228Y277720D01*
X529223Y277675D01*
Y277635D01*
X529218Y277590D01*
X529223Y277545D01*
Y277505D01*
X529228Y277460D01*
X529238Y277420D01*
X529243Y277380D01*
X529258Y277335D01*
X529268Y277295D01*
X529283Y277255D01*
X529303Y277215D01*
X529318Y277180D01*
X529338Y277140D01*
X529438Y277000D01*
X529468Y276970D01*
Y275840D01*
X529478Y275715D01*
X529518Y275590D01*
X529578Y275480D01*
X529658Y275380D01*
X529758Y275300D01*
X529868Y275240D01*
X529993Y275200D01*
X530118Y275190D01*
X530243Y275200D01*
X530368Y275240D01*
X530478Y275300D01*
X530578Y275380D01*
X530658Y275480D01*
X530718Y275590D01*
X530758Y275715D01*
X530768Y275840D01*
Y276970D01*
X530798Y277000D01*
X530898Y277140D01*
X530918Y277180D01*
X530933Y277215D01*
X530953Y277255D01*
X530968Y277295D01*
X530978Y277335D01*
X530993Y277380D01*
X530998Y277420D01*
X531008Y277460D01*
X531013Y277505D01*
Y277545D01*
X531018Y277590D01*
X531013Y277635D01*
Y277675D01*
X531008Y277720D01*
X530998Y277760D01*
X530993Y277800D01*
X530978Y277845D01*
X530968Y277885D01*
X530953Y277925D01*
X530933Y277965D01*
X530918Y278000D01*
X530898Y278040D01*
X530798Y278180D01*
X530768Y278210D01*
Y281640D01*
X530758Y281765D01*
X530718Y281890D01*
X530658Y282000D01*
X530578Y282100D01*
X530478Y282180D01*
X530368Y282240D01*
X530243Y282280D01*
X530118Y282290D01*
G37*
G36*
G01X534843D02*
X534718Y282280D01*
X534593Y282240D01*
X534483Y282180D01*
X534383Y282100D01*
X534303Y282000D01*
X534243Y281890D01*
X534203Y281765D01*
X534193Y281640D01*
Y278210D01*
X534163Y278180D01*
X534063Y278040D01*
X534043Y278000D01*
X534028Y277965D01*
X534008Y277925D01*
X533993Y277885D01*
X533983Y277845D01*
X533968Y277800D01*
X533963Y277760D01*
X533953Y277720D01*
X533948Y277675D01*
Y277635D01*
X533943Y277590D01*
X533948Y277545D01*
Y277505D01*
X533953Y277460D01*
X533963Y277420D01*
X533968Y277380D01*
X533983Y277335D01*
X533993Y277295D01*
X534008Y277255D01*
X534028Y277215D01*
X534043Y277180D01*
X534063Y277140D01*
X534163Y277000D01*
X534193Y276970D01*
Y275840D01*
X534203Y275715D01*
X534243Y275590D01*
X534303Y275480D01*
X534383Y275380D01*
X534483Y275300D01*
X534593Y275240D01*
X534718Y275200D01*
X534843Y275190D01*
X534968Y275200D01*
X535093Y275240D01*
X535203Y275300D01*
X535303Y275380D01*
X535383Y275480D01*
X535443Y275590D01*
X535483Y275715D01*
X535493Y275840D01*
Y276970D01*
X535523Y277000D01*
X535623Y277140D01*
X535643Y277180D01*
X535658Y277215D01*
X535678Y277255D01*
X535693Y277295D01*
X535703Y277335D01*
X535718Y277380D01*
X535723Y277420D01*
X535733Y277460D01*
X535738Y277505D01*
Y277545D01*
X535743Y277590D01*
X535738Y277635D01*
Y277675D01*
X535733Y277720D01*
X535723Y277760D01*
X535718Y277800D01*
X535703Y277845D01*
X535693Y277885D01*
X535678Y277925D01*
X535658Y277965D01*
X535643Y278000D01*
X535623Y278040D01*
X535523Y278180D01*
X535493Y278210D01*
Y281640D01*
X535483Y281765D01*
X535443Y281890D01*
X535383Y282000D01*
X535303Y282100D01*
X535203Y282180D01*
X535093Y282240D01*
X534968Y282280D01*
X534843Y282290D01*
G37*
G36*
G01X539567D02*
X539442Y282280D01*
X539317Y282240D01*
X539207Y282180D01*
X539107Y282100D01*
X539027Y282000D01*
X538967Y281890D01*
X538927Y281765D01*
X538917Y281640D01*
Y278210D01*
X538887Y278180D01*
X538787Y278040D01*
X538767Y278000D01*
X538752Y277965D01*
X538732Y277925D01*
X538717Y277885D01*
X538707Y277845D01*
X538692Y277800D01*
X538687Y277760D01*
X538677Y277720D01*
X538672Y277675D01*
Y277635D01*
X538667Y277590D01*
X538672Y277545D01*
Y277505D01*
X538677Y277460D01*
X538687Y277420D01*
X538692Y277380D01*
X538707Y277335D01*
X538717Y277295D01*
X538732Y277255D01*
X538752Y277215D01*
X538767Y277180D01*
X538787Y277140D01*
X538887Y277000D01*
X538917Y276970D01*
Y275840D01*
X538927Y275715D01*
X538967Y275590D01*
X539027Y275480D01*
X539107Y275380D01*
X539207Y275300D01*
X539317Y275240D01*
X539442Y275200D01*
X539567Y275190D01*
X539692Y275200D01*
X539817Y275240D01*
X539927Y275300D01*
X540027Y275380D01*
X540107Y275480D01*
X540167Y275590D01*
X540207Y275715D01*
X540217Y275840D01*
Y276970D01*
X540247Y277000D01*
X540347Y277140D01*
X540367Y277180D01*
X540382Y277215D01*
X540402Y277255D01*
X540417Y277295D01*
X540427Y277335D01*
X540442Y277380D01*
X540447Y277420D01*
X540457Y277460D01*
X540462Y277505D01*
Y277545D01*
X540467Y277590D01*
X540462Y277635D01*
Y277675D01*
X540457Y277720D01*
X540447Y277760D01*
X540442Y277800D01*
X540427Y277845D01*
X540417Y277885D01*
X540402Y277925D01*
X540382Y277965D01*
X540367Y278000D01*
X540347Y278040D01*
X540247Y278180D01*
X540217Y278210D01*
Y281640D01*
X540207Y281765D01*
X540167Y281890D01*
X540107Y282000D01*
X540027Y282100D01*
X539927Y282180D01*
X539817Y282240D01*
X539692Y282280D01*
X539567Y282290D01*
G37*
G36*
G01X544292D02*
X544167Y282280D01*
X544042Y282240D01*
X543932Y282180D01*
X543832Y282100D01*
X543752Y282000D01*
X543692Y281890D01*
X543652Y281765D01*
X543642Y281640D01*
Y278210D01*
X543612Y278180D01*
X543512Y278040D01*
X543492Y278000D01*
X543477Y277965D01*
X543457Y277925D01*
X543442Y277885D01*
X543432Y277845D01*
X543417Y277800D01*
X543412Y277760D01*
X543402Y277720D01*
X543397Y277675D01*
Y277635D01*
X543392Y277590D01*
X543397Y277545D01*
Y277505D01*
X543402Y277460D01*
X543412Y277420D01*
X543417Y277380D01*
X543432Y277335D01*
X543442Y277295D01*
X543457Y277255D01*
X543477Y277215D01*
X543492Y277180D01*
X543512Y277140D01*
X543612Y277000D01*
X543642Y276970D01*
Y275840D01*
X543652Y275715D01*
X543692Y275590D01*
X543752Y275480D01*
X543832Y275380D01*
X543932Y275300D01*
X544042Y275240D01*
X544167Y275200D01*
X544292Y275190D01*
X544417Y275200D01*
X544542Y275240D01*
X544652Y275300D01*
X544752Y275380D01*
X544832Y275480D01*
X544892Y275590D01*
X544932Y275715D01*
X544942Y275840D01*
Y276970D01*
X544972Y277000D01*
X545072Y277140D01*
X545092Y277180D01*
X545107Y277215D01*
X545127Y277255D01*
X545142Y277295D01*
X545152Y277335D01*
X545167Y277380D01*
X545172Y277420D01*
X545182Y277460D01*
X545187Y277505D01*
Y277545D01*
X545192Y277590D01*
X545187Y277635D01*
Y277675D01*
X545182Y277720D01*
X545172Y277760D01*
X545167Y277800D01*
X545152Y277845D01*
X545142Y277885D01*
X545127Y277925D01*
X545107Y277965D01*
X545092Y278000D01*
X545072Y278040D01*
X544972Y278180D01*
X544942Y278210D01*
Y281640D01*
X544932Y281765D01*
X544892Y281890D01*
X544832Y282000D01*
X544752Y282100D01*
X544652Y282180D01*
X544542Y282240D01*
X544417Y282280D01*
X544292Y282290D01*
G37*
G36*
G01X549016D02*
X548891Y282280D01*
X548766Y282240D01*
X548656Y282180D01*
X548556Y282100D01*
X548476Y282000D01*
X548416Y281890D01*
X548376Y281765D01*
X548366Y281640D01*
Y278210D01*
X548336Y278180D01*
X548236Y278040D01*
X548216Y278000D01*
X548201Y277965D01*
X548181Y277925D01*
X548166Y277885D01*
X548156Y277845D01*
X548141Y277800D01*
X548136Y277760D01*
X548126Y277720D01*
X548121Y277675D01*
Y277635D01*
X548116Y277590D01*
X548121Y277545D01*
Y277505D01*
X548126Y277460D01*
X548136Y277420D01*
X548141Y277380D01*
X548156Y277335D01*
X548166Y277295D01*
X548181Y277255D01*
X548201Y277215D01*
X548216Y277180D01*
X548236Y277140D01*
X548336Y277000D01*
X548366Y276970D01*
Y275840D01*
X548376Y275715D01*
X548416Y275590D01*
X548476Y275480D01*
X548556Y275380D01*
X548656Y275300D01*
X548766Y275240D01*
X548891Y275200D01*
X549016Y275190D01*
X549141Y275200D01*
X549266Y275240D01*
X549376Y275300D01*
X549476Y275380D01*
X549556Y275480D01*
X549616Y275590D01*
X549656Y275715D01*
X549666Y275840D01*
Y276970D01*
X549696Y277000D01*
X549796Y277140D01*
X549816Y277180D01*
X549831Y277215D01*
X549851Y277255D01*
X549866Y277295D01*
X549876Y277335D01*
X549891Y277380D01*
X549896Y277420D01*
X549906Y277460D01*
X549911Y277505D01*
Y277545D01*
X549916Y277590D01*
X549911Y277635D01*
Y277675D01*
X549906Y277720D01*
X549896Y277760D01*
X549891Y277800D01*
X549876Y277845D01*
X549866Y277885D01*
X549851Y277925D01*
X549831Y277965D01*
X549816Y278000D01*
X549796Y278040D01*
X549696Y278180D01*
X549666Y278210D01*
Y281640D01*
X549656Y281765D01*
X549616Y281890D01*
X549556Y282000D01*
X549476Y282100D01*
X549376Y282180D01*
X549266Y282240D01*
X549141Y282280D01*
X549016Y282290D01*
G37*
G36*
G01X553740D02*
X553615Y282280D01*
X553490Y282240D01*
X553380Y282180D01*
X553280Y282100D01*
X553200Y282000D01*
X553140Y281890D01*
X553100Y281765D01*
X553090Y281640D01*
Y278210D01*
X553060Y278180D01*
X552960Y278040D01*
X552940Y278000D01*
X552925Y277965D01*
X552905Y277925D01*
X552890Y277885D01*
X552880Y277845D01*
X552865Y277800D01*
X552860Y277760D01*
X552850Y277720D01*
X552845Y277675D01*
Y277635D01*
X552840Y277590D01*
X552845Y277545D01*
Y277505D01*
X552850Y277460D01*
X552860Y277420D01*
X552865Y277380D01*
X552880Y277335D01*
X552890Y277295D01*
X552905Y277255D01*
X552925Y277215D01*
X552940Y277180D01*
X552960Y277140D01*
X553060Y277000D01*
X553090Y276970D01*
Y275840D01*
X553100Y275715D01*
X553140Y275590D01*
X553200Y275480D01*
X553280Y275380D01*
X553380Y275300D01*
X553490Y275240D01*
X553615Y275200D01*
X553740Y275190D01*
X553865Y275200D01*
X553990Y275240D01*
X554100Y275300D01*
X554200Y275380D01*
X554280Y275480D01*
X554340Y275590D01*
X554380Y275715D01*
X554390Y275840D01*
Y276970D01*
X554420Y277000D01*
X554520Y277140D01*
X554540Y277180D01*
X554555Y277215D01*
X554575Y277255D01*
X554590Y277295D01*
X554600Y277335D01*
X554615Y277380D01*
X554620Y277420D01*
X554630Y277460D01*
X554635Y277505D01*
Y277545D01*
X554640Y277590D01*
X554635Y277635D01*
Y277675D01*
X554630Y277720D01*
X554620Y277760D01*
X554615Y277800D01*
X554600Y277845D01*
X554590Y277885D01*
X554575Y277925D01*
X554555Y277965D01*
X554540Y278000D01*
X554520Y278040D01*
X554420Y278180D01*
X554390Y278210D01*
Y281640D01*
X554380Y281765D01*
X554340Y281890D01*
X554280Y282000D01*
X554200Y282100D01*
X554100Y282180D01*
X553990Y282240D01*
X553865Y282280D01*
X553740Y282290D01*
G37*
G36*
G01X558465D02*
X558340Y282280D01*
X558215Y282240D01*
X558105Y282180D01*
X558005Y282100D01*
X557925Y282000D01*
X557865Y281890D01*
X557825Y281765D01*
X557815Y281640D01*
Y278210D01*
X557785Y278180D01*
X557685Y278040D01*
X557665Y278000D01*
X557650Y277965D01*
X557630Y277925D01*
X557615Y277885D01*
X557605Y277845D01*
X557590Y277800D01*
X557585Y277760D01*
X557575Y277720D01*
X557570Y277675D01*
Y277635D01*
X557565Y277590D01*
X557570Y277545D01*
Y277505D01*
X557575Y277460D01*
X557585Y277420D01*
X557590Y277380D01*
X557605Y277335D01*
X557615Y277295D01*
X557630Y277255D01*
X557650Y277215D01*
X557665Y277180D01*
X557685Y277140D01*
X557785Y277000D01*
X557815Y276970D01*
Y275840D01*
X557825Y275715D01*
X557865Y275590D01*
X557925Y275480D01*
X558005Y275380D01*
X558105Y275300D01*
X558215Y275240D01*
X558340Y275200D01*
X558465Y275190D01*
X558590Y275200D01*
X558715Y275240D01*
X558825Y275300D01*
X558925Y275380D01*
X559005Y275480D01*
X559065Y275590D01*
X559105Y275715D01*
X559115Y275840D01*
Y276970D01*
X559145Y277000D01*
X559245Y277140D01*
X559265Y277180D01*
X559280Y277215D01*
X559300Y277255D01*
X559315Y277295D01*
X559325Y277335D01*
X559340Y277380D01*
X559345Y277420D01*
X559355Y277460D01*
X559360Y277505D01*
Y277545D01*
X559365Y277590D01*
X559360Y277635D01*
Y277675D01*
X559355Y277720D01*
X559345Y277760D01*
X559340Y277800D01*
X559325Y277845D01*
X559315Y277885D01*
X559300Y277925D01*
X559280Y277965D01*
X559265Y278000D01*
X559245Y278040D01*
X559145Y278180D01*
X559115Y278210D01*
Y281640D01*
X559105Y281765D01*
X559065Y281890D01*
X559005Y282000D01*
X558925Y282100D01*
X558825Y282180D01*
X558715Y282240D01*
X558590Y282280D01*
X558465Y282290D01*
G37*
G36*
G01X563189D02*
X563064Y282280D01*
X562939Y282240D01*
X562829Y282180D01*
X562729Y282100D01*
X562649Y282000D01*
X562589Y281890D01*
X562549Y281765D01*
X562539Y281640D01*
Y278210D01*
X562509Y278180D01*
X562409Y278040D01*
X562389Y278000D01*
X562374Y277965D01*
X562354Y277925D01*
X562339Y277885D01*
X562329Y277845D01*
X562314Y277800D01*
X562309Y277760D01*
X562299Y277720D01*
X562294Y277675D01*
Y277635D01*
X562289Y277590D01*
X562294Y277545D01*
Y277505D01*
X562299Y277460D01*
X562309Y277420D01*
X562314Y277380D01*
X562329Y277335D01*
X562339Y277295D01*
X562354Y277255D01*
X562374Y277215D01*
X562389Y277180D01*
X562409Y277140D01*
X562509Y277000D01*
X562539Y276970D01*
Y275840D01*
X562549Y275715D01*
X562589Y275590D01*
X562649Y275480D01*
X562729Y275380D01*
X562829Y275300D01*
X562939Y275240D01*
X563064Y275200D01*
X563189Y275190D01*
X563314Y275200D01*
X563439Y275240D01*
X563549Y275300D01*
X563649Y275380D01*
X563729Y275480D01*
X563789Y275590D01*
X563829Y275715D01*
X563839Y275840D01*
Y276970D01*
X563869Y277000D01*
X563969Y277140D01*
X563989Y277180D01*
X564004Y277215D01*
X564024Y277255D01*
X564039Y277295D01*
X564049Y277335D01*
X564064Y277380D01*
X564069Y277420D01*
X564079Y277460D01*
X564084Y277505D01*
Y277545D01*
X564089Y277590D01*
X564084Y277635D01*
Y277675D01*
X564079Y277720D01*
X564069Y277760D01*
X564064Y277800D01*
X564049Y277845D01*
X564039Y277885D01*
X564024Y277925D01*
X564004Y277965D01*
X563989Y278000D01*
X563969Y278040D01*
X563869Y278180D01*
X563839Y278210D01*
Y281640D01*
X563829Y281765D01*
X563789Y281890D01*
X563729Y282000D01*
X563649Y282100D01*
X563549Y282180D01*
X563439Y282240D01*
X563314Y282280D01*
X563189Y282290D01*
G37*
G36*
G01X567914D02*
X567789Y282280D01*
X567664Y282240D01*
X567554Y282180D01*
X567454Y282100D01*
X567374Y282000D01*
X567314Y281890D01*
X567274Y281765D01*
X567264Y281640D01*
Y278210D01*
X567234Y278180D01*
X567134Y278040D01*
X567114Y278000D01*
X567099Y277965D01*
X567079Y277925D01*
X567064Y277885D01*
X567054Y277845D01*
X567039Y277800D01*
X567034Y277760D01*
X567024Y277720D01*
X567019Y277675D01*
Y277635D01*
X567014Y277590D01*
X567019Y277545D01*
Y277505D01*
X567024Y277460D01*
X567034Y277420D01*
X567039Y277380D01*
X567054Y277335D01*
X567064Y277295D01*
X567079Y277255D01*
X567099Y277215D01*
X567114Y277180D01*
X567134Y277140D01*
X567234Y277000D01*
X567264Y276970D01*
Y275840D01*
X567274Y275715D01*
X567314Y275590D01*
X567374Y275480D01*
X567454Y275380D01*
X567554Y275300D01*
X567664Y275240D01*
X567789Y275200D01*
X567914Y275190D01*
X568039Y275200D01*
X568164Y275240D01*
X568274Y275300D01*
X568374Y275380D01*
X568454Y275480D01*
X568514Y275590D01*
X568554Y275715D01*
X568564Y275840D01*
Y276970D01*
X568594Y277000D01*
X568694Y277140D01*
X568714Y277180D01*
X568729Y277215D01*
X568749Y277255D01*
X568764Y277295D01*
X568774Y277335D01*
X568789Y277380D01*
X568794Y277420D01*
X568804Y277460D01*
X568809Y277505D01*
Y277545D01*
X568814Y277590D01*
X568809Y277635D01*
Y277675D01*
X568804Y277720D01*
X568794Y277760D01*
X568789Y277800D01*
X568774Y277845D01*
X568764Y277885D01*
X568749Y277925D01*
X568729Y277965D01*
X568714Y278000D01*
X568694Y278040D01*
X568594Y278180D01*
X568564Y278210D01*
Y281640D01*
X568554Y281765D01*
X568514Y281890D01*
X568454Y282000D01*
X568374Y282100D01*
X568274Y282180D01*
X568164Y282240D01*
X568039Y282280D01*
X567914Y282290D01*
G37*
G36*
G01X572638D02*
X572513Y282280D01*
X572388Y282240D01*
X572278Y282180D01*
X572178Y282100D01*
X572098Y282000D01*
X572038Y281890D01*
X571998Y281765D01*
X571988Y281640D01*
Y278210D01*
X571958Y278180D01*
X571858Y278040D01*
X571838Y278000D01*
X571823Y277965D01*
X571803Y277925D01*
X571788Y277885D01*
X571778Y277845D01*
X571763Y277800D01*
X571758Y277760D01*
X571748Y277720D01*
X571743Y277675D01*
Y277635D01*
X571738Y277590D01*
X571743Y277545D01*
Y277505D01*
X571748Y277460D01*
X571758Y277420D01*
X571763Y277380D01*
X571778Y277335D01*
X571788Y277295D01*
X571803Y277255D01*
X571823Y277215D01*
X571838Y277180D01*
X571858Y277140D01*
X571958Y277000D01*
X571988Y276970D01*
Y275840D01*
X571998Y275715D01*
X572038Y275590D01*
X572098Y275480D01*
X572178Y275380D01*
X572278Y275300D01*
X572388Y275240D01*
X572513Y275200D01*
X572638Y275190D01*
X572763Y275200D01*
X572888Y275240D01*
X572998Y275300D01*
X573098Y275380D01*
X573178Y275480D01*
X573238Y275590D01*
X573278Y275715D01*
X573288Y275840D01*
Y276970D01*
X573318Y277000D01*
X573418Y277140D01*
X573438Y277180D01*
X573453Y277215D01*
X573473Y277255D01*
X573488Y277295D01*
X573498Y277335D01*
X573513Y277380D01*
X573518Y277420D01*
X573528Y277460D01*
X573533Y277505D01*
Y277545D01*
X573538Y277590D01*
X573533Y277635D01*
Y277675D01*
X573528Y277720D01*
X573518Y277760D01*
X573513Y277800D01*
X573498Y277845D01*
X573488Y277885D01*
X573473Y277925D01*
X573453Y277965D01*
X573438Y278000D01*
X573418Y278040D01*
X573318Y278180D01*
X573288Y278210D01*
Y281640D01*
X573278Y281765D01*
X573238Y281890D01*
X573178Y282000D01*
X573098Y282100D01*
X572998Y282180D01*
X572888Y282240D01*
X572763Y282280D01*
X572638Y282290D01*
G37*
G36*
G01X577362D02*
X577237Y282280D01*
X577112Y282240D01*
X577002Y282180D01*
X576902Y282100D01*
X576822Y282000D01*
X576762Y281890D01*
X576722Y281765D01*
X576712Y281640D01*
Y278210D01*
X576682Y278180D01*
X576582Y278040D01*
X576562Y278000D01*
X576547Y277965D01*
X576527Y277925D01*
X576512Y277885D01*
X576502Y277845D01*
X576487Y277800D01*
X576482Y277760D01*
X576472Y277720D01*
X576467Y277675D01*
Y277635D01*
X576462Y277590D01*
X576467Y277545D01*
Y277505D01*
X576472Y277460D01*
X576482Y277420D01*
X576487Y277380D01*
X576502Y277335D01*
X576512Y277295D01*
X576527Y277255D01*
X576547Y277215D01*
X576562Y277180D01*
X576582Y277140D01*
X576682Y277000D01*
X576712Y276970D01*
Y275840D01*
X576722Y275715D01*
X576762Y275590D01*
X576822Y275480D01*
X576902Y275380D01*
X577002Y275300D01*
X577112Y275240D01*
X577237Y275200D01*
X577362Y275190D01*
X577487Y275200D01*
X577612Y275240D01*
X577722Y275300D01*
X577822Y275380D01*
X577902Y275480D01*
X577962Y275590D01*
X578002Y275715D01*
X578012Y275840D01*
Y276970D01*
X578042Y277000D01*
X578142Y277140D01*
X578162Y277180D01*
X578177Y277215D01*
X578197Y277255D01*
X578212Y277295D01*
X578222Y277335D01*
X578237Y277380D01*
X578242Y277420D01*
X578252Y277460D01*
X578257Y277505D01*
Y277545D01*
X578262Y277590D01*
X578257Y277635D01*
Y277675D01*
X578252Y277720D01*
X578242Y277760D01*
X578237Y277800D01*
X578222Y277845D01*
X578212Y277885D01*
X578197Y277925D01*
X578177Y277965D01*
X578162Y278000D01*
X578142Y278040D01*
X578042Y278180D01*
X578012Y278210D01*
Y281640D01*
X578002Y281765D01*
X577962Y281890D01*
X577902Y282000D01*
X577822Y282100D01*
X577722Y282180D01*
X577612Y282240D01*
X577487Y282280D01*
X577362Y282290D01*
G37*
G36*
G01X582087D02*
X581962Y282280D01*
X581837Y282240D01*
X581727Y282180D01*
X581627Y282100D01*
X581547Y282000D01*
X581487Y281890D01*
X581447Y281765D01*
X581437Y281640D01*
Y278210D01*
X581407Y278180D01*
X581307Y278040D01*
X581287Y278000D01*
X581272Y277965D01*
X581252Y277925D01*
X581237Y277885D01*
X581227Y277845D01*
X581212Y277800D01*
X581207Y277760D01*
X581197Y277720D01*
X581192Y277675D01*
Y277635D01*
X581187Y277590D01*
X581192Y277545D01*
Y277505D01*
X581197Y277460D01*
X581207Y277420D01*
X581212Y277380D01*
X581227Y277335D01*
X581237Y277295D01*
X581252Y277255D01*
X581272Y277215D01*
X581287Y277180D01*
X581307Y277140D01*
X581407Y277000D01*
X581437Y276970D01*
Y275840D01*
X581447Y275715D01*
X581487Y275590D01*
X581547Y275480D01*
X581627Y275380D01*
X581727Y275300D01*
X581837Y275240D01*
X581962Y275200D01*
X582087Y275190D01*
X582212Y275200D01*
X582337Y275240D01*
X582447Y275300D01*
X582547Y275380D01*
X582627Y275480D01*
X582687Y275590D01*
X582727Y275715D01*
X582737Y275840D01*
Y276970D01*
X582767Y277000D01*
X582867Y277140D01*
X582887Y277180D01*
X582902Y277215D01*
X582922Y277255D01*
X582937Y277295D01*
X582947Y277335D01*
X582962Y277380D01*
X582967Y277420D01*
X582977Y277460D01*
X582982Y277505D01*
Y277545D01*
X582987Y277590D01*
X582982Y277635D01*
Y277675D01*
X582977Y277720D01*
X582967Y277760D01*
X582962Y277800D01*
X582947Y277845D01*
X582937Y277885D01*
X582922Y277925D01*
X582902Y277965D01*
X582887Y278000D01*
X582867Y278040D01*
X582767Y278180D01*
X582737Y278210D01*
Y281640D01*
X582727Y281765D01*
X582687Y281890D01*
X582627Y282000D01*
X582547Y282100D01*
X582447Y282180D01*
X582337Y282240D01*
X582212Y282280D01*
X582087Y282290D01*
G37*
G36*
G01X586811D02*
X586686Y282280D01*
X586561Y282240D01*
X586451Y282180D01*
X586351Y282100D01*
X586271Y282000D01*
X586211Y281890D01*
X586171Y281765D01*
X586161Y281640D01*
Y278210D01*
X586131Y278180D01*
X586031Y278040D01*
X586011Y278000D01*
X585996Y277965D01*
X585976Y277925D01*
X585961Y277885D01*
X585951Y277845D01*
X585936Y277800D01*
X585931Y277760D01*
X585921Y277720D01*
X585916Y277675D01*
Y277635D01*
X585911Y277590D01*
X585916Y277545D01*
Y277505D01*
X585921Y277460D01*
X585931Y277420D01*
X585936Y277380D01*
X585951Y277335D01*
X585961Y277295D01*
X585976Y277255D01*
X585996Y277215D01*
X586011Y277180D01*
X586031Y277140D01*
X586131Y277000D01*
X586161Y276970D01*
Y275840D01*
X586171Y275715D01*
X586211Y275590D01*
X586271Y275480D01*
X586351Y275380D01*
X586451Y275300D01*
X586561Y275240D01*
X586686Y275200D01*
X586811Y275190D01*
X586936Y275200D01*
X587061Y275240D01*
X587171Y275300D01*
X587271Y275380D01*
X587351Y275480D01*
X587411Y275590D01*
X587451Y275715D01*
X587461Y275840D01*
Y276970D01*
X587491Y277000D01*
X587591Y277140D01*
X587611Y277180D01*
X587626Y277215D01*
X587646Y277255D01*
X587661Y277295D01*
X587671Y277335D01*
X587686Y277380D01*
X587691Y277420D01*
X587701Y277460D01*
X587706Y277505D01*
Y277545D01*
X587711Y277590D01*
X587706Y277635D01*
Y277675D01*
X587701Y277720D01*
X587691Y277760D01*
X587686Y277800D01*
X587671Y277845D01*
X587661Y277885D01*
X587646Y277925D01*
X587626Y277965D01*
X587611Y278000D01*
X587591Y278040D01*
X587491Y278180D01*
X587461Y278210D01*
Y281640D01*
X587451Y281765D01*
X587411Y281890D01*
X587351Y282000D01*
X587271Y282100D01*
X587171Y282180D01*
X587061Y282240D01*
X586936Y282280D01*
X586811Y282290D01*
G37*
G36*
G01X591536D02*
X591411Y282280D01*
X591286Y282240D01*
X591176Y282180D01*
X591076Y282100D01*
X590996Y282000D01*
X590936Y281890D01*
X590896Y281765D01*
X590886Y281640D01*
Y278210D01*
X590856Y278180D01*
X590756Y278040D01*
X590736Y278000D01*
X590721Y277965D01*
X590701Y277925D01*
X590686Y277885D01*
X590676Y277845D01*
X590661Y277800D01*
X590656Y277760D01*
X590646Y277720D01*
X590641Y277675D01*
Y277635D01*
X590636Y277590D01*
X590641Y277545D01*
Y277505D01*
X590646Y277460D01*
X590656Y277420D01*
X590661Y277380D01*
X590676Y277335D01*
X590686Y277295D01*
X590701Y277255D01*
X590721Y277215D01*
X590736Y277180D01*
X590756Y277140D01*
X590856Y277000D01*
X590886Y276970D01*
Y275840D01*
X590896Y275715D01*
X590936Y275590D01*
X590996Y275480D01*
X591076Y275380D01*
X591176Y275300D01*
X591286Y275240D01*
X591411Y275200D01*
X591536Y275190D01*
X591661Y275200D01*
X591786Y275240D01*
X591896Y275300D01*
X591996Y275380D01*
X592076Y275480D01*
X592136Y275590D01*
X592176Y275715D01*
X592186Y275840D01*
Y276970D01*
X592216Y277000D01*
X592316Y277140D01*
X592336Y277180D01*
X592351Y277215D01*
X592371Y277255D01*
X592386Y277295D01*
X592396Y277335D01*
X592411Y277380D01*
X592416Y277420D01*
X592426Y277460D01*
X592431Y277505D01*
Y277545D01*
X592436Y277590D01*
X592431Y277635D01*
Y277675D01*
X592426Y277720D01*
X592416Y277760D01*
X592411Y277800D01*
X592396Y277845D01*
X592386Y277885D01*
X592371Y277925D01*
X592351Y277965D01*
X592336Y278000D01*
X592316Y278040D01*
X592216Y278180D01*
X592186Y278210D01*
Y281640D01*
X592176Y281765D01*
X592136Y281890D01*
X592076Y282000D01*
X591996Y282100D01*
X591896Y282180D01*
X591786Y282240D01*
X591661Y282280D01*
X591536Y282290D01*
G37*
G36*
G01X596260D02*
X596135Y282280D01*
X596010Y282240D01*
X595900Y282180D01*
X595800Y282100D01*
X595720Y282000D01*
X595660Y281890D01*
X595620Y281765D01*
X595610Y281640D01*
Y278210D01*
X595580Y278180D01*
X595480Y278040D01*
X595460Y278000D01*
X595445Y277965D01*
X595425Y277925D01*
X595410Y277885D01*
X595400Y277845D01*
X595385Y277800D01*
X595380Y277760D01*
X595370Y277720D01*
X595365Y277675D01*
Y277635D01*
X595360Y277590D01*
X595365Y277545D01*
Y277505D01*
X595370Y277460D01*
X595380Y277420D01*
X595385Y277380D01*
X595400Y277335D01*
X595410Y277295D01*
X595425Y277255D01*
X595445Y277215D01*
X595460Y277180D01*
X595480Y277140D01*
X595580Y277000D01*
X595610Y276970D01*
Y275840D01*
X595620Y275715D01*
X595660Y275590D01*
X595720Y275480D01*
X595800Y275380D01*
X595900Y275300D01*
X596010Y275240D01*
X596135Y275200D01*
X596260Y275190D01*
X596385Y275200D01*
X596510Y275240D01*
X596620Y275300D01*
X596720Y275380D01*
X596800Y275480D01*
X596860Y275590D01*
X596900Y275715D01*
X596910Y275840D01*
Y276970D01*
X596940Y277000D01*
X597040Y277140D01*
X597060Y277180D01*
X597075Y277215D01*
X597095Y277255D01*
X597110Y277295D01*
X597120Y277335D01*
X597135Y277380D01*
X597140Y277420D01*
X597150Y277460D01*
X597155Y277505D01*
Y277545D01*
X597160Y277590D01*
X597155Y277635D01*
Y277675D01*
X597150Y277720D01*
X597140Y277760D01*
X597135Y277800D01*
X597120Y277845D01*
X597110Y277885D01*
X597095Y277925D01*
X597075Y277965D01*
X597060Y278000D01*
X597040Y278040D01*
X596940Y278180D01*
X596910Y278210D01*
Y281640D01*
X596900Y281765D01*
X596860Y281890D01*
X596800Y282000D01*
X596720Y282100D01*
X596620Y282180D01*
X596510Y282240D01*
X596385Y282280D01*
X596260Y282290D01*
G37*
G36*
G01X600985D02*
X600860Y282280D01*
X600735Y282240D01*
X600625Y282180D01*
X600525Y282100D01*
X600445Y282000D01*
X600385Y281890D01*
X600345Y281765D01*
X600335Y281640D01*
Y278210D01*
X600305Y278180D01*
X600205Y278040D01*
X600185Y278000D01*
X600170Y277965D01*
X600150Y277925D01*
X600135Y277885D01*
X600125Y277845D01*
X600110Y277800D01*
X600105Y277760D01*
X600095Y277720D01*
X600090Y277675D01*
Y277635D01*
X600085Y277590D01*
X600090Y277545D01*
Y277505D01*
X600095Y277460D01*
X600105Y277420D01*
X600110Y277380D01*
X600125Y277335D01*
X600135Y277295D01*
X600150Y277255D01*
X600170Y277215D01*
X600185Y277180D01*
X600205Y277140D01*
X600305Y277000D01*
X600335Y276970D01*
Y275840D01*
X600345Y275715D01*
X600385Y275590D01*
X600445Y275480D01*
X600525Y275380D01*
X600625Y275300D01*
X600735Y275240D01*
X600860Y275200D01*
X600985Y275190D01*
X601110Y275200D01*
X601235Y275240D01*
X601345Y275300D01*
X601445Y275380D01*
X601525Y275480D01*
X601585Y275590D01*
X601625Y275715D01*
X601635Y275840D01*
Y276970D01*
X601665Y277000D01*
X601765Y277140D01*
X601785Y277180D01*
X601800Y277215D01*
X601820Y277255D01*
X601835Y277295D01*
X601845Y277335D01*
X601860Y277380D01*
X601865Y277420D01*
X601875Y277460D01*
X601880Y277505D01*
Y277545D01*
X601885Y277590D01*
X601880Y277635D01*
Y277675D01*
X601875Y277720D01*
X601865Y277760D01*
X601860Y277800D01*
X601845Y277845D01*
X601835Y277885D01*
X601820Y277925D01*
X601800Y277965D01*
X601785Y278000D01*
X601765Y278040D01*
X601665Y278180D01*
X601635Y278210D01*
Y281640D01*
X601625Y281765D01*
X601585Y281890D01*
X601525Y282000D01*
X601445Y282100D01*
X601345Y282180D01*
X601235Y282240D01*
X601110Y282280D01*
X600985Y282290D01*
G37*
G36*
G01X605709D02*
X605584Y282280D01*
X605459Y282240D01*
X605349Y282180D01*
X605249Y282100D01*
X605169Y282000D01*
X605109Y281890D01*
X605069Y281765D01*
X605059Y281640D01*
Y278210D01*
X605029Y278180D01*
X604929Y278040D01*
X604909Y278000D01*
X604894Y277965D01*
X604874Y277925D01*
X604859Y277885D01*
X604849Y277845D01*
X604834Y277800D01*
X604829Y277760D01*
X604819Y277720D01*
X604814Y277675D01*
Y277635D01*
X604809Y277590D01*
X604814Y277545D01*
Y277505D01*
X604819Y277460D01*
X604829Y277420D01*
X604834Y277380D01*
X604849Y277335D01*
X604859Y277295D01*
X604874Y277255D01*
X604894Y277215D01*
X604909Y277180D01*
X604929Y277140D01*
X605029Y277000D01*
X605059Y276970D01*
Y275840D01*
X605069Y275715D01*
X605109Y275590D01*
X605169Y275480D01*
X605249Y275380D01*
X605349Y275300D01*
X605459Y275240D01*
X605584Y275200D01*
X605709Y275190D01*
X605834Y275200D01*
X605959Y275240D01*
X606069Y275300D01*
X606169Y275380D01*
X606249Y275480D01*
X606309Y275590D01*
X606349Y275715D01*
X606359Y275840D01*
Y276970D01*
X606389Y277000D01*
X606489Y277140D01*
X606509Y277180D01*
X606524Y277215D01*
X606544Y277255D01*
X606559Y277295D01*
X606569Y277335D01*
X606584Y277380D01*
X606589Y277420D01*
X606599Y277460D01*
X606604Y277505D01*
Y277545D01*
X606609Y277590D01*
X606604Y277635D01*
Y277675D01*
X606599Y277720D01*
X606589Y277760D01*
X606584Y277800D01*
X606569Y277845D01*
X606559Y277885D01*
X606544Y277925D01*
X606524Y277965D01*
X606509Y278000D01*
X606489Y278040D01*
X606389Y278180D01*
X606359Y278210D01*
Y281640D01*
X606349Y281765D01*
X606309Y281890D01*
X606249Y282000D01*
X606169Y282100D01*
X606069Y282180D01*
X605959Y282240D01*
X605834Y282280D01*
X605709Y282290D01*
G37*
G36*
G01X610433D02*
X610308Y282280D01*
X610183Y282240D01*
X610073Y282180D01*
X609973Y282100D01*
X609893Y282000D01*
X609833Y281890D01*
X609793Y281765D01*
X609783Y281640D01*
Y278210D01*
X609753Y278180D01*
X609653Y278040D01*
X609633Y278000D01*
X609618Y277965D01*
X609598Y277925D01*
X609583Y277885D01*
X609573Y277845D01*
X609558Y277800D01*
X609553Y277760D01*
X609543Y277720D01*
X609538Y277675D01*
Y277635D01*
X609533Y277590D01*
X609538Y277545D01*
Y277505D01*
X609543Y277460D01*
X609553Y277420D01*
X609558Y277380D01*
X609573Y277335D01*
X609583Y277295D01*
X609598Y277255D01*
X609618Y277215D01*
X609633Y277180D01*
X609653Y277140D01*
X609753Y277000D01*
X609783Y276970D01*
Y275840D01*
X609793Y275715D01*
X609833Y275590D01*
X609893Y275480D01*
X609973Y275380D01*
X610073Y275300D01*
X610183Y275240D01*
X610308Y275200D01*
X610433Y275190D01*
X610558Y275200D01*
X610683Y275240D01*
X610793Y275300D01*
X610893Y275380D01*
X610973Y275480D01*
X611033Y275590D01*
X611073Y275715D01*
X611083Y275840D01*
Y276970D01*
X611113Y277000D01*
X611213Y277140D01*
X611233Y277180D01*
X611248Y277215D01*
X611268Y277255D01*
X611283Y277295D01*
X611293Y277335D01*
X611308Y277380D01*
X611313Y277420D01*
X611323Y277460D01*
X611328Y277505D01*
Y277545D01*
X611333Y277590D01*
X611328Y277635D01*
Y277675D01*
X611323Y277720D01*
X611313Y277760D01*
X611308Y277800D01*
X611293Y277845D01*
X611283Y277885D01*
X611268Y277925D01*
X611248Y277965D01*
X611233Y278000D01*
X611213Y278040D01*
X611113Y278180D01*
X611083Y278210D01*
Y281640D01*
X611073Y281765D01*
X611033Y281890D01*
X610973Y282000D01*
X610893Y282100D01*
X610793Y282180D01*
X610683Y282240D01*
X610558Y282280D01*
X610433Y282290D01*
G37*
G36*
G01X615158D02*
X615033Y282280D01*
X614908Y282240D01*
X614798Y282180D01*
X614698Y282100D01*
X614618Y282000D01*
X614558Y281890D01*
X614518Y281765D01*
X614508Y281640D01*
Y278210D01*
X614478Y278180D01*
X614378Y278040D01*
X614358Y278000D01*
X614343Y277965D01*
X614323Y277925D01*
X614308Y277885D01*
X614298Y277845D01*
X614283Y277800D01*
X614278Y277760D01*
X614268Y277720D01*
X614263Y277675D01*
Y277635D01*
X614258Y277590D01*
X614263Y277545D01*
Y277505D01*
X614268Y277460D01*
X614278Y277420D01*
X614283Y277380D01*
X614298Y277335D01*
X614308Y277295D01*
X614323Y277255D01*
X614343Y277215D01*
X614358Y277180D01*
X614378Y277140D01*
X614478Y277000D01*
X614508Y276970D01*
Y275840D01*
X614518Y275715D01*
X614558Y275590D01*
X614618Y275480D01*
X614698Y275380D01*
X614798Y275300D01*
X614908Y275240D01*
X615033Y275200D01*
X615158Y275190D01*
X615283Y275200D01*
X615408Y275240D01*
X615518Y275300D01*
X615618Y275380D01*
X615698Y275480D01*
X615758Y275590D01*
X615798Y275715D01*
X615808Y275840D01*
Y276970D01*
X615838Y277000D01*
X615938Y277140D01*
X615958Y277180D01*
X615973Y277215D01*
X615993Y277255D01*
X616008Y277295D01*
X616018Y277335D01*
X616033Y277380D01*
X616038Y277420D01*
X616048Y277460D01*
X616053Y277505D01*
Y277545D01*
X616058Y277590D01*
X616053Y277635D01*
Y277675D01*
X616048Y277720D01*
X616038Y277760D01*
X616033Y277800D01*
X616018Y277845D01*
X616008Y277885D01*
X615993Y277925D01*
X615973Y277965D01*
X615958Y278000D01*
X615938Y278040D01*
X615838Y278180D01*
X615808Y278210D01*
Y281640D01*
X615798Y281765D01*
X615758Y281890D01*
X615698Y282000D01*
X615618Y282100D01*
X615518Y282180D01*
X615408Y282240D01*
X615283Y282280D01*
X615158Y282290D01*
G37*
G36*
G01X619882D02*
X619757Y282280D01*
X619632Y282240D01*
X619522Y282180D01*
X619422Y282100D01*
X619342Y282000D01*
X619282Y281890D01*
X619242Y281765D01*
X619232Y281640D01*
Y278210D01*
X619202Y278180D01*
X619102Y278040D01*
X619082Y278000D01*
X619067Y277965D01*
X619047Y277925D01*
X619032Y277885D01*
X619022Y277845D01*
X619007Y277800D01*
X619002Y277760D01*
X618992Y277720D01*
X618987Y277675D01*
Y277635D01*
X618982Y277590D01*
X618987Y277545D01*
Y277505D01*
X618992Y277460D01*
X619002Y277420D01*
X619007Y277380D01*
X619022Y277335D01*
X619032Y277295D01*
X619047Y277255D01*
X619067Y277215D01*
X619082Y277180D01*
X619102Y277140D01*
X619202Y277000D01*
X619232Y276970D01*
Y275840D01*
X619242Y275715D01*
X619282Y275590D01*
X619342Y275480D01*
X619422Y275380D01*
X619522Y275300D01*
X619632Y275240D01*
X619757Y275200D01*
X619882Y275190D01*
X620007Y275200D01*
X620132Y275240D01*
X620242Y275300D01*
X620342Y275380D01*
X620422Y275480D01*
X620482Y275590D01*
X620522Y275715D01*
X620532Y275840D01*
Y276970D01*
X620562Y277000D01*
X620662Y277140D01*
X620682Y277180D01*
X620697Y277215D01*
X620717Y277255D01*
X620732Y277295D01*
X620742Y277335D01*
X620757Y277380D01*
X620762Y277420D01*
X620772Y277460D01*
X620777Y277505D01*
Y277545D01*
X620782Y277590D01*
X620777Y277635D01*
Y277675D01*
X620772Y277720D01*
X620762Y277760D01*
X620757Y277800D01*
X620742Y277845D01*
X620732Y277885D01*
X620717Y277925D01*
X620697Y277965D01*
X620682Y278000D01*
X620662Y278040D01*
X620562Y278180D01*
X620532Y278210D01*
Y281640D01*
X620522Y281765D01*
X620482Y281890D01*
X620422Y282000D01*
X620342Y282100D01*
X620242Y282180D01*
X620132Y282240D01*
X620007Y282280D01*
X619882Y282290D01*
G37*
G36*
G01X624607D02*
X624482Y282280D01*
X624357Y282240D01*
X624247Y282180D01*
X624147Y282100D01*
X624067Y282000D01*
X624007Y281890D01*
X623967Y281765D01*
X623957Y281640D01*
Y278210D01*
X623927Y278180D01*
X623827Y278040D01*
X623807Y278000D01*
X623792Y277965D01*
X623772Y277925D01*
X623757Y277885D01*
X623747Y277845D01*
X623732Y277800D01*
X623727Y277760D01*
X623717Y277720D01*
X623712Y277675D01*
Y277635D01*
X623707Y277590D01*
X623712Y277545D01*
Y277505D01*
X623717Y277460D01*
X623727Y277420D01*
X623732Y277380D01*
X623747Y277335D01*
X623757Y277295D01*
X623772Y277255D01*
X623792Y277215D01*
X623807Y277180D01*
X623827Y277140D01*
X623927Y277000D01*
X623957Y276970D01*
Y275840D01*
X623967Y275715D01*
X624007Y275590D01*
X624067Y275480D01*
X624147Y275380D01*
X624247Y275300D01*
X624357Y275240D01*
X624482Y275200D01*
X624607Y275190D01*
X624732Y275200D01*
X624857Y275240D01*
X624967Y275300D01*
X625067Y275380D01*
X625147Y275480D01*
X625207Y275590D01*
X625247Y275715D01*
X625257Y275840D01*
Y276970D01*
X625287Y277000D01*
X625387Y277140D01*
X625407Y277180D01*
X625422Y277215D01*
X625442Y277255D01*
X625457Y277295D01*
X625467Y277335D01*
X625482Y277380D01*
X625487Y277420D01*
X625497Y277460D01*
X625502Y277505D01*
Y277545D01*
X625507Y277590D01*
X625502Y277635D01*
Y277675D01*
X625497Y277720D01*
X625487Y277760D01*
X625482Y277800D01*
X625467Y277845D01*
X625457Y277885D01*
X625442Y277925D01*
X625422Y277965D01*
X625407Y278000D01*
X625387Y278040D01*
X625287Y278180D01*
X625257Y278210D01*
Y281640D01*
X625247Y281765D01*
X625207Y281890D01*
X625147Y282000D01*
X625067Y282100D01*
X624967Y282180D01*
X624857Y282240D01*
X624732Y282280D01*
X624607Y282290D01*
G37*
G36*
G01X629331D02*
X629206Y282280D01*
X629081Y282240D01*
X628971Y282180D01*
X628871Y282100D01*
X628791Y282000D01*
X628731Y281890D01*
X628691Y281765D01*
X628681Y281640D01*
Y278210D01*
X628651Y278180D01*
X628551Y278040D01*
X628531Y278000D01*
X628516Y277965D01*
X628496Y277925D01*
X628481Y277885D01*
X628471Y277845D01*
X628456Y277800D01*
X628451Y277760D01*
X628441Y277720D01*
X628436Y277675D01*
Y277635D01*
X628431Y277590D01*
X628436Y277545D01*
Y277505D01*
X628441Y277460D01*
X628451Y277420D01*
X628456Y277380D01*
X628471Y277335D01*
X628481Y277295D01*
X628496Y277255D01*
X628516Y277215D01*
X628531Y277180D01*
X628551Y277140D01*
X628651Y277000D01*
X628681Y276970D01*
Y275840D01*
X628691Y275715D01*
X628731Y275590D01*
X628791Y275480D01*
X628871Y275380D01*
X628971Y275300D01*
X629081Y275240D01*
X629206Y275200D01*
X629331Y275190D01*
X629456Y275200D01*
X629581Y275240D01*
X629691Y275300D01*
X629791Y275380D01*
X629871Y275480D01*
X629931Y275590D01*
X629971Y275715D01*
X629981Y275840D01*
Y276970D01*
X630011Y277000D01*
X630111Y277140D01*
X630131Y277180D01*
X630146Y277215D01*
X630166Y277255D01*
X630181Y277295D01*
X630191Y277335D01*
X630206Y277380D01*
X630211Y277420D01*
X630221Y277460D01*
X630226Y277505D01*
Y277545D01*
X630231Y277590D01*
X630226Y277635D01*
Y277675D01*
X630221Y277720D01*
X630211Y277760D01*
X630206Y277800D01*
X630191Y277845D01*
X630181Y277885D01*
X630166Y277925D01*
X630146Y277965D01*
X630131Y278000D01*
X630111Y278040D01*
X630011Y278180D01*
X629981Y278210D01*
Y281640D01*
X629971Y281765D01*
X629931Y281890D01*
X629871Y282000D01*
X629791Y282100D01*
X629691Y282180D01*
X629581Y282240D01*
X629456Y282280D01*
X629331Y282290D01*
G37*
G36*
G01X634055D02*
X633930Y282280D01*
X633805Y282240D01*
X633695Y282180D01*
X633595Y282100D01*
X633515Y282000D01*
X633455Y281890D01*
X633415Y281765D01*
X633405Y281640D01*
Y278210D01*
X633375Y278180D01*
X633275Y278040D01*
X633255Y278000D01*
X633240Y277965D01*
X633220Y277925D01*
X633205Y277885D01*
X633195Y277845D01*
X633180Y277800D01*
X633175Y277760D01*
X633165Y277720D01*
X633160Y277675D01*
Y277635D01*
X633155Y277590D01*
X633160Y277545D01*
Y277505D01*
X633165Y277460D01*
X633175Y277420D01*
X633180Y277380D01*
X633195Y277335D01*
X633205Y277295D01*
X633220Y277255D01*
X633240Y277215D01*
X633255Y277180D01*
X633275Y277140D01*
X633375Y277000D01*
X633405Y276970D01*
Y275840D01*
X633415Y275715D01*
X633455Y275590D01*
X633515Y275480D01*
X633595Y275380D01*
X633695Y275300D01*
X633805Y275240D01*
X633930Y275200D01*
X634055Y275190D01*
X634180Y275200D01*
X634305Y275240D01*
X634415Y275300D01*
X634515Y275380D01*
X634595Y275480D01*
X634655Y275590D01*
X634695Y275715D01*
X634705Y275840D01*
Y276970D01*
X634735Y277000D01*
X634835Y277140D01*
X634855Y277180D01*
X634870Y277215D01*
X634890Y277255D01*
X634905Y277295D01*
X634915Y277335D01*
X634930Y277380D01*
X634935Y277420D01*
X634945Y277460D01*
X634950Y277505D01*
Y277545D01*
X634955Y277590D01*
X634950Y277635D01*
Y277675D01*
X634945Y277720D01*
X634935Y277760D01*
X634930Y277800D01*
X634915Y277845D01*
X634905Y277885D01*
X634890Y277925D01*
X634870Y277965D01*
X634855Y278000D01*
X634835Y278040D01*
X634735Y278180D01*
X634705Y278210D01*
Y281640D01*
X634695Y281765D01*
X634655Y281890D01*
X634595Y282000D01*
X634515Y282100D01*
X634415Y282180D01*
X634305Y282240D01*
X634180Y282280D01*
X634055Y282290D01*
G37*
G36*
G01X638780D02*
X638655Y282280D01*
X638530Y282240D01*
X638420Y282180D01*
X638320Y282100D01*
X638240Y282000D01*
X638180Y281890D01*
X638140Y281765D01*
X638130Y281640D01*
Y278210D01*
X638100Y278180D01*
X638000Y278040D01*
X637980Y278000D01*
X637965Y277965D01*
X637945Y277925D01*
X637930Y277885D01*
X637920Y277845D01*
X637905Y277800D01*
X637900Y277760D01*
X637890Y277720D01*
X637885Y277675D01*
Y277635D01*
X637880Y277590D01*
X637885Y277545D01*
Y277505D01*
X637890Y277460D01*
X637900Y277420D01*
X637905Y277380D01*
X637920Y277335D01*
X637930Y277295D01*
X637945Y277255D01*
X637965Y277215D01*
X637980Y277180D01*
X638000Y277140D01*
X638100Y277000D01*
X638130Y276970D01*
Y275840D01*
X638140Y275715D01*
X638180Y275590D01*
X638240Y275480D01*
X638320Y275380D01*
X638420Y275300D01*
X638530Y275240D01*
X638655Y275200D01*
X638780Y275190D01*
X638905Y275200D01*
X639030Y275240D01*
X639140Y275300D01*
X639240Y275380D01*
X639320Y275480D01*
X639380Y275590D01*
X639420Y275715D01*
X639430Y275840D01*
Y276970D01*
X639460Y277000D01*
X639560Y277140D01*
X639580Y277180D01*
X639595Y277215D01*
X639615Y277255D01*
X639630Y277295D01*
X639640Y277335D01*
X639655Y277380D01*
X639660Y277420D01*
X639670Y277460D01*
X639675Y277505D01*
Y277545D01*
X639680Y277590D01*
X639675Y277635D01*
Y277675D01*
X639670Y277720D01*
X639660Y277760D01*
X639655Y277800D01*
X639640Y277845D01*
X639630Y277885D01*
X639615Y277925D01*
X639595Y277965D01*
X639580Y278000D01*
X639560Y278040D01*
X639460Y278180D01*
X639430Y278210D01*
Y281640D01*
X639420Y281765D01*
X639380Y281890D01*
X639320Y282000D01*
X639240Y282100D01*
X639140Y282180D01*
X639030Y282240D01*
X638905Y282280D01*
X638780Y282290D01*
G37*
G36*
G01X643504D02*
X643379Y282280D01*
X643254Y282240D01*
X643144Y282180D01*
X643044Y282100D01*
X642964Y282000D01*
X642904Y281890D01*
X642864Y281765D01*
X642854Y281640D01*
Y278210D01*
X642824Y278180D01*
X642724Y278040D01*
X642704Y278000D01*
X642689Y277965D01*
X642669Y277925D01*
X642654Y277885D01*
X642644Y277845D01*
X642629Y277800D01*
X642624Y277760D01*
X642614Y277720D01*
X642609Y277675D01*
Y277635D01*
X642604Y277590D01*
X642609Y277545D01*
Y277505D01*
X642614Y277460D01*
X642624Y277420D01*
X642629Y277380D01*
X642644Y277335D01*
X642654Y277295D01*
X642669Y277255D01*
X642689Y277215D01*
X642704Y277180D01*
X642724Y277140D01*
X642824Y277000D01*
X642854Y276970D01*
Y275840D01*
X642864Y275715D01*
X642904Y275590D01*
X642964Y275480D01*
X643044Y275380D01*
X643144Y275300D01*
X643254Y275240D01*
X643379Y275200D01*
X643504Y275190D01*
X643629Y275200D01*
X643754Y275240D01*
X643864Y275300D01*
X643964Y275380D01*
X644044Y275480D01*
X644104Y275590D01*
X644144Y275715D01*
X644154Y275840D01*
Y276970D01*
X644184Y277000D01*
X644284Y277140D01*
X644304Y277180D01*
X644319Y277215D01*
X644339Y277255D01*
X644354Y277295D01*
X644364Y277335D01*
X644379Y277380D01*
X644384Y277420D01*
X644394Y277460D01*
X644399Y277505D01*
Y277545D01*
X644404Y277590D01*
X644399Y277635D01*
Y277675D01*
X644394Y277720D01*
X644384Y277760D01*
X644379Y277800D01*
X644364Y277845D01*
X644354Y277885D01*
X644339Y277925D01*
X644319Y277965D01*
X644304Y278000D01*
X644284Y278040D01*
X644184Y278180D01*
X644154Y278210D01*
Y281640D01*
X644144Y281765D01*
X644104Y281890D01*
X644044Y282000D01*
X643964Y282100D01*
X643864Y282180D01*
X643754Y282240D01*
X643629Y282280D01*
X643504Y282290D01*
G37*
G36*
G01X648229D02*
X648104Y282280D01*
X647979Y282240D01*
X647869Y282180D01*
X647769Y282100D01*
X647689Y282000D01*
X647629Y281890D01*
X647589Y281765D01*
X647579Y281640D01*
Y278210D01*
X647549Y278180D01*
X647449Y278040D01*
X647429Y278000D01*
X647414Y277965D01*
X647394Y277925D01*
X647379Y277885D01*
X647369Y277845D01*
X647354Y277800D01*
X647349Y277760D01*
X647339Y277720D01*
X647334Y277675D01*
Y277635D01*
X647329Y277590D01*
X647334Y277545D01*
Y277505D01*
X647339Y277460D01*
X647349Y277420D01*
X647354Y277380D01*
X647369Y277335D01*
X647379Y277295D01*
X647394Y277255D01*
X647414Y277215D01*
X647429Y277180D01*
X647449Y277140D01*
X647549Y277000D01*
X647579Y276970D01*
Y275840D01*
X647589Y275715D01*
X647629Y275590D01*
X647689Y275480D01*
X647769Y275380D01*
X647869Y275300D01*
X647979Y275240D01*
X648104Y275200D01*
X648229Y275190D01*
X648354Y275200D01*
X648479Y275240D01*
X648589Y275300D01*
X648689Y275380D01*
X648769Y275480D01*
X648829Y275590D01*
X648869Y275715D01*
X648879Y275840D01*
Y276970D01*
X648909Y277000D01*
X649009Y277140D01*
X649029Y277180D01*
X649044Y277215D01*
X649064Y277255D01*
X649079Y277295D01*
X649089Y277335D01*
X649104Y277380D01*
X649109Y277420D01*
X649119Y277460D01*
X649124Y277505D01*
Y277545D01*
X649129Y277590D01*
X649124Y277635D01*
Y277675D01*
X649119Y277720D01*
X649109Y277760D01*
X649104Y277800D01*
X649089Y277845D01*
X649079Y277885D01*
X649064Y277925D01*
X649044Y277965D01*
X649029Y278000D01*
X649009Y278040D01*
X648909Y278180D01*
X648879Y278210D01*
Y281640D01*
X648869Y281765D01*
X648829Y281890D01*
X648769Y282000D01*
X648689Y282100D01*
X648589Y282180D01*
X648479Y282240D01*
X648354Y282280D01*
X648229Y282290D01*
G37*
G36*
G01X652953D02*
X652828Y282280D01*
X652703Y282240D01*
X652593Y282180D01*
X652493Y282100D01*
X652413Y282000D01*
X652353Y281890D01*
X652313Y281765D01*
X652303Y281640D01*
Y278210D01*
X652273Y278180D01*
X652173Y278040D01*
X652153Y278000D01*
X652138Y277965D01*
X652118Y277925D01*
X652103Y277885D01*
X652093Y277845D01*
X652078Y277800D01*
X652073Y277760D01*
X652063Y277720D01*
X652058Y277675D01*
Y277635D01*
X652053Y277590D01*
X652058Y277545D01*
Y277505D01*
X652063Y277460D01*
X652073Y277420D01*
X652078Y277380D01*
X652093Y277335D01*
X652103Y277295D01*
X652118Y277255D01*
X652138Y277215D01*
X652153Y277180D01*
X652173Y277140D01*
X652273Y277000D01*
X652303Y276970D01*
Y275840D01*
X652313Y275715D01*
X652353Y275590D01*
X652413Y275480D01*
X652493Y275380D01*
X652593Y275300D01*
X652703Y275240D01*
X652828Y275200D01*
X652953Y275190D01*
X653078Y275200D01*
X653203Y275240D01*
X653313Y275300D01*
X653413Y275380D01*
X653493Y275480D01*
X653553Y275590D01*
X653593Y275715D01*
X653603Y275840D01*
Y276970D01*
X653633Y277000D01*
X653733Y277140D01*
X653753Y277180D01*
X653768Y277215D01*
X653788Y277255D01*
X653803Y277295D01*
X653813Y277335D01*
X653828Y277380D01*
X653833Y277420D01*
X653843Y277460D01*
X653848Y277505D01*
Y277545D01*
X653853Y277590D01*
X653848Y277635D01*
Y277675D01*
X653843Y277720D01*
X653833Y277760D01*
X653828Y277800D01*
X653813Y277845D01*
X653803Y277885D01*
X653788Y277925D01*
X653768Y277965D01*
X653753Y278000D01*
X653733Y278040D01*
X653633Y278180D01*
X653603Y278210D01*
Y281640D01*
X653593Y281765D01*
X653553Y281890D01*
X653493Y282000D01*
X653413Y282100D01*
X653313Y282180D01*
X653203Y282240D01*
X653078Y282280D01*
X652953Y282290D01*
G37*
G36*
G01X667126D02*
X667001Y282280D01*
X666876Y282240D01*
X666766Y282180D01*
X666666Y282100D01*
X666586Y282000D01*
X666526Y281890D01*
X666486Y281765D01*
X666476Y281640D01*
Y278210D01*
X666446Y278180D01*
X666346Y278040D01*
X666326Y278000D01*
X666311Y277965D01*
X666291Y277925D01*
X666276Y277885D01*
X666266Y277845D01*
X666251Y277800D01*
X666246Y277760D01*
X666236Y277720D01*
X666231Y277675D01*
Y277635D01*
X666226Y277590D01*
X666231Y277545D01*
Y277505D01*
X666236Y277460D01*
X666246Y277420D01*
X666251Y277380D01*
X666266Y277335D01*
X666276Y277295D01*
X666291Y277255D01*
X666311Y277215D01*
X666326Y277180D01*
X666346Y277140D01*
X666446Y277000D01*
X666476Y276970D01*
Y275840D01*
X666486Y275715D01*
X666526Y275590D01*
X666586Y275480D01*
X666666Y275380D01*
X666766Y275300D01*
X666876Y275240D01*
X667001Y275200D01*
X667126Y275190D01*
X667251Y275200D01*
X667376Y275240D01*
X667486Y275300D01*
X667586Y275380D01*
X667666Y275480D01*
X667726Y275590D01*
X667766Y275715D01*
X667776Y275840D01*
Y276970D01*
X667806Y277000D01*
X667906Y277140D01*
X667926Y277180D01*
X667941Y277215D01*
X667961Y277255D01*
X667976Y277295D01*
X667986Y277335D01*
X668001Y277380D01*
X668006Y277420D01*
X668016Y277460D01*
X668021Y277505D01*
Y277545D01*
X668026Y277590D01*
X668021Y277635D01*
Y277675D01*
X668016Y277720D01*
X668006Y277760D01*
X668001Y277800D01*
X667986Y277845D01*
X667976Y277885D01*
X667961Y277925D01*
X667941Y277965D01*
X667926Y278000D01*
X667906Y278040D01*
X667806Y278180D01*
X667776Y278210D01*
Y281640D01*
X667766Y281765D01*
X667726Y281890D01*
X667666Y282000D01*
X667586Y282100D01*
X667486Y282180D01*
X667376Y282240D01*
X667251Y282280D01*
X667126Y282290D01*
G37*
G36*
G01X671851D02*
X671726Y282280D01*
X671601Y282240D01*
X671491Y282180D01*
X671391Y282100D01*
X671311Y282000D01*
X671251Y281890D01*
X671211Y281765D01*
X671201Y281640D01*
Y278210D01*
X671171Y278180D01*
X671071Y278040D01*
X671051Y278000D01*
X671036Y277965D01*
X671016Y277925D01*
X671001Y277885D01*
X670991Y277845D01*
X670976Y277800D01*
X670971Y277760D01*
X670961Y277720D01*
X670956Y277675D01*
Y277635D01*
X670951Y277590D01*
X670956Y277545D01*
Y277505D01*
X670961Y277460D01*
X670971Y277420D01*
X670976Y277380D01*
X670991Y277335D01*
X671001Y277295D01*
X671016Y277255D01*
X671036Y277215D01*
X671051Y277180D01*
X671071Y277140D01*
X671171Y277000D01*
X671201Y276970D01*
Y275840D01*
X671211Y275715D01*
X671251Y275590D01*
X671311Y275480D01*
X671391Y275380D01*
X671491Y275300D01*
X671601Y275240D01*
X671726Y275200D01*
X671851Y275190D01*
X671976Y275200D01*
X672101Y275240D01*
X672211Y275300D01*
X672311Y275380D01*
X672391Y275480D01*
X672451Y275590D01*
X672491Y275715D01*
X672501Y275840D01*
Y276970D01*
X672531Y277000D01*
X672631Y277140D01*
X672651Y277180D01*
X672666Y277215D01*
X672686Y277255D01*
X672701Y277295D01*
X672711Y277335D01*
X672726Y277380D01*
X672731Y277420D01*
X672741Y277460D01*
X672746Y277505D01*
Y277545D01*
X672751Y277590D01*
X672746Y277635D01*
Y277675D01*
X672741Y277720D01*
X672731Y277760D01*
X672726Y277800D01*
X672711Y277845D01*
X672701Y277885D01*
X672686Y277925D01*
X672666Y277965D01*
X672651Y278000D01*
X672631Y278040D01*
X672531Y278180D01*
X672501Y278210D01*
Y281640D01*
X672491Y281765D01*
X672451Y281890D01*
X672391Y282000D01*
X672311Y282100D01*
X672211Y282180D01*
X672101Y282240D01*
X671976Y282280D01*
X671851Y282290D01*
G37*
G36*
G01X676575D02*
X676450Y282280D01*
X676325Y282240D01*
X676215Y282180D01*
X676115Y282100D01*
X676035Y282000D01*
X675975Y281890D01*
X675935Y281765D01*
X675925Y281640D01*
Y278210D01*
X675895Y278180D01*
X675795Y278040D01*
X675775Y278000D01*
X675760Y277965D01*
X675740Y277925D01*
X675725Y277885D01*
X675715Y277845D01*
X675700Y277800D01*
X675695Y277760D01*
X675685Y277720D01*
X675680Y277675D01*
Y277635D01*
X675675Y277590D01*
X675680Y277545D01*
Y277505D01*
X675685Y277460D01*
X675695Y277420D01*
X675700Y277380D01*
X675715Y277335D01*
X675725Y277295D01*
X675740Y277255D01*
X675760Y277215D01*
X675775Y277180D01*
X675795Y277140D01*
X675895Y277000D01*
X675925Y276970D01*
Y275840D01*
X675935Y275715D01*
X675975Y275590D01*
X676035Y275480D01*
X676115Y275380D01*
X676215Y275300D01*
X676325Y275240D01*
X676450Y275200D01*
X676575Y275190D01*
X676700Y275200D01*
X676825Y275240D01*
X676935Y275300D01*
X677035Y275380D01*
X677115Y275480D01*
X677175Y275590D01*
X677215Y275715D01*
X677225Y275840D01*
Y276970D01*
X677255Y277000D01*
X677355Y277140D01*
X677375Y277180D01*
X677390Y277215D01*
X677410Y277255D01*
X677425Y277295D01*
X677435Y277335D01*
X677450Y277380D01*
X677455Y277420D01*
X677465Y277460D01*
X677470Y277505D01*
Y277545D01*
X677475Y277590D01*
X677470Y277635D01*
Y277675D01*
X677465Y277720D01*
X677455Y277760D01*
X677450Y277800D01*
X677435Y277845D01*
X677425Y277885D01*
X677410Y277925D01*
X677390Y277965D01*
X677375Y278000D01*
X677355Y278040D01*
X677255Y278180D01*
X677225Y278210D01*
Y281640D01*
X677215Y281765D01*
X677175Y281890D01*
X677115Y282000D01*
X677035Y282100D01*
X676935Y282180D01*
X676825Y282240D01*
X676700Y282280D01*
X676575Y282290D01*
G37*
G36*
G01X681299D02*
X681174Y282280D01*
X681049Y282240D01*
X680939Y282180D01*
X680839Y282100D01*
X680759Y282000D01*
X680699Y281890D01*
X680659Y281765D01*
X680649Y281640D01*
Y278210D01*
X680619Y278180D01*
X680519Y278040D01*
X680499Y278000D01*
X680484Y277965D01*
X680464Y277925D01*
X680449Y277885D01*
X680439Y277845D01*
X680424Y277800D01*
X680419Y277760D01*
X680409Y277720D01*
X680404Y277675D01*
Y277635D01*
X680399Y277590D01*
X680404Y277545D01*
Y277505D01*
X680409Y277460D01*
X680419Y277420D01*
X680424Y277380D01*
X680439Y277335D01*
X680449Y277295D01*
X680464Y277255D01*
X680484Y277215D01*
X680499Y277180D01*
X680519Y277140D01*
X680619Y277000D01*
X680649Y276970D01*
Y275840D01*
X680659Y275715D01*
X680699Y275590D01*
X680759Y275480D01*
X680839Y275380D01*
X680939Y275300D01*
X681049Y275240D01*
X681174Y275200D01*
X681299Y275190D01*
X681424Y275200D01*
X681549Y275240D01*
X681659Y275300D01*
X681759Y275380D01*
X681839Y275480D01*
X681899Y275590D01*
X681939Y275715D01*
X681949Y275840D01*
Y276970D01*
X681979Y277000D01*
X682079Y277140D01*
X682099Y277180D01*
X682114Y277215D01*
X682134Y277255D01*
X682149Y277295D01*
X682159Y277335D01*
X682174Y277380D01*
X682179Y277420D01*
X682189Y277460D01*
X682194Y277505D01*
Y277545D01*
X682199Y277590D01*
X682194Y277635D01*
Y277675D01*
X682189Y277720D01*
X682179Y277760D01*
X682174Y277800D01*
X682159Y277845D01*
X682149Y277885D01*
X682134Y277925D01*
X682114Y277965D01*
X682099Y278000D01*
X682079Y278040D01*
X681979Y278180D01*
X681949Y278210D01*
Y281640D01*
X681939Y281765D01*
X681899Y281890D01*
X681839Y282000D01*
X681759Y282100D01*
X681659Y282180D01*
X681549Y282240D01*
X681424Y282280D01*
X681299Y282290D01*
G37*
G36*
G01X686024D02*
X685899Y282280D01*
X685774Y282240D01*
X685664Y282180D01*
X685564Y282100D01*
X685484Y282000D01*
X685424Y281890D01*
X685384Y281765D01*
X685374Y281640D01*
Y278210D01*
X685344Y278180D01*
X685244Y278040D01*
X685224Y278000D01*
X685209Y277965D01*
X685189Y277925D01*
X685174Y277885D01*
X685164Y277845D01*
X685149Y277800D01*
X685144Y277760D01*
X685134Y277720D01*
X685129Y277675D01*
Y277635D01*
X685124Y277590D01*
X685129Y277545D01*
Y277505D01*
X685134Y277460D01*
X685144Y277420D01*
X685149Y277380D01*
X685164Y277335D01*
X685174Y277295D01*
X685189Y277255D01*
X685209Y277215D01*
X685224Y277180D01*
X685244Y277140D01*
X685344Y277000D01*
X685374Y276970D01*
Y275840D01*
X685384Y275715D01*
X685424Y275590D01*
X685484Y275480D01*
X685564Y275380D01*
X685664Y275300D01*
X685774Y275240D01*
X685899Y275200D01*
X686024Y275190D01*
X686149Y275200D01*
X686274Y275240D01*
X686384Y275300D01*
X686484Y275380D01*
X686564Y275480D01*
X686624Y275590D01*
X686664Y275715D01*
X686674Y275840D01*
Y276970D01*
X686704Y277000D01*
X686804Y277140D01*
X686824Y277180D01*
X686839Y277215D01*
X686859Y277255D01*
X686874Y277295D01*
X686884Y277335D01*
X686899Y277380D01*
X686904Y277420D01*
X686914Y277460D01*
X686919Y277505D01*
Y277545D01*
X686924Y277590D01*
X686919Y277635D01*
Y277675D01*
X686914Y277720D01*
X686904Y277760D01*
X686899Y277800D01*
X686884Y277845D01*
X686874Y277885D01*
X686859Y277925D01*
X686839Y277965D01*
X686824Y278000D01*
X686804Y278040D01*
X686704Y278180D01*
X686674Y278210D01*
Y281640D01*
X686664Y281765D01*
X686624Y281890D01*
X686564Y282000D01*
X686484Y282100D01*
X686384Y282180D01*
X686274Y282240D01*
X686149Y282280D01*
X686024Y282290D01*
G37*
G36*
G01X690748D02*
X690623Y282280D01*
X690498Y282240D01*
X690388Y282180D01*
X690288Y282100D01*
X690208Y282000D01*
X690148Y281890D01*
X690108Y281765D01*
X690098Y281640D01*
Y278210D01*
X690068Y278180D01*
X689968Y278040D01*
X689948Y278000D01*
X689933Y277965D01*
X689913Y277925D01*
X689898Y277885D01*
X689888Y277845D01*
X689873Y277800D01*
X689868Y277760D01*
X689858Y277720D01*
X689853Y277675D01*
Y277635D01*
X689848Y277590D01*
X689853Y277545D01*
Y277505D01*
X689858Y277460D01*
X689868Y277420D01*
X689873Y277380D01*
X689888Y277335D01*
X689898Y277295D01*
X689913Y277255D01*
X689933Y277215D01*
X689948Y277180D01*
X689968Y277140D01*
X690068Y277000D01*
X690098Y276970D01*
Y275840D01*
X690108Y275715D01*
X690148Y275590D01*
X690208Y275480D01*
X690288Y275380D01*
X690388Y275300D01*
X690498Y275240D01*
X690623Y275200D01*
X690748Y275190D01*
X690873Y275200D01*
X690998Y275240D01*
X691108Y275300D01*
X691208Y275380D01*
X691288Y275480D01*
X691348Y275590D01*
X691388Y275715D01*
X691398Y275840D01*
Y276970D01*
X691428Y277000D01*
X691528Y277140D01*
X691548Y277180D01*
X691563Y277215D01*
X691583Y277255D01*
X691598Y277295D01*
X691608Y277335D01*
X691623Y277380D01*
X691628Y277420D01*
X691638Y277460D01*
X691643Y277505D01*
Y277545D01*
X691648Y277590D01*
X691643Y277635D01*
Y277675D01*
X691638Y277720D01*
X691628Y277760D01*
X691623Y277800D01*
X691608Y277845D01*
X691598Y277885D01*
X691583Y277925D01*
X691563Y277965D01*
X691548Y278000D01*
X691528Y278040D01*
X691428Y278180D01*
X691398Y278210D01*
Y281640D01*
X691388Y281765D01*
X691348Y281890D01*
X691288Y282000D01*
X691208Y282100D01*
X691108Y282180D01*
X690998Y282240D01*
X690873Y282280D01*
X690748Y282290D01*
G37*
G36*
G01X695473D02*
X695348Y282280D01*
X695223Y282240D01*
X695113Y282180D01*
X695013Y282100D01*
X694933Y282000D01*
X694873Y281890D01*
X694833Y281765D01*
X694823Y281640D01*
Y278210D01*
X694793Y278180D01*
X694693Y278040D01*
X694673Y278000D01*
X694658Y277965D01*
X694638Y277925D01*
X694623Y277885D01*
X694613Y277845D01*
X694598Y277800D01*
X694593Y277760D01*
X694583Y277720D01*
X694578Y277675D01*
Y277635D01*
X694573Y277590D01*
X694578Y277545D01*
Y277505D01*
X694583Y277460D01*
X694593Y277420D01*
X694598Y277380D01*
X694613Y277335D01*
X694623Y277295D01*
X694638Y277255D01*
X694658Y277215D01*
X694673Y277180D01*
X694693Y277140D01*
X694793Y277000D01*
X694823Y276970D01*
Y275840D01*
X694833Y275715D01*
X694873Y275590D01*
X694933Y275480D01*
X695013Y275380D01*
X695113Y275300D01*
X695223Y275240D01*
X695348Y275200D01*
X695473Y275190D01*
X695598Y275200D01*
X695723Y275240D01*
X695833Y275300D01*
X695933Y275380D01*
X696013Y275480D01*
X696073Y275590D01*
X696113Y275715D01*
X696123Y275840D01*
Y276970D01*
X696153Y277000D01*
X696253Y277140D01*
X696273Y277180D01*
X696288Y277215D01*
X696308Y277255D01*
X696323Y277295D01*
X696333Y277335D01*
X696348Y277380D01*
X696353Y277420D01*
X696363Y277460D01*
X696368Y277505D01*
Y277545D01*
X696373Y277590D01*
X696368Y277635D01*
Y277675D01*
X696363Y277720D01*
X696353Y277760D01*
X696348Y277800D01*
X696333Y277845D01*
X696323Y277885D01*
X696308Y277925D01*
X696288Y277965D01*
X696273Y278000D01*
X696253Y278040D01*
X696153Y278180D01*
X696123Y278210D01*
Y281640D01*
X696113Y281765D01*
X696073Y281890D01*
X696013Y282000D01*
X695933Y282100D01*
X695833Y282180D01*
X695723Y282240D01*
X695598Y282280D01*
X695473Y282290D01*
G37*
G36*
G01X700197D02*
X700072Y282280D01*
X699947Y282240D01*
X699837Y282180D01*
X699737Y282100D01*
X699657Y282000D01*
X699597Y281890D01*
X699557Y281765D01*
X699547Y281640D01*
Y278210D01*
X699517Y278180D01*
X699417Y278040D01*
X699397Y278000D01*
X699382Y277965D01*
X699362Y277925D01*
X699347Y277885D01*
X699337Y277845D01*
X699322Y277800D01*
X699317Y277760D01*
X699307Y277720D01*
X699302Y277675D01*
Y277635D01*
X699297Y277590D01*
X699302Y277545D01*
Y277505D01*
X699307Y277460D01*
X699317Y277420D01*
X699322Y277380D01*
X699337Y277335D01*
X699347Y277295D01*
X699362Y277255D01*
X699382Y277215D01*
X699397Y277180D01*
X699417Y277140D01*
X699517Y277000D01*
X699547Y276970D01*
Y275840D01*
X699557Y275715D01*
X699597Y275590D01*
X699657Y275480D01*
X699737Y275380D01*
X699837Y275300D01*
X699947Y275240D01*
X700072Y275200D01*
X700197Y275190D01*
X700322Y275200D01*
X700447Y275240D01*
X700557Y275300D01*
X700657Y275380D01*
X700737Y275480D01*
X700797Y275590D01*
X700837Y275715D01*
X700847Y275840D01*
Y276970D01*
X700877Y277000D01*
X700977Y277140D01*
X700997Y277180D01*
X701012Y277215D01*
X701032Y277255D01*
X701047Y277295D01*
X701057Y277335D01*
X701072Y277380D01*
X701077Y277420D01*
X701087Y277460D01*
X701092Y277505D01*
Y277545D01*
X701097Y277590D01*
X701092Y277635D01*
Y277675D01*
X701087Y277720D01*
X701077Y277760D01*
X701072Y277800D01*
X701057Y277845D01*
X701047Y277885D01*
X701032Y277925D01*
X701012Y277965D01*
X700997Y278000D01*
X700977Y278040D01*
X700877Y278180D01*
X700847Y278210D01*
Y281640D01*
X700837Y281765D01*
X700797Y281890D01*
X700737Y282000D01*
X700657Y282100D01*
X700557Y282180D01*
X700447Y282240D01*
X700322Y282280D01*
X700197Y282290D01*
G37*
G36*
G01X704922D02*
X704797Y282280D01*
X704672Y282240D01*
X704562Y282180D01*
X704462Y282100D01*
X704382Y282000D01*
X704322Y281890D01*
X704282Y281765D01*
X704272Y281640D01*
Y278210D01*
X704242Y278180D01*
X704142Y278040D01*
X704122Y278000D01*
X704107Y277965D01*
X704087Y277925D01*
X704072Y277885D01*
X704062Y277845D01*
X704047Y277800D01*
X704042Y277760D01*
X704032Y277720D01*
X704027Y277675D01*
Y277635D01*
X704022Y277590D01*
X704027Y277545D01*
Y277505D01*
X704032Y277460D01*
X704042Y277420D01*
X704047Y277380D01*
X704062Y277335D01*
X704072Y277295D01*
X704087Y277255D01*
X704107Y277215D01*
X704122Y277180D01*
X704142Y277140D01*
X704242Y277000D01*
X704272Y276970D01*
Y275840D01*
X704282Y275715D01*
X704322Y275590D01*
X704382Y275480D01*
X704462Y275380D01*
X704562Y275300D01*
X704672Y275240D01*
X704797Y275200D01*
X704922Y275190D01*
X705047Y275200D01*
X705172Y275240D01*
X705282Y275300D01*
X705382Y275380D01*
X705462Y275480D01*
X705522Y275590D01*
X705562Y275715D01*
X705572Y275840D01*
Y276970D01*
X705602Y277000D01*
X705702Y277140D01*
X705722Y277180D01*
X705737Y277215D01*
X705757Y277255D01*
X705772Y277295D01*
X705782Y277335D01*
X705797Y277380D01*
X705802Y277420D01*
X705812Y277460D01*
X705817Y277505D01*
Y277545D01*
X705822Y277590D01*
X705817Y277635D01*
Y277675D01*
X705812Y277720D01*
X705802Y277760D01*
X705797Y277800D01*
X705782Y277845D01*
X705772Y277885D01*
X705757Y277925D01*
X705737Y277965D01*
X705722Y278000D01*
X705702Y278040D01*
X705602Y278180D01*
X705572Y278210D01*
Y281640D01*
X705562Y281765D01*
X705522Y281890D01*
X705462Y282000D01*
X705382Y282100D01*
X705282Y282180D01*
X705172Y282240D01*
X705047Y282280D01*
X704922Y282290D01*
G37*
G36*
G01X709646D02*
X709521Y282280D01*
X709396Y282240D01*
X709286Y282180D01*
X709186Y282100D01*
X709106Y282000D01*
X709046Y281890D01*
X709006Y281765D01*
X708996Y281640D01*
Y278210D01*
X708966Y278180D01*
X708866Y278040D01*
X708846Y278000D01*
X708831Y277965D01*
X708811Y277925D01*
X708796Y277885D01*
X708786Y277845D01*
X708771Y277800D01*
X708766Y277760D01*
X708756Y277720D01*
X708751Y277675D01*
Y277635D01*
X708746Y277590D01*
X708751Y277545D01*
Y277505D01*
X708756Y277460D01*
X708766Y277420D01*
X708771Y277380D01*
X708786Y277335D01*
X708796Y277295D01*
X708811Y277255D01*
X708831Y277215D01*
X708846Y277180D01*
X708866Y277140D01*
X708966Y277000D01*
X708996Y276970D01*
Y275840D01*
X709006Y275715D01*
X709046Y275590D01*
X709106Y275480D01*
X709186Y275380D01*
X709286Y275300D01*
X709396Y275240D01*
X709521Y275200D01*
X709646Y275190D01*
X709771Y275200D01*
X709896Y275240D01*
X710006Y275300D01*
X710106Y275380D01*
X710186Y275480D01*
X710246Y275590D01*
X710286Y275715D01*
X710296Y275840D01*
Y276970D01*
X710326Y277000D01*
X710426Y277140D01*
X710446Y277180D01*
X710461Y277215D01*
X710481Y277255D01*
X710496Y277295D01*
X710506Y277335D01*
X710521Y277380D01*
X710526Y277420D01*
X710536Y277460D01*
X710541Y277505D01*
Y277545D01*
X710546Y277590D01*
X710541Y277635D01*
Y277675D01*
X710536Y277720D01*
X710526Y277760D01*
X710521Y277800D01*
X710506Y277845D01*
X710496Y277885D01*
X710481Y277925D01*
X710461Y277965D01*
X710446Y278000D01*
X710426Y278040D01*
X710326Y278180D01*
X710296Y278210D01*
Y281640D01*
X710286Y281765D01*
X710246Y281890D01*
X710186Y282000D01*
X710106Y282100D01*
X710006Y282180D01*
X709896Y282240D01*
X709771Y282280D01*
X709646Y282290D01*
G37*
G36*
G01X714370D02*
X714245Y282280D01*
X714120Y282240D01*
X714010Y282180D01*
X713910Y282100D01*
X713830Y282000D01*
X713770Y281890D01*
X713730Y281765D01*
X713720Y281640D01*
Y278210D01*
X713690Y278180D01*
X713590Y278040D01*
X713570Y278000D01*
X713555Y277965D01*
X713535Y277925D01*
X713520Y277885D01*
X713510Y277845D01*
X713495Y277800D01*
X713490Y277760D01*
X713480Y277720D01*
X713475Y277675D01*
Y277635D01*
X713470Y277590D01*
X713475Y277545D01*
Y277505D01*
X713480Y277460D01*
X713490Y277420D01*
X713495Y277380D01*
X713510Y277335D01*
X713520Y277295D01*
X713535Y277255D01*
X713555Y277215D01*
X713570Y277180D01*
X713590Y277140D01*
X713690Y277000D01*
X713720Y276970D01*
Y275840D01*
X713730Y275715D01*
X713770Y275590D01*
X713830Y275480D01*
X713910Y275380D01*
X714010Y275300D01*
X714120Y275240D01*
X714245Y275200D01*
X714370Y275190D01*
X714495Y275200D01*
X714620Y275240D01*
X714730Y275300D01*
X714830Y275380D01*
X714910Y275480D01*
X714970Y275590D01*
X715010Y275715D01*
X715020Y275840D01*
Y276970D01*
X715050Y277000D01*
X715150Y277140D01*
X715170Y277180D01*
X715185Y277215D01*
X715205Y277255D01*
X715220Y277295D01*
X715230Y277335D01*
X715245Y277380D01*
X715250Y277420D01*
X715260Y277460D01*
X715265Y277505D01*
Y277545D01*
X715270Y277590D01*
X715265Y277635D01*
Y277675D01*
X715260Y277720D01*
X715250Y277760D01*
X715245Y277800D01*
X715230Y277845D01*
X715220Y277885D01*
X715205Y277925D01*
X715185Y277965D01*
X715170Y278000D01*
X715150Y278040D01*
X715050Y278180D01*
X715020Y278210D01*
Y281640D01*
X715010Y281765D01*
X714970Y281890D01*
X714910Y282000D01*
X714830Y282100D01*
X714730Y282180D01*
X714620Y282240D01*
X714495Y282280D01*
X714370Y282290D01*
G37*
G36*
G01X719095D02*
X718970Y282280D01*
X718845Y282240D01*
X718735Y282180D01*
X718635Y282100D01*
X718555Y282000D01*
X718495Y281890D01*
X718455Y281765D01*
X718445Y281640D01*
Y278210D01*
X718415Y278180D01*
X718315Y278040D01*
X718295Y278000D01*
X718280Y277965D01*
X718260Y277925D01*
X718245Y277885D01*
X718235Y277845D01*
X718220Y277800D01*
X718215Y277760D01*
X718205Y277720D01*
X718200Y277675D01*
Y277635D01*
X718195Y277590D01*
X718200Y277545D01*
Y277505D01*
X718205Y277460D01*
X718215Y277420D01*
X718220Y277380D01*
X718235Y277335D01*
X718245Y277295D01*
X718260Y277255D01*
X718280Y277215D01*
X718295Y277180D01*
X718315Y277140D01*
X718415Y277000D01*
X718445Y276970D01*
Y275840D01*
X718455Y275715D01*
X718495Y275590D01*
X718555Y275480D01*
X718635Y275380D01*
X718735Y275300D01*
X718845Y275240D01*
X718970Y275200D01*
X719095Y275190D01*
X719220Y275200D01*
X719345Y275240D01*
X719455Y275300D01*
X719555Y275380D01*
X719635Y275480D01*
X719695Y275590D01*
X719735Y275715D01*
X719745Y275840D01*
Y276970D01*
X719775Y277000D01*
X719875Y277140D01*
X719895Y277180D01*
X719910Y277215D01*
X719930Y277255D01*
X719945Y277295D01*
X719955Y277335D01*
X719970Y277380D01*
X719975Y277420D01*
X719985Y277460D01*
X719990Y277505D01*
Y277545D01*
X719995Y277590D01*
X719990Y277635D01*
Y277675D01*
X719985Y277720D01*
X719975Y277760D01*
X719970Y277800D01*
X719955Y277845D01*
X719945Y277885D01*
X719930Y277925D01*
X719910Y277965D01*
X719895Y278000D01*
X719875Y278040D01*
X719775Y278180D01*
X719745Y278210D01*
Y281640D01*
X719735Y281765D01*
X719695Y281890D01*
X719635Y282000D01*
X719555Y282100D01*
X719455Y282180D01*
X719345Y282240D01*
X719220Y282280D01*
X719095Y282290D01*
G37*
G36*
G01X723819D02*
X723694Y282280D01*
X723569Y282240D01*
X723459Y282180D01*
X723359Y282100D01*
X723279Y282000D01*
X723219Y281890D01*
X723179Y281765D01*
X723169Y281640D01*
Y278210D01*
X723139Y278180D01*
X723039Y278040D01*
X723019Y278000D01*
X723004Y277965D01*
X722984Y277925D01*
X722969Y277885D01*
X722959Y277845D01*
X722944Y277800D01*
X722939Y277760D01*
X722929Y277720D01*
X722924Y277675D01*
Y277635D01*
X722919Y277590D01*
X722924Y277545D01*
Y277505D01*
X722929Y277460D01*
X722939Y277420D01*
X722944Y277380D01*
X722959Y277335D01*
X722969Y277295D01*
X722984Y277255D01*
X723004Y277215D01*
X723019Y277180D01*
X723039Y277140D01*
X723139Y277000D01*
X723169Y276970D01*
Y275840D01*
X723179Y275715D01*
X723219Y275590D01*
X723279Y275480D01*
X723359Y275380D01*
X723459Y275300D01*
X723569Y275240D01*
X723694Y275200D01*
X723819Y275190D01*
X723944Y275200D01*
X724069Y275240D01*
X724179Y275300D01*
X724279Y275380D01*
X724359Y275480D01*
X724419Y275590D01*
X724459Y275715D01*
X724469Y275840D01*
Y276970D01*
X724499Y277000D01*
X724599Y277140D01*
X724619Y277180D01*
X724634Y277215D01*
X724654Y277255D01*
X724669Y277295D01*
X724679Y277335D01*
X724694Y277380D01*
X724699Y277420D01*
X724709Y277460D01*
X724714Y277505D01*
Y277545D01*
X724719Y277590D01*
X724714Y277635D01*
Y277675D01*
X724709Y277720D01*
X724699Y277760D01*
X724694Y277800D01*
X724679Y277845D01*
X724669Y277885D01*
X724654Y277925D01*
X724634Y277965D01*
X724619Y278000D01*
X724599Y278040D01*
X724499Y278180D01*
X724469Y278210D01*
Y281640D01*
X724459Y281765D01*
X724419Y281890D01*
X724359Y282000D01*
X724279Y282100D01*
X724179Y282180D01*
X724069Y282240D01*
X723944Y282280D01*
X723819Y282290D01*
G37*
G36*
G01X728544D02*
X728419Y282280D01*
X728294Y282240D01*
X728184Y282180D01*
X728084Y282100D01*
X728004Y282000D01*
X727944Y281890D01*
X727904Y281765D01*
X727894Y281640D01*
Y278210D01*
X727864Y278180D01*
X727764Y278040D01*
X727744Y278000D01*
X727729Y277965D01*
X727709Y277925D01*
X727694Y277885D01*
X727684Y277845D01*
X727669Y277800D01*
X727664Y277760D01*
X727654Y277720D01*
X727649Y277675D01*
Y277635D01*
X727644Y277590D01*
X727649Y277545D01*
Y277505D01*
X727654Y277460D01*
X727664Y277420D01*
X727669Y277380D01*
X727684Y277335D01*
X727694Y277295D01*
X727709Y277255D01*
X727729Y277215D01*
X727744Y277180D01*
X727764Y277140D01*
X727864Y277000D01*
X727894Y276970D01*
Y275840D01*
X727904Y275715D01*
X727944Y275590D01*
X728004Y275480D01*
X728084Y275380D01*
X728184Y275300D01*
X728294Y275240D01*
X728419Y275200D01*
X728544Y275190D01*
X728669Y275200D01*
X728794Y275240D01*
X728904Y275300D01*
X729004Y275380D01*
X729084Y275480D01*
X729144Y275590D01*
X729184Y275715D01*
X729194Y275840D01*
Y276970D01*
X729224Y277000D01*
X729324Y277140D01*
X729344Y277180D01*
X729359Y277215D01*
X729379Y277255D01*
X729394Y277295D01*
X729404Y277335D01*
X729419Y277380D01*
X729424Y277420D01*
X729434Y277460D01*
X729439Y277505D01*
Y277545D01*
X729444Y277590D01*
X729439Y277635D01*
Y277675D01*
X729434Y277720D01*
X729424Y277760D01*
X729419Y277800D01*
X729404Y277845D01*
X729394Y277885D01*
X729379Y277925D01*
X729359Y277965D01*
X729344Y278000D01*
X729324Y278040D01*
X729224Y278180D01*
X729194Y278210D01*
Y281640D01*
X729184Y281765D01*
X729144Y281890D01*
X729084Y282000D01*
X729004Y282100D01*
X728904Y282180D01*
X728794Y282240D01*
X728669Y282280D01*
X728544Y282290D01*
G37*
G36*
G01X733268D02*
X733143Y282280D01*
X733018Y282240D01*
X732908Y282180D01*
X732808Y282100D01*
X732728Y282000D01*
X732668Y281890D01*
X732628Y281765D01*
X732618Y281640D01*
Y278210D01*
X732588Y278180D01*
X732488Y278040D01*
X732468Y278000D01*
X732453Y277965D01*
X732433Y277925D01*
X732418Y277885D01*
X732408Y277845D01*
X732393Y277800D01*
X732388Y277760D01*
X732378Y277720D01*
X732373Y277675D01*
Y277635D01*
X732368Y277590D01*
X732373Y277545D01*
Y277505D01*
X732378Y277460D01*
X732388Y277420D01*
X732393Y277380D01*
X732408Y277335D01*
X732418Y277295D01*
X732433Y277255D01*
X732453Y277215D01*
X732468Y277180D01*
X732488Y277140D01*
X732588Y277000D01*
X732618Y276970D01*
Y275840D01*
X732628Y275715D01*
X732668Y275590D01*
X732728Y275480D01*
X732808Y275380D01*
X732908Y275300D01*
X733018Y275240D01*
X733143Y275200D01*
X733268Y275190D01*
X733393Y275200D01*
X733518Y275240D01*
X733628Y275300D01*
X733728Y275380D01*
X733808Y275480D01*
X733868Y275590D01*
X733908Y275715D01*
X733918Y275840D01*
Y276970D01*
X733948Y277000D01*
X734048Y277140D01*
X734068Y277180D01*
X734083Y277215D01*
X734103Y277255D01*
X734118Y277295D01*
X734128Y277335D01*
X734143Y277380D01*
X734148Y277420D01*
X734158Y277460D01*
X734163Y277505D01*
Y277545D01*
X734168Y277590D01*
X734163Y277635D01*
Y277675D01*
X734158Y277720D01*
X734148Y277760D01*
X734143Y277800D01*
X734128Y277845D01*
X734118Y277885D01*
X734103Y277925D01*
X734083Y277965D01*
X734068Y278000D01*
X734048Y278040D01*
X733948Y278180D01*
X733918Y278210D01*
Y281640D01*
X733908Y281765D01*
X733868Y281890D01*
X733808Y282000D01*
X733728Y282100D01*
X733628Y282180D01*
X733518Y282240D01*
X733393Y282280D01*
X733268Y282290D01*
G37*
G36*
G01X737992D02*
X737867Y282280D01*
X737742Y282240D01*
X737632Y282180D01*
X737532Y282100D01*
X737452Y282000D01*
X737392Y281890D01*
X737352Y281765D01*
X737342Y281640D01*
Y278210D01*
X737312Y278180D01*
X737212Y278040D01*
X737192Y278000D01*
X737177Y277965D01*
X737157Y277925D01*
X737142Y277885D01*
X737132Y277845D01*
X737117Y277800D01*
X737112Y277760D01*
X737102Y277720D01*
X737097Y277675D01*
Y277635D01*
X737092Y277590D01*
X737097Y277545D01*
Y277505D01*
X737102Y277460D01*
X737112Y277420D01*
X737117Y277380D01*
X737132Y277335D01*
X737142Y277295D01*
X737157Y277255D01*
X737177Y277215D01*
X737192Y277180D01*
X737212Y277140D01*
X737312Y277000D01*
X737342Y276970D01*
Y275840D01*
X737352Y275715D01*
X737392Y275590D01*
X737452Y275480D01*
X737532Y275380D01*
X737632Y275300D01*
X737742Y275240D01*
X737867Y275200D01*
X737992Y275190D01*
X738117Y275200D01*
X738242Y275240D01*
X738352Y275300D01*
X738452Y275380D01*
X738532Y275480D01*
X738592Y275590D01*
X738632Y275715D01*
X738642Y275840D01*
Y276970D01*
X738672Y277000D01*
X738772Y277140D01*
X738792Y277180D01*
X738807Y277215D01*
X738827Y277255D01*
X738842Y277295D01*
X738852Y277335D01*
X738867Y277380D01*
X738872Y277420D01*
X738882Y277460D01*
X738887Y277505D01*
Y277545D01*
X738892Y277590D01*
X738887Y277635D01*
Y277675D01*
X738882Y277720D01*
X738872Y277760D01*
X738867Y277800D01*
X738852Y277845D01*
X738842Y277885D01*
X738827Y277925D01*
X738807Y277965D01*
X738792Y278000D01*
X738772Y278040D01*
X738672Y278180D01*
X738642Y278210D01*
Y281640D01*
X738632Y281765D01*
X738592Y281890D01*
X738532Y282000D01*
X738452Y282100D01*
X738352Y282180D01*
X738242Y282240D01*
X738117Y282280D01*
X737992Y282290D01*
G37*
G36*
G01X742717D02*
X742592Y282280D01*
X742467Y282240D01*
X742357Y282180D01*
X742257Y282100D01*
X742177Y282000D01*
X742117Y281890D01*
X742077Y281765D01*
X742067Y281640D01*
Y278210D01*
X742037Y278180D01*
X741937Y278040D01*
X741917Y278000D01*
X741902Y277965D01*
X741882Y277925D01*
X741867Y277885D01*
X741857Y277845D01*
X741842Y277800D01*
X741837Y277760D01*
X741827Y277720D01*
X741822Y277675D01*
Y277635D01*
X741817Y277590D01*
X741822Y277545D01*
Y277505D01*
X741827Y277460D01*
X741837Y277420D01*
X741842Y277380D01*
X741857Y277335D01*
X741867Y277295D01*
X741882Y277255D01*
X741902Y277215D01*
X741917Y277180D01*
X741937Y277140D01*
X742037Y277000D01*
X742067Y276970D01*
Y275840D01*
X742077Y275715D01*
X742117Y275590D01*
X742177Y275480D01*
X742257Y275380D01*
X742357Y275300D01*
X742467Y275240D01*
X742592Y275200D01*
X742717Y275190D01*
X742842Y275200D01*
X742967Y275240D01*
X743077Y275300D01*
X743177Y275380D01*
X743257Y275480D01*
X743317Y275590D01*
X743357Y275715D01*
X743367Y275840D01*
Y276970D01*
X743397Y277000D01*
X743497Y277140D01*
X743517Y277180D01*
X743532Y277215D01*
X743552Y277255D01*
X743567Y277295D01*
X743577Y277335D01*
X743592Y277380D01*
X743597Y277420D01*
X743607Y277460D01*
X743612Y277505D01*
Y277545D01*
X743617Y277590D01*
X743612Y277635D01*
Y277675D01*
X743607Y277720D01*
X743597Y277760D01*
X743592Y277800D01*
X743577Y277845D01*
X743567Y277885D01*
X743552Y277925D01*
X743532Y277965D01*
X743517Y278000D01*
X743497Y278040D01*
X743397Y278180D01*
X743367Y278210D01*
Y281640D01*
X743357Y281765D01*
X743317Y281890D01*
X743257Y282000D01*
X743177Y282100D01*
X743077Y282180D01*
X742967Y282240D01*
X742842Y282280D01*
X742717Y282290D01*
G37*
G36*
G01X747441D02*
X747316Y282280D01*
X747191Y282240D01*
X747081Y282180D01*
X746981Y282100D01*
X746901Y282000D01*
X746841Y281890D01*
X746801Y281765D01*
X746791Y281640D01*
Y278210D01*
X746761Y278180D01*
X746661Y278040D01*
X746641Y278000D01*
X746626Y277965D01*
X746606Y277925D01*
X746591Y277885D01*
X746581Y277845D01*
X746566Y277800D01*
X746561Y277760D01*
X746551Y277720D01*
X746546Y277675D01*
Y277635D01*
X746541Y277590D01*
X746546Y277545D01*
Y277505D01*
X746551Y277460D01*
X746561Y277420D01*
X746566Y277380D01*
X746581Y277335D01*
X746591Y277295D01*
X746606Y277255D01*
X746626Y277215D01*
X746641Y277180D01*
X746661Y277140D01*
X746761Y277000D01*
X746791Y276970D01*
Y275840D01*
X746801Y275715D01*
X746841Y275590D01*
X746901Y275480D01*
X746981Y275380D01*
X747081Y275300D01*
X747191Y275240D01*
X747316Y275200D01*
X747441Y275190D01*
X747566Y275200D01*
X747691Y275240D01*
X747801Y275300D01*
X747901Y275380D01*
X747981Y275480D01*
X748041Y275590D01*
X748081Y275715D01*
X748091Y275840D01*
Y276970D01*
X748121Y277000D01*
X748221Y277140D01*
X748241Y277180D01*
X748256Y277215D01*
X748276Y277255D01*
X748291Y277295D01*
X748301Y277335D01*
X748316Y277380D01*
X748321Y277420D01*
X748331Y277460D01*
X748336Y277505D01*
Y277545D01*
X748341Y277590D01*
X748336Y277635D01*
Y277675D01*
X748331Y277720D01*
X748321Y277760D01*
X748316Y277800D01*
X748301Y277845D01*
X748291Y277885D01*
X748276Y277925D01*
X748256Y277965D01*
X748241Y278000D01*
X748221Y278040D01*
X748121Y278180D01*
X748091Y278210D01*
Y281640D01*
X748081Y281765D01*
X748041Y281890D01*
X747981Y282000D01*
X747901Y282100D01*
X747801Y282180D01*
X747691Y282240D01*
X747566Y282280D01*
X747441Y282290D01*
G37*
G54D64*
X276811Y263386D03*
X296811D03*
X457913Y45276D03*
X477913D03*
G54D28*
X42717Y270472D03*
X235630Y75590D03*
X492520Y262598D03*
D03*
X761417Y22798D03*
D03*
G54D37*
X94900Y193000D03*
X100100D03*
X120900Y121000D03*
X126100D03*
X154900Y157500D03*
X142900Y190500D03*
X148100D03*
X160100Y157500D03*
X192900Y115200D03*
X198100D03*
X262400Y65500D03*
X261400Y83000D03*
X267600Y65500D03*
X266600Y83000D03*
X300400Y77700D03*
X305600D03*
X334400Y131000D03*
X339600D03*
X338360Y150400D03*
X343560D03*
X370396Y68063D03*
X370400Y73200D03*
X368400Y175650D03*
X375596Y68063D03*
X375600Y73200D03*
X373600Y175650D03*
X508900Y46507D03*
X514100D03*
X725900Y59000D03*
Y54000D03*
X731100Y59000D03*
Y54000D03*
X775900Y6500D03*
X781100D03*
X775900Y11700D03*
X781100D03*
X799400Y252300D03*
Y257300D03*
Y262500D03*
X804600Y252300D03*
Y257300D03*
Y262500D03*
G54D19*
X25700Y131500D03*
X22300D03*
X64200Y94500D03*
X60800D03*
X64300Y135500D03*
Y138500D03*
X78800Y110000D03*
X67700Y135500D03*
Y138500D03*
X74900Y238700D03*
X71500D03*
X82200Y110000D03*
X138200Y67000D03*
X134800D03*
X138200Y64000D03*
X134800D03*
X132200Y169000D03*
X128800D03*
X138600Y192500D03*
X135200D03*
X147200Y112000D03*
X143800D03*
X155200Y195300D03*
X151800D03*
X155200Y198300D03*
X151800D03*
X147200Y194500D03*
X143800D03*
X155300Y257000D03*
X163700Y57500D03*
X160300D03*
X171400Y113200D03*
X168000D03*
X171300Y213000D03*
X158700Y257000D03*
X177300Y61300D03*
X173900D03*
X174700Y213000D03*
X193200Y57500D03*
X189800D03*
X200300Y195000D03*
X202300Y230500D03*
X203700Y195000D03*
X205700Y230500D03*
X261400Y73100D03*
X258000D03*
X263800Y70000D03*
X262200Y146300D03*
X267200Y70000D03*
X265600Y146300D03*
X274200Y247500D03*
X270800D03*
X291900Y90600D03*
X288500D03*
X285200Y95000D03*
X281800D03*
X292300Y97600D03*
X293200Y113000D03*
X289800D03*
X293200Y116000D03*
X289800D03*
X293200Y110000D03*
X289800D03*
X293200Y119000D03*
X289800D03*
X293200Y128000D03*
X289800D03*
X293200Y122000D03*
X289800D03*
X293200Y125000D03*
X289800D03*
X293200Y131000D03*
X289800D03*
X293200Y144500D03*
X289800D03*
X293200Y147500D03*
X289800D03*
X293700Y160500D03*
X290300D03*
X293700Y164000D03*
X290300D03*
X293700Y174000D03*
X290300D03*
X293700Y168000D03*
X290300D03*
X293700Y177500D03*
X290300D03*
X293700Y171000D03*
X290300D03*
X293700Y181500D03*
X290300D03*
X293300Y196500D03*
Y193500D03*
X295700Y97600D03*
X307800Y151300D03*
X296700Y196500D03*
Y193500D03*
X321700Y106500D03*
X318300D03*
X317700Y129200D03*
X314300D03*
X311200Y151300D03*
X340700Y84500D03*
X337300D03*
X337200Y125000D03*
X333800D03*
X341300Y181000D03*
X333700Y254000D03*
X330300D03*
X346150Y159200D03*
X342750D03*
X344700Y181000D03*
X392200Y81000D03*
X388800D03*
X397200Y227500D03*
X393800D03*
X415950Y175623D03*
X419350D03*
X444200Y127063D03*
X440800D03*
X458700Y252000D03*
X455300D03*
X530700Y191500D03*
X527300D03*
X530700Y188500D03*
X527300D03*
X557200Y179000D03*
X553800D03*
X570300Y187000D03*
X566900D03*
X638200Y285000D03*
X634800D03*
X736200Y105500D03*
X732800D03*
X738000Y134100D03*
X734600D03*
X748100Y50007D03*
X744700D03*
X751600Y46507D03*
X748200D03*
X778700Y139000D03*
X775300D03*
X778200Y260000D03*
X774800D03*
X778200Y266000D03*
X774800D03*
X778200Y263000D03*
X774800D03*
G54D46*
X144000Y67875D03*
Y147125D03*
G54D92*
X517000Y102100D03*
X513000D03*
X515000Y96900D03*
X770700Y149600D03*
X766700D03*
X768700Y144400D03*
G54D83*
X500787Y70042D03*
X494882Y215354D03*
X759055Y70042D03*
X753150Y215354D03*
G54D47*
X157545Y73450D03*
X159515D03*
X161485D03*
X163455D03*
X165425D03*
X167395D03*
X169365D03*
X171335D03*
X169365Y101750D03*
X167395D03*
X165425D03*
X163455D03*
X161485D03*
X159515D03*
X157545D03*
X171335D03*
X173305Y73450D03*
X175275D03*
X177245D03*
X179215D03*
X181185D03*
X183155D03*
X185125D03*
X187095D03*
Y101750D03*
X185125D03*
X183155D03*
X181185D03*
X179215D03*
X177245D03*
X175275D03*
X173305D03*
X191035Y73450D03*
X193005D03*
X194975D03*
X196945D03*
X198915D03*
X200885D03*
X189065D03*
X200885Y101750D03*
X198915D03*
X196945D03*
X194975D03*
X193005D03*
X191035D03*
X189065D03*
X202855Y73450D03*
Y101750D03*
G54D74*
X372426Y258500D03*
Y256531D03*
Y254563D03*
Y252594D03*
Y250626D03*
Y248657D03*
Y268343D03*
Y266374D03*
Y264406D03*
Y262437D03*
Y260469D03*
X387574Y248657D03*
Y250626D03*
Y252594D03*
Y254563D03*
Y256531D03*
Y258500D03*
Y260469D03*
Y262437D03*
Y264406D03*
Y266374D03*
Y268343D03*
G54D56*
X231760Y48820D03*
Y56180D03*
X226640D03*
Y48820D03*
X229200D03*
X274560Y145320D03*
Y152680D03*
X269440D03*
Y145320D03*
X272000D03*
X438940Y24820D03*
X444060D03*
X438940Y32180D03*
X444060D03*
X441500D03*
G54D38*
X81500Y234500D03*
X127000Y209500D03*
X154000Y118500D03*
X150500Y177000D03*
X160000Y165000D03*
X161000Y203000D03*
X212500Y169500D03*
X259000Y52000D03*
X262000D03*
X353000Y146500D03*
X356000Y158600D03*
Y180000D03*
X352500Y174000D03*
X359000Y145800D03*
X370742Y139924D03*
X361300Y162200D03*
X364300Y159850D03*
X359000Y168000D03*
Y180000D03*
X371500Y187600D03*
X376390Y187650D03*
X385500Y200700D03*
X389500Y150463D03*
X401866Y162000D03*
X396142Y165024D03*
X400500Y201063D03*
X395000Y267500D03*
X406500Y68500D03*
X411500Y130000D03*
X403500Y201063D03*
X406500D03*
X409500D03*
X424500Y160000D03*
X420000Y206000D03*
X423000Y206063D03*
X517000Y56507D03*
X626500Y47507D03*
X633300D03*
X636600D03*
X661500Y48107D03*
X658500D03*
X664500D03*
X735000Y66500D03*
X739300Y109000D03*
G54D29*
X60433Y24392D03*
X68307D03*
X72244D03*
X76181D03*
X80118D03*
X84055D03*
X87992D03*
X91929D03*
X95866D03*
X99803D03*
X103740D03*
X107677D03*
X111614D03*
X115551D03*
X119488D03*
X123425D03*
X127362D03*
X131299D03*
X135236D03*
X139173D03*
X143110D03*
X147047D03*
X150984D03*
X154921D03*
X158858D03*
X162795D03*
X166732D03*
X170669D03*
X174606D03*
X178543D03*
X182480D03*
X186417D03*
X190354D03*
X194291D03*
X198228D03*
X202165D03*
X206102D03*
X210039D03*
X213976D03*
X217913D03*
X221850D03*
X225787D03*
X229724D03*
X233661D03*
X237598D03*
X241535D03*
X245472D03*
X249409D03*
X253346D03*
X257283D03*
X261220D03*
X265157D03*
X269094D03*
X273031D03*
X276968D03*
X280905D03*
X284842D03*
X288779D03*
X292716D03*
X296653D03*
X300590D03*
X304527D03*
X308464D03*
X312401D03*
X316338D03*
X320275D03*
X324212D03*
X328149D03*
X332086D03*
X336023D03*
X347835D03*
X351772D03*
X355709D03*
X359646D03*
X363583D03*
X367520D03*
X371457D03*
X375394D03*
X379331D03*
X383268D03*
X387205D03*
G54D65*
X283279Y103321D03*
X297500Y118600D03*
X298500Y129500D03*
X317000Y139600D03*
X338000Y171500D03*
X370700Y165000D03*
X371700Y156440D03*
X375100Y118700D03*
X373500Y114063D03*
Y109063D03*
X375000Y123563D03*
X377700Y152300D03*
X386938Y146572D03*
X376300Y160900D03*
X379700Y157450D03*
X375300Y166545D03*
X384400Y156400D03*
X389624Y140246D03*
X407492Y164734D03*
X412000Y168200D03*
G54D66*
X286900Y208000D03*
Y204000D03*
X292100Y206000D03*
G54D75*
X375079Y245020D03*
X384921D03*
X377047D03*
X379016D03*
X380984D03*
X382953D03*
X375079Y271980D03*
X384921D03*
X382953D03*
X380984D03*
X379016D03*
X377047D03*
G54D93*
X762000Y163331D03*
Y154669D03*
G54D39*
X81500Y237500D03*
X127000Y212500D03*
X154000Y121500D03*
X150500Y180000D03*
X160000Y168000D03*
X161000Y206000D03*
X212500Y172500D03*
X259000Y55000D03*
X262000D03*
X353000Y149500D03*
X356000Y161600D03*
Y183000D03*
X352500Y177000D03*
X359000Y148800D03*
X370742Y142924D03*
X361300Y165200D03*
X364300Y162850D03*
X359000Y171000D03*
Y183000D03*
X371500Y190600D03*
X376390Y190650D03*
X385500Y203700D03*
X401866Y165000D03*
X389500Y153463D03*
X396142Y168024D03*
X400500Y204063D03*
X395000Y270500D03*
X406500Y71500D03*
X411500Y133000D03*
X403500Y204063D03*
X406500D03*
X409500D03*
X424500Y163000D03*
X420000Y209000D03*
X423000Y209063D03*
X517000Y59507D03*
X626500Y50507D03*
X633300D03*
X636600D03*
X661500Y51107D03*
X658500D03*
X664500D03*
X735000Y69500D03*
X739300Y112000D03*
G54D57*
X235630Y174016D03*
X498425Y22798D03*
D03*
X755512Y262598D03*
D03*
G54D48*
X169085Y183848D03*
Y201170D03*
X192007Y183848D03*
Y201170D03*
G36*
G01X508858Y3106D02*
X508983Y3116D01*
X509108Y3156D01*
X509218Y3216D01*
X509318Y3296D01*
X509398Y3396D01*
X509458Y3506D01*
X509498Y3631D01*
X509508Y3756D01*
Y6186D01*
X509538Y6216D01*
X509638Y6356D01*
X509658Y6396D01*
X509673Y6431D01*
X509693Y6471D01*
X509708Y6511D01*
X509718Y6551D01*
X509733Y6596D01*
X509738Y6636D01*
X509748Y6676D01*
X509753Y6721D01*
Y6761D01*
X509758Y6806D01*
X509753Y6851D01*
Y6891D01*
X509748Y6936D01*
X509738Y6976D01*
X509733Y7016D01*
X509718Y7061D01*
X509708Y7101D01*
X509693Y7141D01*
X509673Y7181D01*
X509658Y7216D01*
X509638Y7256D01*
X509538Y7396D01*
X509508Y7426D01*
Y9556D01*
X509498Y9681D01*
X509458Y9806D01*
X509398Y9916D01*
X509318Y10016D01*
X509218Y10096D01*
X509108Y10156D01*
X508983Y10196D01*
X508858Y10206D01*
X508733Y10196D01*
X508608Y10156D01*
X508498Y10096D01*
X508398Y10016D01*
X508318Y9916D01*
X508258Y9806D01*
X508218Y9681D01*
X508208Y9556D01*
Y7431D01*
X508178Y7401D01*
X508153Y7366D01*
X508123Y7331D01*
X508103Y7296D01*
X508078Y7261D01*
X508038Y7181D01*
X507993Y7061D01*
X507983Y7021D01*
X507973Y6976D01*
X507968Y6936D01*
X507958Y6891D01*
Y6721D01*
X507968Y6676D01*
X507973Y6636D01*
X507983Y6591D01*
X507993Y6551D01*
X508038Y6431D01*
X508078Y6351D01*
X508103Y6316D01*
X508123Y6281D01*
X508153Y6246D01*
X508178Y6211D01*
X508208Y6181D01*
Y3756D01*
X508218Y3631D01*
X508258Y3506D01*
X508318Y3396D01*
X508398Y3296D01*
X508498Y3216D01*
X508608Y3156D01*
X508733Y3116D01*
X508858Y3106D01*
G37*
G36*
G01X523031D02*
X523156Y3116D01*
X523281Y3156D01*
X523391Y3216D01*
X523491Y3296D01*
X523571Y3396D01*
X523631Y3506D01*
X523671Y3631D01*
X523681Y3756D01*
Y6186D01*
X523711Y6216D01*
X523811Y6356D01*
X523831Y6396D01*
X523846Y6431D01*
X523866Y6471D01*
X523881Y6511D01*
X523891Y6551D01*
X523906Y6596D01*
X523911Y6636D01*
X523921Y6676D01*
X523926Y6721D01*
Y6761D01*
X523931Y6806D01*
X523926Y6851D01*
Y6891D01*
X523921Y6936D01*
X523911Y6976D01*
X523906Y7016D01*
X523891Y7061D01*
X523881Y7101D01*
X523866Y7141D01*
X523846Y7181D01*
X523831Y7216D01*
X523811Y7256D01*
X523711Y7396D01*
X523681Y7426D01*
Y9556D01*
X523671Y9681D01*
X523631Y9806D01*
X523571Y9916D01*
X523491Y10016D01*
X523391Y10096D01*
X523281Y10156D01*
X523156Y10196D01*
X523031Y10206D01*
X522906Y10196D01*
X522781Y10156D01*
X522671Y10096D01*
X522571Y10016D01*
X522491Y9916D01*
X522431Y9806D01*
X522391Y9681D01*
X522381Y9556D01*
Y7431D01*
X522351Y7401D01*
X522326Y7366D01*
X522296Y7331D01*
X522276Y7296D01*
X522251Y7261D01*
X522211Y7181D01*
X522166Y7061D01*
X522156Y7021D01*
X522146Y6976D01*
X522141Y6936D01*
X522131Y6891D01*
Y6721D01*
X522141Y6676D01*
X522146Y6636D01*
X522156Y6591D01*
X522166Y6551D01*
X522211Y6431D01*
X522251Y6351D01*
X522276Y6316D01*
X522296Y6281D01*
X522326Y6246D01*
X522351Y6211D01*
X522381Y6181D01*
Y3756D01*
X522391Y3631D01*
X522431Y3506D01*
X522491Y3396D01*
X522571Y3296D01*
X522671Y3216D01*
X522781Y3156D01*
X522906Y3116D01*
X523031Y3106D01*
G37*
G36*
G01X518307D02*
X518432Y3116D01*
X518557Y3156D01*
X518667Y3216D01*
X518767Y3296D01*
X518847Y3396D01*
X518907Y3506D01*
X518947Y3631D01*
X518957Y3756D01*
Y6186D01*
X518987Y6216D01*
X519087Y6356D01*
X519107Y6396D01*
X519122Y6431D01*
X519142Y6471D01*
X519157Y6511D01*
X519167Y6551D01*
X519182Y6596D01*
X519187Y6636D01*
X519197Y6676D01*
X519202Y6721D01*
Y6761D01*
X519207Y6806D01*
X519202Y6851D01*
Y6891D01*
X519197Y6936D01*
X519187Y6976D01*
X519182Y7016D01*
X519167Y7061D01*
X519157Y7101D01*
X519142Y7141D01*
X519122Y7181D01*
X519107Y7216D01*
X519087Y7256D01*
X518987Y7396D01*
X518957Y7426D01*
Y9556D01*
X518947Y9681D01*
X518907Y9806D01*
X518847Y9916D01*
X518767Y10016D01*
X518667Y10096D01*
X518557Y10156D01*
X518432Y10196D01*
X518307Y10206D01*
X518182Y10196D01*
X518057Y10156D01*
X517947Y10096D01*
X517847Y10016D01*
X517767Y9916D01*
X517707Y9806D01*
X517667Y9681D01*
X517657Y9556D01*
Y7431D01*
X517627Y7401D01*
X517602Y7366D01*
X517572Y7331D01*
X517552Y7296D01*
X517527Y7261D01*
X517487Y7181D01*
X517442Y7061D01*
X517432Y7021D01*
X517422Y6976D01*
X517417Y6936D01*
X517407Y6891D01*
Y6721D01*
X517417Y6676D01*
X517422Y6636D01*
X517432Y6591D01*
X517442Y6551D01*
X517487Y6431D01*
X517527Y6351D01*
X517552Y6316D01*
X517572Y6281D01*
X517602Y6246D01*
X517627Y6211D01*
X517657Y6181D01*
Y3756D01*
X517667Y3631D01*
X517707Y3506D01*
X517767Y3396D01*
X517847Y3296D01*
X517947Y3216D01*
X518057Y3156D01*
X518182Y3116D01*
X518307Y3106D01*
G37*
G36*
G01X513582D02*
X513707Y3116D01*
X513832Y3156D01*
X513942Y3216D01*
X514042Y3296D01*
X514122Y3396D01*
X514182Y3506D01*
X514222Y3631D01*
X514232Y3756D01*
Y6186D01*
X514262Y6216D01*
X514362Y6356D01*
X514382Y6396D01*
X514397Y6431D01*
X514417Y6471D01*
X514432Y6511D01*
X514442Y6551D01*
X514457Y6596D01*
X514462Y6636D01*
X514472Y6676D01*
X514477Y6721D01*
Y6761D01*
X514482Y6806D01*
X514477Y6851D01*
Y6891D01*
X514472Y6936D01*
X514462Y6976D01*
X514457Y7016D01*
X514442Y7061D01*
X514432Y7101D01*
X514417Y7141D01*
X514397Y7181D01*
X514382Y7216D01*
X514362Y7256D01*
X514262Y7396D01*
X514232Y7426D01*
Y9556D01*
X514222Y9681D01*
X514182Y9806D01*
X514122Y9916D01*
X514042Y10016D01*
X513942Y10096D01*
X513832Y10156D01*
X513707Y10196D01*
X513582Y10206D01*
X513457Y10196D01*
X513332Y10156D01*
X513222Y10096D01*
X513122Y10016D01*
X513042Y9916D01*
X512982Y9806D01*
X512942Y9681D01*
X512932Y9556D01*
Y7431D01*
X512902Y7401D01*
X512877Y7366D01*
X512847Y7331D01*
X512827Y7296D01*
X512802Y7261D01*
X512762Y7181D01*
X512717Y7061D01*
X512707Y7021D01*
X512697Y6976D01*
X512692Y6936D01*
X512682Y6891D01*
Y6721D01*
X512692Y6676D01*
X512697Y6636D01*
X512707Y6591D01*
X512717Y6551D01*
X512762Y6431D01*
X512802Y6351D01*
X512827Y6316D01*
X512847Y6281D01*
X512877Y6246D01*
X512902Y6211D01*
X512932Y6181D01*
Y3756D01*
X512942Y3631D01*
X512982Y3506D01*
X513042Y3396D01*
X513122Y3296D01*
X513222Y3216D01*
X513332Y3156D01*
X513457Y3116D01*
X513582Y3106D01*
G37*
G36*
G01X541929D02*
X542054Y3116D01*
X542179Y3156D01*
X542289Y3216D01*
X542389Y3296D01*
X542469Y3396D01*
X542529Y3506D01*
X542569Y3631D01*
X542579Y3756D01*
Y6186D01*
X542609Y6216D01*
X542709Y6356D01*
X542729Y6396D01*
X542744Y6431D01*
X542764Y6471D01*
X542779Y6511D01*
X542789Y6551D01*
X542804Y6596D01*
X542809Y6636D01*
X542819Y6676D01*
X542824Y6721D01*
Y6761D01*
X542829Y6806D01*
X542824Y6851D01*
Y6891D01*
X542819Y6936D01*
X542809Y6976D01*
X542804Y7016D01*
X542789Y7061D01*
X542779Y7101D01*
X542764Y7141D01*
X542744Y7181D01*
X542729Y7216D01*
X542709Y7256D01*
X542609Y7396D01*
X542579Y7426D01*
Y9556D01*
X542569Y9681D01*
X542529Y9806D01*
X542469Y9916D01*
X542389Y10016D01*
X542289Y10096D01*
X542179Y10156D01*
X542054Y10196D01*
X541929Y10206D01*
X541804Y10196D01*
X541679Y10156D01*
X541569Y10096D01*
X541469Y10016D01*
X541389Y9916D01*
X541329Y9806D01*
X541289Y9681D01*
X541279Y9556D01*
Y7431D01*
X541249Y7401D01*
X541224Y7366D01*
X541194Y7331D01*
X541174Y7296D01*
X541149Y7261D01*
X541109Y7181D01*
X541064Y7061D01*
X541054Y7021D01*
X541044Y6976D01*
X541039Y6936D01*
X541029Y6891D01*
Y6721D01*
X541039Y6676D01*
X541044Y6636D01*
X541054Y6591D01*
X541064Y6551D01*
X541109Y6431D01*
X541149Y6351D01*
X541174Y6316D01*
X541194Y6281D01*
X541224Y6246D01*
X541249Y6211D01*
X541279Y6181D01*
Y3756D01*
X541289Y3631D01*
X541329Y3506D01*
X541389Y3396D01*
X541469Y3296D01*
X541569Y3216D01*
X541679Y3156D01*
X541804Y3116D01*
X541929Y3106D01*
G37*
G36*
G01X537204D02*
X537329Y3116D01*
X537454Y3156D01*
X537564Y3216D01*
X537664Y3296D01*
X537744Y3396D01*
X537804Y3506D01*
X537844Y3631D01*
X537854Y3756D01*
Y6186D01*
X537884Y6216D01*
X537984Y6356D01*
X538004Y6396D01*
X538019Y6431D01*
X538039Y6471D01*
X538054Y6511D01*
X538064Y6551D01*
X538079Y6596D01*
X538084Y6636D01*
X538094Y6676D01*
X538099Y6721D01*
Y6761D01*
X538104Y6806D01*
X538099Y6851D01*
Y6891D01*
X538094Y6936D01*
X538084Y6976D01*
X538079Y7016D01*
X538064Y7061D01*
X538054Y7101D01*
X538039Y7141D01*
X538019Y7181D01*
X538004Y7216D01*
X537984Y7256D01*
X537884Y7396D01*
X537854Y7426D01*
Y9556D01*
X537844Y9681D01*
X537804Y9806D01*
X537744Y9916D01*
X537664Y10016D01*
X537564Y10096D01*
X537454Y10156D01*
X537329Y10196D01*
X537204Y10206D01*
X537079Y10196D01*
X536954Y10156D01*
X536844Y10096D01*
X536744Y10016D01*
X536664Y9916D01*
X536604Y9806D01*
X536564Y9681D01*
X536554Y9556D01*
Y7431D01*
X536524Y7401D01*
X536499Y7366D01*
X536469Y7331D01*
X536449Y7296D01*
X536424Y7261D01*
X536384Y7181D01*
X536339Y7061D01*
X536329Y7021D01*
X536319Y6976D01*
X536314Y6936D01*
X536304Y6891D01*
Y6721D01*
X536314Y6676D01*
X536319Y6636D01*
X536329Y6591D01*
X536339Y6551D01*
X536384Y6431D01*
X536424Y6351D01*
X536449Y6316D01*
X536469Y6281D01*
X536499Y6246D01*
X536524Y6211D01*
X536554Y6181D01*
Y3756D01*
X536564Y3631D01*
X536604Y3506D01*
X536664Y3396D01*
X536744Y3296D01*
X536844Y3216D01*
X536954Y3156D01*
X537079Y3116D01*
X537204Y3106D01*
G37*
G36*
G01X532480D02*
X532605Y3116D01*
X532730Y3156D01*
X532840Y3216D01*
X532940Y3296D01*
X533020Y3396D01*
X533080Y3506D01*
X533120Y3631D01*
X533130Y3756D01*
Y6186D01*
X533160Y6216D01*
X533260Y6356D01*
X533280Y6396D01*
X533295Y6431D01*
X533315Y6471D01*
X533330Y6511D01*
X533340Y6551D01*
X533355Y6596D01*
X533360Y6636D01*
X533370Y6676D01*
X533375Y6721D01*
Y6761D01*
X533380Y6806D01*
X533375Y6851D01*
Y6891D01*
X533370Y6936D01*
X533360Y6976D01*
X533355Y7016D01*
X533340Y7061D01*
X533330Y7101D01*
X533315Y7141D01*
X533295Y7181D01*
X533280Y7216D01*
X533260Y7256D01*
X533160Y7396D01*
X533130Y7426D01*
Y9556D01*
X533120Y9681D01*
X533080Y9806D01*
X533020Y9916D01*
X532940Y10016D01*
X532840Y10096D01*
X532730Y10156D01*
X532605Y10196D01*
X532480Y10206D01*
X532355Y10196D01*
X532230Y10156D01*
X532120Y10096D01*
X532020Y10016D01*
X531940Y9916D01*
X531880Y9806D01*
X531840Y9681D01*
X531830Y9556D01*
Y7431D01*
X531800Y7401D01*
X531775Y7366D01*
X531745Y7331D01*
X531725Y7296D01*
X531700Y7261D01*
X531660Y7181D01*
X531615Y7061D01*
X531605Y7021D01*
X531595Y6976D01*
X531590Y6936D01*
X531580Y6891D01*
Y6721D01*
X531590Y6676D01*
X531595Y6636D01*
X531605Y6591D01*
X531615Y6551D01*
X531660Y6431D01*
X531700Y6351D01*
X531725Y6316D01*
X531745Y6281D01*
X531775Y6246D01*
X531800Y6211D01*
X531830Y6181D01*
Y3756D01*
X531840Y3631D01*
X531880Y3506D01*
X531940Y3396D01*
X532020Y3296D01*
X532120Y3216D01*
X532230Y3156D01*
X532355Y3116D01*
X532480Y3106D01*
G37*
G36*
G01X527756D02*
X527881Y3116D01*
X528006Y3156D01*
X528116Y3216D01*
X528216Y3296D01*
X528296Y3396D01*
X528356Y3506D01*
X528396Y3631D01*
X528406Y3756D01*
Y6186D01*
X528436Y6216D01*
X528536Y6356D01*
X528556Y6396D01*
X528571Y6431D01*
X528591Y6471D01*
X528606Y6511D01*
X528616Y6551D01*
X528631Y6596D01*
X528636Y6636D01*
X528646Y6676D01*
X528651Y6721D01*
Y6761D01*
X528656Y6806D01*
X528651Y6851D01*
Y6891D01*
X528646Y6936D01*
X528636Y6976D01*
X528631Y7016D01*
X528616Y7061D01*
X528606Y7101D01*
X528591Y7141D01*
X528571Y7181D01*
X528556Y7216D01*
X528536Y7256D01*
X528436Y7396D01*
X528406Y7426D01*
Y9556D01*
X528396Y9681D01*
X528356Y9806D01*
X528296Y9916D01*
X528216Y10016D01*
X528116Y10096D01*
X528006Y10156D01*
X527881Y10196D01*
X527756Y10206D01*
X527631Y10196D01*
X527506Y10156D01*
X527396Y10096D01*
X527296Y10016D01*
X527216Y9916D01*
X527156Y9806D01*
X527116Y9681D01*
X527106Y9556D01*
Y7431D01*
X527076Y7401D01*
X527051Y7366D01*
X527021Y7331D01*
X527001Y7296D01*
X526976Y7261D01*
X526936Y7181D01*
X526891Y7061D01*
X526881Y7021D01*
X526871Y6976D01*
X526866Y6936D01*
X526856Y6891D01*
Y6721D01*
X526866Y6676D01*
X526871Y6636D01*
X526881Y6591D01*
X526891Y6551D01*
X526936Y6431D01*
X526976Y6351D01*
X527001Y6316D01*
X527021Y6281D01*
X527051Y6246D01*
X527076Y6211D01*
X527106Y6181D01*
Y3756D01*
X527116Y3631D01*
X527156Y3506D01*
X527216Y3396D01*
X527296Y3296D01*
X527396Y3216D01*
X527506Y3156D01*
X527631Y3116D01*
X527756Y3106D01*
G37*
G36*
G01X556102D02*
X556227Y3116D01*
X556352Y3156D01*
X556462Y3216D01*
X556562Y3296D01*
X556642Y3396D01*
X556702Y3506D01*
X556742Y3631D01*
X556752Y3756D01*
Y6186D01*
X556782Y6216D01*
X556882Y6356D01*
X556902Y6396D01*
X556917Y6431D01*
X556937Y6471D01*
X556952Y6511D01*
X556962Y6551D01*
X556977Y6596D01*
X556982Y6636D01*
X556992Y6676D01*
X556997Y6721D01*
Y6761D01*
X557002Y6806D01*
X556997Y6851D01*
Y6891D01*
X556992Y6936D01*
X556982Y6976D01*
X556977Y7016D01*
X556962Y7061D01*
X556952Y7101D01*
X556937Y7141D01*
X556917Y7181D01*
X556902Y7216D01*
X556882Y7256D01*
X556782Y7396D01*
X556752Y7426D01*
Y9556D01*
X556742Y9681D01*
X556702Y9806D01*
X556642Y9916D01*
X556562Y10016D01*
X556462Y10096D01*
X556352Y10156D01*
X556227Y10196D01*
X556102Y10206D01*
X555977Y10196D01*
X555852Y10156D01*
X555742Y10096D01*
X555642Y10016D01*
X555562Y9916D01*
X555502Y9806D01*
X555462Y9681D01*
X555452Y9556D01*
Y7431D01*
X555422Y7401D01*
X555397Y7366D01*
X555367Y7331D01*
X555347Y7296D01*
X555322Y7261D01*
X555282Y7181D01*
X555237Y7061D01*
X555227Y7021D01*
X555217Y6976D01*
X555212Y6936D01*
X555202Y6891D01*
Y6721D01*
X555212Y6676D01*
X555217Y6636D01*
X555227Y6591D01*
X555237Y6551D01*
X555282Y6431D01*
X555322Y6351D01*
X555347Y6316D01*
X555367Y6281D01*
X555397Y6246D01*
X555422Y6211D01*
X555452Y6181D01*
Y3756D01*
X555462Y3631D01*
X555502Y3506D01*
X555562Y3396D01*
X555642Y3296D01*
X555742Y3216D01*
X555852Y3156D01*
X555977Y3116D01*
X556102Y3106D01*
G37*
G36*
G01X551378D02*
X551503Y3116D01*
X551628Y3156D01*
X551738Y3216D01*
X551838Y3296D01*
X551918Y3396D01*
X551978Y3506D01*
X552018Y3631D01*
X552028Y3756D01*
Y6186D01*
X552058Y6216D01*
X552158Y6356D01*
X552178Y6396D01*
X552193Y6431D01*
X552213Y6471D01*
X552228Y6511D01*
X552238Y6551D01*
X552253Y6596D01*
X552258Y6636D01*
X552268Y6676D01*
X552273Y6721D01*
Y6761D01*
X552278Y6806D01*
X552273Y6851D01*
Y6891D01*
X552268Y6936D01*
X552258Y6976D01*
X552253Y7016D01*
X552238Y7061D01*
X552228Y7101D01*
X552213Y7141D01*
X552193Y7181D01*
X552178Y7216D01*
X552158Y7256D01*
X552058Y7396D01*
X552028Y7426D01*
Y9556D01*
X552018Y9681D01*
X551978Y9806D01*
X551918Y9916D01*
X551838Y10016D01*
X551738Y10096D01*
X551628Y10156D01*
X551503Y10196D01*
X551378Y10206D01*
X551253Y10196D01*
X551128Y10156D01*
X551018Y10096D01*
X550918Y10016D01*
X550838Y9916D01*
X550778Y9806D01*
X550738Y9681D01*
X550728Y9556D01*
Y7431D01*
X550698Y7401D01*
X550673Y7366D01*
X550643Y7331D01*
X550623Y7296D01*
X550598Y7261D01*
X550558Y7181D01*
X550513Y7061D01*
X550503Y7021D01*
X550493Y6976D01*
X550488Y6936D01*
X550478Y6891D01*
Y6721D01*
X550488Y6676D01*
X550493Y6636D01*
X550503Y6591D01*
X550513Y6551D01*
X550558Y6431D01*
X550598Y6351D01*
X550623Y6316D01*
X550643Y6281D01*
X550673Y6246D01*
X550698Y6211D01*
X550728Y6181D01*
Y3756D01*
X550738Y3631D01*
X550778Y3506D01*
X550838Y3396D01*
X550918Y3296D01*
X551018Y3216D01*
X551128Y3156D01*
X551253Y3116D01*
X551378Y3106D01*
G37*
G36*
G01X546653D02*
X546778Y3116D01*
X546903Y3156D01*
X547013Y3216D01*
X547113Y3296D01*
X547193Y3396D01*
X547253Y3506D01*
X547293Y3631D01*
X547303Y3756D01*
Y6186D01*
X547333Y6216D01*
X547433Y6356D01*
X547453Y6396D01*
X547468Y6431D01*
X547488Y6471D01*
X547503Y6511D01*
X547513Y6551D01*
X547528Y6596D01*
X547533Y6636D01*
X547543Y6676D01*
X547548Y6721D01*
Y6761D01*
X547553Y6806D01*
X547548Y6851D01*
Y6891D01*
X547543Y6936D01*
X547533Y6976D01*
X547528Y7016D01*
X547513Y7061D01*
X547503Y7101D01*
X547488Y7141D01*
X547468Y7181D01*
X547453Y7216D01*
X547433Y7256D01*
X547333Y7396D01*
X547303Y7426D01*
Y9556D01*
X547293Y9681D01*
X547253Y9806D01*
X547193Y9916D01*
X547113Y10016D01*
X547013Y10096D01*
X546903Y10156D01*
X546778Y10196D01*
X546653Y10206D01*
X546528Y10196D01*
X546403Y10156D01*
X546293Y10096D01*
X546193Y10016D01*
X546113Y9916D01*
X546053Y9806D01*
X546013Y9681D01*
X546003Y9556D01*
Y7431D01*
X545973Y7401D01*
X545948Y7366D01*
X545918Y7331D01*
X545898Y7296D01*
X545873Y7261D01*
X545833Y7181D01*
X545788Y7061D01*
X545778Y7021D01*
X545768Y6976D01*
X545763Y6936D01*
X545753Y6891D01*
Y6721D01*
X545763Y6676D01*
X545768Y6636D01*
X545778Y6591D01*
X545788Y6551D01*
X545833Y6431D01*
X545873Y6351D01*
X545898Y6316D01*
X545918Y6281D01*
X545948Y6246D01*
X545973Y6211D01*
X546003Y6181D01*
Y3756D01*
X546013Y3631D01*
X546053Y3506D01*
X546113Y3396D01*
X546193Y3296D01*
X546293Y3216D01*
X546403Y3156D01*
X546528Y3116D01*
X546653Y3106D01*
G37*
G36*
G01X570275D02*
X570400Y3116D01*
X570525Y3156D01*
X570635Y3216D01*
X570735Y3296D01*
X570815Y3396D01*
X570875Y3506D01*
X570915Y3631D01*
X570925Y3756D01*
Y6186D01*
X570955Y6216D01*
X571055Y6356D01*
X571075Y6396D01*
X571090Y6431D01*
X571110Y6471D01*
X571125Y6511D01*
X571135Y6551D01*
X571150Y6596D01*
X571155Y6636D01*
X571165Y6676D01*
X571170Y6721D01*
Y6761D01*
X571175Y6806D01*
X571170Y6851D01*
Y6891D01*
X571165Y6936D01*
X571155Y6976D01*
X571150Y7016D01*
X571135Y7061D01*
X571125Y7101D01*
X571110Y7141D01*
X571090Y7181D01*
X571075Y7216D01*
X571055Y7256D01*
X570955Y7396D01*
X570925Y7426D01*
Y9556D01*
X570915Y9681D01*
X570875Y9806D01*
X570815Y9916D01*
X570735Y10016D01*
X570635Y10096D01*
X570525Y10156D01*
X570400Y10196D01*
X570275Y10206D01*
X570150Y10196D01*
X570025Y10156D01*
X569915Y10096D01*
X569815Y10016D01*
X569735Y9916D01*
X569675Y9806D01*
X569635Y9681D01*
X569625Y9556D01*
Y7431D01*
X569595Y7401D01*
X569570Y7366D01*
X569540Y7331D01*
X569520Y7296D01*
X569495Y7261D01*
X569455Y7181D01*
X569410Y7061D01*
X569400Y7021D01*
X569390Y6976D01*
X569385Y6936D01*
X569375Y6891D01*
Y6721D01*
X569385Y6676D01*
X569390Y6636D01*
X569400Y6591D01*
X569410Y6551D01*
X569455Y6431D01*
X569495Y6351D01*
X569520Y6316D01*
X569540Y6281D01*
X569570Y6246D01*
X569595Y6211D01*
X569625Y6181D01*
Y3756D01*
X569635Y3631D01*
X569675Y3506D01*
X569735Y3396D01*
X569815Y3296D01*
X569915Y3216D01*
X570025Y3156D01*
X570150Y3116D01*
X570275Y3106D01*
G37*
G36*
G01X565551D02*
X565676Y3116D01*
X565801Y3156D01*
X565911Y3216D01*
X566011Y3296D01*
X566091Y3396D01*
X566151Y3506D01*
X566191Y3631D01*
X566201Y3756D01*
Y6186D01*
X566231Y6216D01*
X566331Y6356D01*
X566351Y6396D01*
X566366Y6431D01*
X566386Y6471D01*
X566401Y6511D01*
X566411Y6551D01*
X566426Y6596D01*
X566431Y6636D01*
X566441Y6676D01*
X566446Y6721D01*
Y6761D01*
X566451Y6806D01*
X566446Y6851D01*
Y6891D01*
X566441Y6936D01*
X566431Y6976D01*
X566426Y7016D01*
X566411Y7061D01*
X566401Y7101D01*
X566386Y7141D01*
X566366Y7181D01*
X566351Y7216D01*
X566331Y7256D01*
X566231Y7396D01*
X566201Y7426D01*
Y9556D01*
X566191Y9681D01*
X566151Y9806D01*
X566091Y9916D01*
X566011Y10016D01*
X565911Y10096D01*
X565801Y10156D01*
X565676Y10196D01*
X565551Y10206D01*
X565426Y10196D01*
X565301Y10156D01*
X565191Y10096D01*
X565091Y10016D01*
X565011Y9916D01*
X564951Y9806D01*
X564911Y9681D01*
X564901Y9556D01*
Y7431D01*
X564871Y7401D01*
X564846Y7366D01*
X564816Y7331D01*
X564796Y7296D01*
X564771Y7261D01*
X564731Y7181D01*
X564686Y7061D01*
X564676Y7021D01*
X564666Y6976D01*
X564661Y6936D01*
X564651Y6891D01*
Y6721D01*
X564661Y6676D01*
X564666Y6636D01*
X564676Y6591D01*
X564686Y6551D01*
X564731Y6431D01*
X564771Y6351D01*
X564796Y6316D01*
X564816Y6281D01*
X564846Y6246D01*
X564871Y6211D01*
X564901Y6181D01*
Y3756D01*
X564911Y3631D01*
X564951Y3506D01*
X565011Y3396D01*
X565091Y3296D01*
X565191Y3216D01*
X565301Y3156D01*
X565426Y3116D01*
X565551Y3106D01*
G37*
G36*
G01X560827D02*
X560952Y3116D01*
X561077Y3156D01*
X561187Y3216D01*
X561287Y3296D01*
X561367Y3396D01*
X561427Y3506D01*
X561467Y3631D01*
X561477Y3756D01*
Y6186D01*
X561507Y6216D01*
X561607Y6356D01*
X561627Y6396D01*
X561642Y6431D01*
X561662Y6471D01*
X561677Y6511D01*
X561687Y6551D01*
X561702Y6596D01*
X561707Y6636D01*
X561717Y6676D01*
X561722Y6721D01*
Y6761D01*
X561727Y6806D01*
X561722Y6851D01*
Y6891D01*
X561717Y6936D01*
X561707Y6976D01*
X561702Y7016D01*
X561687Y7061D01*
X561677Y7101D01*
X561662Y7141D01*
X561642Y7181D01*
X561627Y7216D01*
X561607Y7256D01*
X561507Y7396D01*
X561477Y7426D01*
Y9556D01*
X561467Y9681D01*
X561427Y9806D01*
X561367Y9916D01*
X561287Y10016D01*
X561187Y10096D01*
X561077Y10156D01*
X560952Y10196D01*
X560827Y10206D01*
X560702Y10196D01*
X560577Y10156D01*
X560467Y10096D01*
X560367Y10016D01*
X560287Y9916D01*
X560227Y9806D01*
X560187Y9681D01*
X560177Y9556D01*
Y7431D01*
X560147Y7401D01*
X560122Y7366D01*
X560092Y7331D01*
X560072Y7296D01*
X560047Y7261D01*
X560007Y7181D01*
X559962Y7061D01*
X559952Y7021D01*
X559942Y6976D01*
X559937Y6936D01*
X559927Y6891D01*
Y6721D01*
X559937Y6676D01*
X559942Y6636D01*
X559952Y6591D01*
X559962Y6551D01*
X560007Y6431D01*
X560047Y6351D01*
X560072Y6316D01*
X560092Y6281D01*
X560122Y6246D01*
X560147Y6211D01*
X560177Y6181D01*
Y3756D01*
X560187Y3631D01*
X560227Y3506D01*
X560287Y3396D01*
X560367Y3296D01*
X560467Y3216D01*
X560577Y3156D01*
X560702Y3116D01*
X560827Y3106D01*
G37*
G36*
G01X584449D02*
X584574Y3116D01*
X584699Y3156D01*
X584809Y3216D01*
X584909Y3296D01*
X584989Y3396D01*
X585049Y3506D01*
X585089Y3631D01*
X585099Y3756D01*
Y6186D01*
X585129Y6216D01*
X585229Y6356D01*
X585249Y6396D01*
X585264Y6431D01*
X585284Y6471D01*
X585299Y6511D01*
X585309Y6551D01*
X585324Y6596D01*
X585329Y6636D01*
X585339Y6676D01*
X585344Y6721D01*
Y6761D01*
X585349Y6806D01*
X585344Y6851D01*
Y6891D01*
X585339Y6936D01*
X585329Y6976D01*
X585324Y7016D01*
X585309Y7061D01*
X585299Y7101D01*
X585284Y7141D01*
X585264Y7181D01*
X585249Y7216D01*
X585229Y7256D01*
X585129Y7396D01*
X585099Y7426D01*
Y9556D01*
X585089Y9681D01*
X585049Y9806D01*
X584989Y9916D01*
X584909Y10016D01*
X584809Y10096D01*
X584699Y10156D01*
X584574Y10196D01*
X584449Y10206D01*
X584324Y10196D01*
X584199Y10156D01*
X584089Y10096D01*
X583989Y10016D01*
X583909Y9916D01*
X583849Y9806D01*
X583809Y9681D01*
X583799Y9556D01*
Y7431D01*
X583769Y7401D01*
X583744Y7366D01*
X583714Y7331D01*
X583694Y7296D01*
X583669Y7261D01*
X583629Y7181D01*
X583584Y7061D01*
X583574Y7021D01*
X583564Y6976D01*
X583559Y6936D01*
X583549Y6891D01*
Y6721D01*
X583559Y6676D01*
X583564Y6636D01*
X583574Y6591D01*
X583584Y6551D01*
X583629Y6431D01*
X583669Y6351D01*
X583694Y6316D01*
X583714Y6281D01*
X583744Y6246D01*
X583769Y6211D01*
X583799Y6181D01*
Y3756D01*
X583809Y3631D01*
X583849Y3506D01*
X583909Y3396D01*
X583989Y3296D01*
X584089Y3216D01*
X584199Y3156D01*
X584324Y3116D01*
X584449Y3106D01*
G37*
G36*
G01X579724D02*
X579849Y3116D01*
X579974Y3156D01*
X580084Y3216D01*
X580184Y3296D01*
X580264Y3396D01*
X580324Y3506D01*
X580364Y3631D01*
X580374Y3756D01*
Y6186D01*
X580404Y6216D01*
X580504Y6356D01*
X580524Y6396D01*
X580539Y6431D01*
X580559Y6471D01*
X580574Y6511D01*
X580584Y6551D01*
X580599Y6596D01*
X580604Y6636D01*
X580614Y6676D01*
X580619Y6721D01*
Y6761D01*
X580624Y6806D01*
X580619Y6851D01*
Y6891D01*
X580614Y6936D01*
X580604Y6976D01*
X580599Y7016D01*
X580584Y7061D01*
X580574Y7101D01*
X580559Y7141D01*
X580539Y7181D01*
X580524Y7216D01*
X580504Y7256D01*
X580404Y7396D01*
X580374Y7426D01*
Y9556D01*
X580364Y9681D01*
X580324Y9806D01*
X580264Y9916D01*
X580184Y10016D01*
X580084Y10096D01*
X579974Y10156D01*
X579849Y10196D01*
X579724Y10206D01*
X579599Y10196D01*
X579474Y10156D01*
X579364Y10096D01*
X579264Y10016D01*
X579184Y9916D01*
X579124Y9806D01*
X579084Y9681D01*
X579074Y9556D01*
Y7431D01*
X579044Y7401D01*
X579019Y7366D01*
X578989Y7331D01*
X578969Y7296D01*
X578944Y7261D01*
X578904Y7181D01*
X578859Y7061D01*
X578849Y7021D01*
X578839Y6976D01*
X578834Y6936D01*
X578824Y6891D01*
Y6721D01*
X578834Y6676D01*
X578839Y6636D01*
X578849Y6591D01*
X578859Y6551D01*
X578904Y6431D01*
X578944Y6351D01*
X578969Y6316D01*
X578989Y6281D01*
X579019Y6246D01*
X579044Y6211D01*
X579074Y6181D01*
Y3756D01*
X579084Y3631D01*
X579124Y3506D01*
X579184Y3396D01*
X579264Y3296D01*
X579364Y3216D01*
X579474Y3156D01*
X579599Y3116D01*
X579724Y3106D01*
G37*
G36*
G01X575000D02*
X575125Y3116D01*
X575250Y3156D01*
X575360Y3216D01*
X575460Y3296D01*
X575540Y3396D01*
X575600Y3506D01*
X575640Y3631D01*
X575650Y3756D01*
Y6186D01*
X575680Y6216D01*
X575780Y6356D01*
X575800Y6396D01*
X575815Y6431D01*
X575835Y6471D01*
X575850Y6511D01*
X575860Y6551D01*
X575875Y6596D01*
X575880Y6636D01*
X575890Y6676D01*
X575895Y6721D01*
Y6761D01*
X575900Y6806D01*
X575895Y6851D01*
Y6891D01*
X575890Y6936D01*
X575880Y6976D01*
X575875Y7016D01*
X575860Y7061D01*
X575850Y7101D01*
X575835Y7141D01*
X575815Y7181D01*
X575800Y7216D01*
X575780Y7256D01*
X575680Y7396D01*
X575650Y7426D01*
Y9556D01*
X575640Y9681D01*
X575600Y9806D01*
X575540Y9916D01*
X575460Y10016D01*
X575360Y10096D01*
X575250Y10156D01*
X575125Y10196D01*
X575000Y10206D01*
X574875Y10196D01*
X574750Y10156D01*
X574640Y10096D01*
X574540Y10016D01*
X574460Y9916D01*
X574400Y9806D01*
X574360Y9681D01*
X574350Y9556D01*
Y7431D01*
X574320Y7401D01*
X574295Y7366D01*
X574265Y7331D01*
X574245Y7296D01*
X574220Y7261D01*
X574180Y7181D01*
X574135Y7061D01*
X574125Y7021D01*
X574115Y6976D01*
X574110Y6936D01*
X574100Y6891D01*
Y6721D01*
X574110Y6676D01*
X574115Y6636D01*
X574125Y6591D01*
X574135Y6551D01*
X574180Y6431D01*
X574220Y6351D01*
X574245Y6316D01*
X574265Y6281D01*
X574295Y6246D01*
X574320Y6211D01*
X574350Y6181D01*
Y3756D01*
X574360Y3631D01*
X574400Y3506D01*
X574460Y3396D01*
X574540Y3296D01*
X574640Y3216D01*
X574750Y3156D01*
X574875Y3116D01*
X575000Y3106D01*
G37*
G36*
G01X603346D02*
X603471Y3116D01*
X603596Y3156D01*
X603706Y3216D01*
X603806Y3296D01*
X603886Y3396D01*
X603946Y3506D01*
X603986Y3631D01*
X603996Y3756D01*
Y6186D01*
X604026Y6216D01*
X604126Y6356D01*
X604146Y6396D01*
X604161Y6431D01*
X604181Y6471D01*
X604196Y6511D01*
X604206Y6551D01*
X604221Y6596D01*
X604226Y6636D01*
X604236Y6676D01*
X604241Y6721D01*
Y6761D01*
X604246Y6806D01*
X604241Y6851D01*
Y6891D01*
X604236Y6936D01*
X604226Y6976D01*
X604221Y7016D01*
X604206Y7061D01*
X604196Y7101D01*
X604181Y7141D01*
X604161Y7181D01*
X604146Y7216D01*
X604126Y7256D01*
X604026Y7396D01*
X603996Y7426D01*
Y9556D01*
X603986Y9681D01*
X603946Y9806D01*
X603886Y9916D01*
X603806Y10016D01*
X603706Y10096D01*
X603596Y10156D01*
X603471Y10196D01*
X603346Y10206D01*
X603221Y10196D01*
X603096Y10156D01*
X602986Y10096D01*
X602886Y10016D01*
X602806Y9916D01*
X602746Y9806D01*
X602706Y9681D01*
X602696Y9556D01*
Y7431D01*
X602666Y7401D01*
X602641Y7366D01*
X602611Y7331D01*
X602591Y7296D01*
X602566Y7261D01*
X602526Y7181D01*
X602481Y7061D01*
X602471Y7021D01*
X602461Y6976D01*
X602456Y6936D01*
X602446Y6891D01*
Y6721D01*
X602456Y6676D01*
X602461Y6636D01*
X602471Y6591D01*
X602481Y6551D01*
X602526Y6431D01*
X602566Y6351D01*
X602591Y6316D01*
X602611Y6281D01*
X602641Y6246D01*
X602666Y6211D01*
X602696Y6181D01*
Y3756D01*
X602706Y3631D01*
X602746Y3506D01*
X602806Y3396D01*
X602886Y3296D01*
X602986Y3216D01*
X603096Y3156D01*
X603221Y3116D01*
X603346Y3106D01*
G37*
G36*
G01X589173D02*
X589298Y3116D01*
X589423Y3156D01*
X589533Y3216D01*
X589633Y3296D01*
X589713Y3396D01*
X589773Y3506D01*
X589813Y3631D01*
X589823Y3756D01*
Y6186D01*
X589853Y6216D01*
X589953Y6356D01*
X589973Y6396D01*
X589988Y6431D01*
X590008Y6471D01*
X590023Y6511D01*
X590033Y6551D01*
X590048Y6596D01*
X590053Y6636D01*
X590063Y6676D01*
X590068Y6721D01*
Y6761D01*
X590073Y6806D01*
X590068Y6851D01*
Y6891D01*
X590063Y6936D01*
X590053Y6976D01*
X590048Y7016D01*
X590033Y7061D01*
X590023Y7101D01*
X590008Y7141D01*
X589988Y7181D01*
X589973Y7216D01*
X589953Y7256D01*
X589853Y7396D01*
X589823Y7426D01*
Y9556D01*
X589813Y9681D01*
X589773Y9806D01*
X589713Y9916D01*
X589633Y10016D01*
X589533Y10096D01*
X589423Y10156D01*
X589298Y10196D01*
X589173Y10206D01*
X589048Y10196D01*
X588923Y10156D01*
X588813Y10096D01*
X588713Y10016D01*
X588633Y9916D01*
X588573Y9806D01*
X588533Y9681D01*
X588523Y9556D01*
Y7431D01*
X588493Y7401D01*
X588468Y7366D01*
X588438Y7331D01*
X588418Y7296D01*
X588393Y7261D01*
X588353Y7181D01*
X588308Y7061D01*
X588298Y7021D01*
X588288Y6976D01*
X588283Y6936D01*
X588273Y6891D01*
Y6721D01*
X588283Y6676D01*
X588288Y6636D01*
X588298Y6591D01*
X588308Y6551D01*
X588353Y6431D01*
X588393Y6351D01*
X588418Y6316D01*
X588438Y6281D01*
X588468Y6246D01*
X588493Y6211D01*
X588523Y6181D01*
Y3756D01*
X588533Y3631D01*
X588573Y3506D01*
X588633Y3396D01*
X588713Y3296D01*
X588813Y3216D01*
X588923Y3156D01*
X589048Y3116D01*
X589173Y3106D01*
G37*
G36*
G01X617519D02*
X617644Y3116D01*
X617769Y3156D01*
X617879Y3216D01*
X617979Y3296D01*
X618059Y3396D01*
X618119Y3506D01*
X618159Y3631D01*
X618169Y3756D01*
Y6186D01*
X618199Y6216D01*
X618299Y6356D01*
X618319Y6396D01*
X618334Y6431D01*
X618354Y6471D01*
X618369Y6511D01*
X618379Y6551D01*
X618394Y6596D01*
X618399Y6636D01*
X618409Y6676D01*
X618414Y6721D01*
Y6761D01*
X618419Y6806D01*
X618414Y6851D01*
Y6891D01*
X618409Y6936D01*
X618399Y6976D01*
X618394Y7016D01*
X618379Y7061D01*
X618369Y7101D01*
X618354Y7141D01*
X618334Y7181D01*
X618319Y7216D01*
X618299Y7256D01*
X618199Y7396D01*
X618169Y7426D01*
Y9556D01*
X618159Y9681D01*
X618119Y9806D01*
X618059Y9916D01*
X617979Y10016D01*
X617879Y10096D01*
X617769Y10156D01*
X617644Y10196D01*
X617519Y10206D01*
X617394Y10196D01*
X617269Y10156D01*
X617159Y10096D01*
X617059Y10016D01*
X616979Y9916D01*
X616919Y9806D01*
X616879Y9681D01*
X616869Y9556D01*
Y7431D01*
X616839Y7401D01*
X616814Y7366D01*
X616784Y7331D01*
X616764Y7296D01*
X616739Y7261D01*
X616699Y7181D01*
X616654Y7061D01*
X616644Y7021D01*
X616634Y6976D01*
X616629Y6936D01*
X616619Y6891D01*
Y6721D01*
X616629Y6676D01*
X616634Y6636D01*
X616644Y6591D01*
X616654Y6551D01*
X616699Y6431D01*
X616739Y6351D01*
X616764Y6316D01*
X616784Y6281D01*
X616814Y6246D01*
X616839Y6211D01*
X616869Y6181D01*
Y3756D01*
X616879Y3631D01*
X616919Y3506D01*
X616979Y3396D01*
X617059Y3296D01*
X617159Y3216D01*
X617269Y3156D01*
X617394Y3116D01*
X617519Y3106D01*
G37*
G36*
G01X612795D02*
X612920Y3116D01*
X613045Y3156D01*
X613155Y3216D01*
X613255Y3296D01*
X613335Y3396D01*
X613395Y3506D01*
X613435Y3631D01*
X613445Y3756D01*
Y6186D01*
X613475Y6216D01*
X613575Y6356D01*
X613595Y6396D01*
X613610Y6431D01*
X613630Y6471D01*
X613645Y6511D01*
X613655Y6551D01*
X613670Y6596D01*
X613675Y6636D01*
X613685Y6676D01*
X613690Y6721D01*
Y6761D01*
X613695Y6806D01*
X613690Y6851D01*
Y6891D01*
X613685Y6936D01*
X613675Y6976D01*
X613670Y7016D01*
X613655Y7061D01*
X613645Y7101D01*
X613630Y7141D01*
X613610Y7181D01*
X613595Y7216D01*
X613575Y7256D01*
X613475Y7396D01*
X613445Y7426D01*
Y9556D01*
X613435Y9681D01*
X613395Y9806D01*
X613335Y9916D01*
X613255Y10016D01*
X613155Y10096D01*
X613045Y10156D01*
X612920Y10196D01*
X612795Y10206D01*
X612670Y10196D01*
X612545Y10156D01*
X612435Y10096D01*
X612335Y10016D01*
X612255Y9916D01*
X612195Y9806D01*
X612155Y9681D01*
X612145Y9556D01*
Y7431D01*
X612115Y7401D01*
X612090Y7366D01*
X612060Y7331D01*
X612040Y7296D01*
X612015Y7261D01*
X611975Y7181D01*
X611930Y7061D01*
X611920Y7021D01*
X611910Y6976D01*
X611905Y6936D01*
X611895Y6891D01*
Y6721D01*
X611905Y6676D01*
X611910Y6636D01*
X611920Y6591D01*
X611930Y6551D01*
X611975Y6431D01*
X612015Y6351D01*
X612040Y6316D01*
X612060Y6281D01*
X612090Y6246D01*
X612115Y6211D01*
X612145Y6181D01*
Y3756D01*
X612155Y3631D01*
X612195Y3506D01*
X612255Y3396D01*
X612335Y3296D01*
X612435Y3216D01*
X612545Y3156D01*
X612670Y3116D01*
X612795Y3106D01*
G37*
G36*
G01X608071D02*
X608196Y3116D01*
X608321Y3156D01*
X608431Y3216D01*
X608531Y3296D01*
X608611Y3396D01*
X608671Y3506D01*
X608711Y3631D01*
X608721Y3756D01*
Y6186D01*
X608751Y6216D01*
X608851Y6356D01*
X608871Y6396D01*
X608886Y6431D01*
X608906Y6471D01*
X608921Y6511D01*
X608931Y6551D01*
X608946Y6596D01*
X608951Y6636D01*
X608961Y6676D01*
X608966Y6721D01*
Y6761D01*
X608971Y6806D01*
X608966Y6851D01*
Y6891D01*
X608961Y6936D01*
X608951Y6976D01*
X608946Y7016D01*
X608931Y7061D01*
X608921Y7101D01*
X608906Y7141D01*
X608886Y7181D01*
X608871Y7216D01*
X608851Y7256D01*
X608751Y7396D01*
X608721Y7426D01*
Y9556D01*
X608711Y9681D01*
X608671Y9806D01*
X608611Y9916D01*
X608531Y10016D01*
X608431Y10096D01*
X608321Y10156D01*
X608196Y10196D01*
X608071Y10206D01*
X607946Y10196D01*
X607821Y10156D01*
X607711Y10096D01*
X607611Y10016D01*
X607531Y9916D01*
X607471Y9806D01*
X607431Y9681D01*
X607421Y9556D01*
Y7431D01*
X607391Y7401D01*
X607366Y7366D01*
X607336Y7331D01*
X607316Y7296D01*
X607291Y7261D01*
X607251Y7181D01*
X607206Y7061D01*
X607196Y7021D01*
X607186Y6976D01*
X607181Y6936D01*
X607171Y6891D01*
Y6721D01*
X607181Y6676D01*
X607186Y6636D01*
X607196Y6591D01*
X607206Y6551D01*
X607251Y6431D01*
X607291Y6351D01*
X607316Y6316D01*
X607336Y6281D01*
X607366Y6246D01*
X607391Y6211D01*
X607421Y6181D01*
Y3756D01*
X607431Y3631D01*
X607471Y3506D01*
X607531Y3396D01*
X607611Y3296D01*
X607711Y3216D01*
X607821Y3156D01*
X607946Y3116D01*
X608071Y3106D01*
G37*
G36*
G01X631693D02*
X631818Y3116D01*
X631943Y3156D01*
X632053Y3216D01*
X632153Y3296D01*
X632233Y3396D01*
X632293Y3506D01*
X632333Y3631D01*
X632343Y3756D01*
Y6186D01*
X632373Y6216D01*
X632473Y6356D01*
X632493Y6396D01*
X632508Y6431D01*
X632528Y6471D01*
X632543Y6511D01*
X632553Y6551D01*
X632568Y6596D01*
X632573Y6636D01*
X632583Y6676D01*
X632588Y6721D01*
Y6761D01*
X632593Y6806D01*
X632588Y6851D01*
Y6891D01*
X632583Y6936D01*
X632573Y6976D01*
X632568Y7016D01*
X632553Y7061D01*
X632543Y7101D01*
X632528Y7141D01*
X632508Y7181D01*
X632493Y7216D01*
X632473Y7256D01*
X632373Y7396D01*
X632343Y7426D01*
Y9556D01*
X632333Y9681D01*
X632293Y9806D01*
X632233Y9916D01*
X632153Y10016D01*
X632053Y10096D01*
X631943Y10156D01*
X631818Y10196D01*
X631693Y10206D01*
X631568Y10196D01*
X631443Y10156D01*
X631333Y10096D01*
X631233Y10016D01*
X631153Y9916D01*
X631093Y9806D01*
X631053Y9681D01*
X631043Y9556D01*
Y7431D01*
X631013Y7401D01*
X630988Y7366D01*
X630958Y7331D01*
X630938Y7296D01*
X630913Y7261D01*
X630873Y7181D01*
X630828Y7061D01*
X630818Y7021D01*
X630808Y6976D01*
X630803Y6936D01*
X630793Y6891D01*
Y6721D01*
X630803Y6676D01*
X630808Y6636D01*
X630818Y6591D01*
X630828Y6551D01*
X630873Y6431D01*
X630913Y6351D01*
X630938Y6316D01*
X630958Y6281D01*
X630988Y6246D01*
X631013Y6211D01*
X631043Y6181D01*
Y3756D01*
X631053Y3631D01*
X631093Y3506D01*
X631153Y3396D01*
X631233Y3296D01*
X631333Y3216D01*
X631443Y3156D01*
X631568Y3116D01*
X631693Y3106D01*
G37*
G36*
G01X626968D02*
X627093Y3116D01*
X627218Y3156D01*
X627328Y3216D01*
X627428Y3296D01*
X627508Y3396D01*
X627568Y3506D01*
X627608Y3631D01*
X627618Y3756D01*
Y6186D01*
X627648Y6216D01*
X627748Y6356D01*
X627768Y6396D01*
X627783Y6431D01*
X627803Y6471D01*
X627818Y6511D01*
X627828Y6551D01*
X627843Y6596D01*
X627848Y6636D01*
X627858Y6676D01*
X627863Y6721D01*
Y6761D01*
X627868Y6806D01*
X627863Y6851D01*
Y6891D01*
X627858Y6936D01*
X627848Y6976D01*
X627843Y7016D01*
X627828Y7061D01*
X627818Y7101D01*
X627803Y7141D01*
X627783Y7181D01*
X627768Y7216D01*
X627748Y7256D01*
X627648Y7396D01*
X627618Y7426D01*
Y9556D01*
X627608Y9681D01*
X627568Y9806D01*
X627508Y9916D01*
X627428Y10016D01*
X627328Y10096D01*
X627218Y10156D01*
X627093Y10196D01*
X626968Y10206D01*
X626843Y10196D01*
X626718Y10156D01*
X626608Y10096D01*
X626508Y10016D01*
X626428Y9916D01*
X626368Y9806D01*
X626328Y9681D01*
X626318Y9556D01*
Y7431D01*
X626288Y7401D01*
X626263Y7366D01*
X626233Y7331D01*
X626213Y7296D01*
X626188Y7261D01*
X626148Y7181D01*
X626103Y7061D01*
X626093Y7021D01*
X626083Y6976D01*
X626078Y6936D01*
X626068Y6891D01*
Y6721D01*
X626078Y6676D01*
X626083Y6636D01*
X626093Y6591D01*
X626103Y6551D01*
X626148Y6431D01*
X626188Y6351D01*
X626213Y6316D01*
X626233Y6281D01*
X626263Y6246D01*
X626288Y6211D01*
X626318Y6181D01*
Y3756D01*
X626328Y3631D01*
X626368Y3506D01*
X626428Y3396D01*
X626508Y3296D01*
X626608Y3216D01*
X626718Y3156D01*
X626843Y3116D01*
X626968Y3106D01*
G37*
G36*
G01X622244D02*
X622369Y3116D01*
X622494Y3156D01*
X622604Y3216D01*
X622704Y3296D01*
X622784Y3396D01*
X622844Y3506D01*
X622884Y3631D01*
X622894Y3756D01*
Y6186D01*
X622924Y6216D01*
X623024Y6356D01*
X623044Y6396D01*
X623059Y6431D01*
X623079Y6471D01*
X623094Y6511D01*
X623104Y6551D01*
X623119Y6596D01*
X623124Y6636D01*
X623134Y6676D01*
X623139Y6721D01*
Y6761D01*
X623144Y6806D01*
X623139Y6851D01*
Y6891D01*
X623134Y6936D01*
X623124Y6976D01*
X623119Y7016D01*
X623104Y7061D01*
X623094Y7101D01*
X623079Y7141D01*
X623059Y7181D01*
X623044Y7216D01*
X623024Y7256D01*
X622924Y7396D01*
X622894Y7426D01*
Y9556D01*
X622884Y9681D01*
X622844Y9806D01*
X622784Y9916D01*
X622704Y10016D01*
X622604Y10096D01*
X622494Y10156D01*
X622369Y10196D01*
X622244Y10206D01*
X622119Y10196D01*
X621994Y10156D01*
X621884Y10096D01*
X621784Y10016D01*
X621704Y9916D01*
X621644Y9806D01*
X621604Y9681D01*
X621594Y9556D01*
Y7431D01*
X621564Y7401D01*
X621539Y7366D01*
X621509Y7331D01*
X621489Y7296D01*
X621464Y7261D01*
X621424Y7181D01*
X621379Y7061D01*
X621369Y7021D01*
X621359Y6976D01*
X621354Y6936D01*
X621344Y6891D01*
Y6721D01*
X621354Y6676D01*
X621359Y6636D01*
X621369Y6591D01*
X621379Y6551D01*
X621424Y6431D01*
X621464Y6351D01*
X621489Y6316D01*
X621509Y6281D01*
X621539Y6246D01*
X621564Y6211D01*
X621594Y6181D01*
Y3756D01*
X621604Y3631D01*
X621644Y3506D01*
X621704Y3396D01*
X621784Y3296D01*
X621884Y3216D01*
X621994Y3156D01*
X622119Y3116D01*
X622244Y3106D01*
G37*
G36*
G01X645866D02*
X645991Y3116D01*
X646116Y3156D01*
X646226Y3216D01*
X646326Y3296D01*
X646406Y3396D01*
X646466Y3506D01*
X646506Y3631D01*
X646516Y3756D01*
Y6186D01*
X646546Y6216D01*
X646646Y6356D01*
X646666Y6396D01*
X646681Y6431D01*
X646701Y6471D01*
X646716Y6511D01*
X646726Y6551D01*
X646741Y6596D01*
X646746Y6636D01*
X646756Y6676D01*
X646761Y6721D01*
Y6761D01*
X646766Y6806D01*
X646761Y6851D01*
Y6891D01*
X646756Y6936D01*
X646746Y6976D01*
X646741Y7016D01*
X646726Y7061D01*
X646716Y7101D01*
X646701Y7141D01*
X646681Y7181D01*
X646666Y7216D01*
X646646Y7256D01*
X646546Y7396D01*
X646516Y7426D01*
Y9556D01*
X646506Y9681D01*
X646466Y9806D01*
X646406Y9916D01*
X646326Y10016D01*
X646226Y10096D01*
X646116Y10156D01*
X645991Y10196D01*
X645866Y10206D01*
X645741Y10196D01*
X645616Y10156D01*
X645506Y10096D01*
X645406Y10016D01*
X645326Y9916D01*
X645266Y9806D01*
X645226Y9681D01*
X645216Y9556D01*
Y7431D01*
X645186Y7401D01*
X645161Y7366D01*
X645131Y7331D01*
X645111Y7296D01*
X645086Y7261D01*
X645046Y7181D01*
X645001Y7061D01*
X644991Y7021D01*
X644981Y6976D01*
X644976Y6936D01*
X644966Y6891D01*
Y6721D01*
X644976Y6676D01*
X644981Y6636D01*
X644991Y6591D01*
X645001Y6551D01*
X645046Y6431D01*
X645086Y6351D01*
X645111Y6316D01*
X645131Y6281D01*
X645161Y6246D01*
X645186Y6211D01*
X645216Y6181D01*
Y3756D01*
X645226Y3631D01*
X645266Y3506D01*
X645326Y3396D01*
X645406Y3296D01*
X645506Y3216D01*
X645616Y3156D01*
X645741Y3116D01*
X645866Y3106D01*
G37*
G36*
G01X641141D02*
X641266Y3116D01*
X641391Y3156D01*
X641501Y3216D01*
X641601Y3296D01*
X641681Y3396D01*
X641741Y3506D01*
X641781Y3631D01*
X641791Y3756D01*
Y6186D01*
X641821Y6216D01*
X641921Y6356D01*
X641941Y6396D01*
X641956Y6431D01*
X641976Y6471D01*
X641991Y6511D01*
X642001Y6551D01*
X642016Y6596D01*
X642021Y6636D01*
X642031Y6676D01*
X642036Y6721D01*
Y6761D01*
X642041Y6806D01*
X642036Y6851D01*
Y6891D01*
X642031Y6936D01*
X642021Y6976D01*
X642016Y7016D01*
X642001Y7061D01*
X641991Y7101D01*
X641976Y7141D01*
X641956Y7181D01*
X641941Y7216D01*
X641921Y7256D01*
X641821Y7396D01*
X641791Y7426D01*
Y9556D01*
X641781Y9681D01*
X641741Y9806D01*
X641681Y9916D01*
X641601Y10016D01*
X641501Y10096D01*
X641391Y10156D01*
X641266Y10196D01*
X641141Y10206D01*
X641016Y10196D01*
X640891Y10156D01*
X640781Y10096D01*
X640681Y10016D01*
X640601Y9916D01*
X640541Y9806D01*
X640501Y9681D01*
X640491Y9556D01*
Y7431D01*
X640461Y7401D01*
X640436Y7366D01*
X640406Y7331D01*
X640386Y7296D01*
X640361Y7261D01*
X640321Y7181D01*
X640276Y7061D01*
X640266Y7021D01*
X640256Y6976D01*
X640251Y6936D01*
X640241Y6891D01*
Y6721D01*
X640251Y6676D01*
X640256Y6636D01*
X640266Y6591D01*
X640276Y6551D01*
X640321Y6431D01*
X640361Y6351D01*
X640386Y6316D01*
X640406Y6281D01*
X640436Y6246D01*
X640461Y6211D01*
X640491Y6181D01*
Y3756D01*
X640501Y3631D01*
X640541Y3506D01*
X640601Y3396D01*
X640681Y3296D01*
X640781Y3216D01*
X640891Y3156D01*
X641016Y3116D01*
X641141Y3106D01*
G37*
G36*
G01X636417D02*
X636542Y3116D01*
X636667Y3156D01*
X636777Y3216D01*
X636877Y3296D01*
X636957Y3396D01*
X637017Y3506D01*
X637057Y3631D01*
X637067Y3756D01*
Y6186D01*
X637097Y6216D01*
X637197Y6356D01*
X637217Y6396D01*
X637232Y6431D01*
X637252Y6471D01*
X637267Y6511D01*
X637277Y6551D01*
X637292Y6596D01*
X637297Y6636D01*
X637307Y6676D01*
X637312Y6721D01*
Y6761D01*
X637317Y6806D01*
X637312Y6851D01*
Y6891D01*
X637307Y6936D01*
X637297Y6976D01*
X637292Y7016D01*
X637277Y7061D01*
X637267Y7101D01*
X637252Y7141D01*
X637232Y7181D01*
X637217Y7216D01*
X637197Y7256D01*
X637097Y7396D01*
X637067Y7426D01*
Y9556D01*
X637057Y9681D01*
X637017Y9806D01*
X636957Y9916D01*
X636877Y10016D01*
X636777Y10096D01*
X636667Y10156D01*
X636542Y10196D01*
X636417Y10206D01*
X636292Y10196D01*
X636167Y10156D01*
X636057Y10096D01*
X635957Y10016D01*
X635877Y9916D01*
X635817Y9806D01*
X635777Y9681D01*
X635767Y9556D01*
Y7431D01*
X635737Y7401D01*
X635712Y7366D01*
X635682Y7331D01*
X635662Y7296D01*
X635637Y7261D01*
X635597Y7181D01*
X635552Y7061D01*
X635542Y7021D01*
X635532Y6976D01*
X635527Y6936D01*
X635517Y6891D01*
Y6721D01*
X635527Y6676D01*
X635532Y6636D01*
X635542Y6591D01*
X635552Y6551D01*
X635597Y6431D01*
X635637Y6351D01*
X635662Y6316D01*
X635682Y6281D01*
X635712Y6246D01*
X635737Y6211D01*
X635767Y6181D01*
Y3756D01*
X635777Y3631D01*
X635817Y3506D01*
X635877Y3396D01*
X635957Y3296D01*
X636057Y3216D01*
X636167Y3156D01*
X636292Y3116D01*
X636417Y3106D01*
G37*
G36*
G01X664764D02*
X664889Y3116D01*
X665014Y3156D01*
X665124Y3216D01*
X665224Y3296D01*
X665304Y3396D01*
X665364Y3506D01*
X665404Y3631D01*
X665414Y3756D01*
Y6186D01*
X665444Y6216D01*
X665544Y6356D01*
X665564Y6396D01*
X665579Y6431D01*
X665599Y6471D01*
X665614Y6511D01*
X665624Y6551D01*
X665639Y6596D01*
X665644Y6636D01*
X665654Y6676D01*
X665659Y6721D01*
Y6761D01*
X665664Y6806D01*
X665659Y6851D01*
Y6891D01*
X665654Y6936D01*
X665644Y6976D01*
X665639Y7016D01*
X665624Y7061D01*
X665614Y7101D01*
X665599Y7141D01*
X665579Y7181D01*
X665564Y7216D01*
X665544Y7256D01*
X665444Y7396D01*
X665414Y7426D01*
Y9556D01*
X665404Y9681D01*
X665364Y9806D01*
X665304Y9916D01*
X665224Y10016D01*
X665124Y10096D01*
X665014Y10156D01*
X664889Y10196D01*
X664764Y10206D01*
X664639Y10196D01*
X664514Y10156D01*
X664404Y10096D01*
X664304Y10016D01*
X664224Y9916D01*
X664164Y9806D01*
X664124Y9681D01*
X664114Y9556D01*
Y7431D01*
X664084Y7401D01*
X664059Y7366D01*
X664029Y7331D01*
X664009Y7296D01*
X663984Y7261D01*
X663944Y7181D01*
X663899Y7061D01*
X663889Y7021D01*
X663879Y6976D01*
X663874Y6936D01*
X663864Y6891D01*
Y6721D01*
X663874Y6676D01*
X663879Y6636D01*
X663889Y6591D01*
X663899Y6551D01*
X663944Y6431D01*
X663984Y6351D01*
X664009Y6316D01*
X664029Y6281D01*
X664059Y6246D01*
X664084Y6211D01*
X664114Y6181D01*
Y3756D01*
X664124Y3631D01*
X664164Y3506D01*
X664224Y3396D01*
X664304Y3296D01*
X664404Y3216D01*
X664514Y3156D01*
X664639Y3116D01*
X664764Y3106D01*
G37*
G36*
G01X660039D02*
X660164Y3116D01*
X660289Y3156D01*
X660399Y3216D01*
X660499Y3296D01*
X660579Y3396D01*
X660639Y3506D01*
X660679Y3631D01*
X660689Y3756D01*
Y6186D01*
X660719Y6216D01*
X660819Y6356D01*
X660839Y6396D01*
X660854Y6431D01*
X660874Y6471D01*
X660889Y6511D01*
X660899Y6551D01*
X660914Y6596D01*
X660919Y6636D01*
X660929Y6676D01*
X660934Y6721D01*
Y6761D01*
X660939Y6806D01*
X660934Y6851D01*
Y6891D01*
X660929Y6936D01*
X660919Y6976D01*
X660914Y7016D01*
X660899Y7061D01*
X660889Y7101D01*
X660874Y7141D01*
X660854Y7181D01*
X660839Y7216D01*
X660819Y7256D01*
X660719Y7396D01*
X660689Y7426D01*
Y9556D01*
X660679Y9681D01*
X660639Y9806D01*
X660579Y9916D01*
X660499Y10016D01*
X660399Y10096D01*
X660289Y10156D01*
X660164Y10196D01*
X660039Y10206D01*
X659914Y10196D01*
X659789Y10156D01*
X659679Y10096D01*
X659579Y10016D01*
X659499Y9916D01*
X659439Y9806D01*
X659399Y9681D01*
X659389Y9556D01*
Y7431D01*
X659359Y7401D01*
X659334Y7366D01*
X659304Y7331D01*
X659284Y7296D01*
X659259Y7261D01*
X659219Y7181D01*
X659174Y7061D01*
X659164Y7021D01*
X659154Y6976D01*
X659149Y6936D01*
X659139Y6891D01*
Y6721D01*
X659149Y6676D01*
X659154Y6636D01*
X659164Y6591D01*
X659174Y6551D01*
X659219Y6431D01*
X659259Y6351D01*
X659284Y6316D01*
X659304Y6281D01*
X659334Y6246D01*
X659359Y6211D01*
X659389Y6181D01*
Y3756D01*
X659399Y3631D01*
X659439Y3506D01*
X659499Y3396D01*
X659579Y3296D01*
X659679Y3216D01*
X659789Y3156D01*
X659914Y3116D01*
X660039Y3106D01*
G37*
G36*
G01X655315D02*
X655440Y3116D01*
X655565Y3156D01*
X655675Y3216D01*
X655775Y3296D01*
X655855Y3396D01*
X655915Y3506D01*
X655955Y3631D01*
X655965Y3756D01*
Y6186D01*
X655995Y6216D01*
X656095Y6356D01*
X656115Y6396D01*
X656130Y6431D01*
X656150Y6471D01*
X656165Y6511D01*
X656175Y6551D01*
X656190Y6596D01*
X656195Y6636D01*
X656205Y6676D01*
X656210Y6721D01*
Y6761D01*
X656215Y6806D01*
X656210Y6851D01*
Y6891D01*
X656205Y6936D01*
X656195Y6976D01*
X656190Y7016D01*
X656175Y7061D01*
X656165Y7101D01*
X656150Y7141D01*
X656130Y7181D01*
X656115Y7216D01*
X656095Y7256D01*
X655995Y7396D01*
X655965Y7426D01*
Y9556D01*
X655955Y9681D01*
X655915Y9806D01*
X655855Y9916D01*
X655775Y10016D01*
X655675Y10096D01*
X655565Y10156D01*
X655440Y10196D01*
X655315Y10206D01*
X655190Y10196D01*
X655065Y10156D01*
X654955Y10096D01*
X654855Y10016D01*
X654775Y9916D01*
X654715Y9806D01*
X654675Y9681D01*
X654665Y9556D01*
Y7431D01*
X654635Y7401D01*
X654610Y7366D01*
X654580Y7331D01*
X654560Y7296D01*
X654535Y7261D01*
X654495Y7181D01*
X654450Y7061D01*
X654440Y7021D01*
X654430Y6976D01*
X654425Y6936D01*
X654415Y6891D01*
Y6721D01*
X654425Y6676D01*
X654430Y6636D01*
X654440Y6591D01*
X654450Y6551D01*
X654495Y6431D01*
X654535Y6351D01*
X654560Y6316D01*
X654580Y6281D01*
X654610Y6246D01*
X654635Y6211D01*
X654665Y6181D01*
Y3756D01*
X654675Y3631D01*
X654715Y3506D01*
X654775Y3396D01*
X654855Y3296D01*
X654955Y3216D01*
X655065Y3156D01*
X655190Y3116D01*
X655315Y3106D01*
G37*
G36*
G01X650590D02*
X650715Y3116D01*
X650840Y3156D01*
X650950Y3216D01*
X651050Y3296D01*
X651130Y3396D01*
X651190Y3506D01*
X651230Y3631D01*
X651240Y3756D01*
Y6186D01*
X651270Y6216D01*
X651370Y6356D01*
X651390Y6396D01*
X651405Y6431D01*
X651425Y6471D01*
X651440Y6511D01*
X651450Y6551D01*
X651465Y6596D01*
X651470Y6636D01*
X651480Y6676D01*
X651485Y6721D01*
Y6761D01*
X651490Y6806D01*
X651485Y6851D01*
Y6891D01*
X651480Y6936D01*
X651470Y6976D01*
X651465Y7016D01*
X651450Y7061D01*
X651440Y7101D01*
X651425Y7141D01*
X651405Y7181D01*
X651390Y7216D01*
X651370Y7256D01*
X651270Y7396D01*
X651240Y7426D01*
Y9556D01*
X651230Y9681D01*
X651190Y9806D01*
X651130Y9916D01*
X651050Y10016D01*
X650950Y10096D01*
X650840Y10156D01*
X650715Y10196D01*
X650590Y10206D01*
X650465Y10196D01*
X650340Y10156D01*
X650230Y10096D01*
X650130Y10016D01*
X650050Y9916D01*
X649990Y9806D01*
X649950Y9681D01*
X649940Y9556D01*
Y7431D01*
X649910Y7401D01*
X649885Y7366D01*
X649855Y7331D01*
X649835Y7296D01*
X649810Y7261D01*
X649770Y7181D01*
X649725Y7061D01*
X649715Y7021D01*
X649705Y6976D01*
X649700Y6936D01*
X649690Y6891D01*
Y6721D01*
X649700Y6676D01*
X649705Y6636D01*
X649715Y6591D01*
X649725Y6551D01*
X649770Y6431D01*
X649810Y6351D01*
X649835Y6316D01*
X649855Y6281D01*
X649885Y6246D01*
X649910Y6211D01*
X649940Y6181D01*
Y3756D01*
X649950Y3631D01*
X649990Y3506D01*
X650050Y3396D01*
X650130Y3296D01*
X650230Y3216D01*
X650340Y3156D01*
X650465Y3116D01*
X650590Y3106D01*
G37*
G36*
G01X678937D02*
X679062Y3116D01*
X679187Y3156D01*
X679297Y3216D01*
X679397Y3296D01*
X679477Y3396D01*
X679537Y3506D01*
X679577Y3631D01*
X679587Y3756D01*
Y6186D01*
X679617Y6216D01*
X679717Y6356D01*
X679737Y6396D01*
X679752Y6431D01*
X679772Y6471D01*
X679787Y6511D01*
X679797Y6551D01*
X679812Y6596D01*
X679817Y6636D01*
X679827Y6676D01*
X679832Y6721D01*
Y6761D01*
X679837Y6806D01*
X679832Y6851D01*
Y6891D01*
X679827Y6936D01*
X679817Y6976D01*
X679812Y7016D01*
X679797Y7061D01*
X679787Y7101D01*
X679772Y7141D01*
X679752Y7181D01*
X679737Y7216D01*
X679717Y7256D01*
X679617Y7396D01*
X679587Y7426D01*
Y9556D01*
X679577Y9681D01*
X679537Y9806D01*
X679477Y9916D01*
X679397Y10016D01*
X679297Y10096D01*
X679187Y10156D01*
X679062Y10196D01*
X678937Y10206D01*
X678812Y10196D01*
X678687Y10156D01*
X678577Y10096D01*
X678477Y10016D01*
X678397Y9916D01*
X678337Y9806D01*
X678297Y9681D01*
X678287Y9556D01*
Y7431D01*
X678257Y7401D01*
X678232Y7366D01*
X678202Y7331D01*
X678182Y7296D01*
X678157Y7261D01*
X678117Y7181D01*
X678072Y7061D01*
X678062Y7021D01*
X678052Y6976D01*
X678047Y6936D01*
X678037Y6891D01*
Y6721D01*
X678047Y6676D01*
X678052Y6636D01*
X678062Y6591D01*
X678072Y6551D01*
X678117Y6431D01*
X678157Y6351D01*
X678182Y6316D01*
X678202Y6281D01*
X678232Y6246D01*
X678257Y6211D01*
X678287Y6181D01*
Y3756D01*
X678297Y3631D01*
X678337Y3506D01*
X678397Y3396D01*
X678477Y3296D01*
X678577Y3216D01*
X678687Y3156D01*
X678812Y3116D01*
X678937Y3106D01*
G37*
G36*
G01X674212D02*
X674337Y3116D01*
X674462Y3156D01*
X674572Y3216D01*
X674672Y3296D01*
X674752Y3396D01*
X674812Y3506D01*
X674852Y3631D01*
X674862Y3756D01*
Y6186D01*
X674892Y6216D01*
X674992Y6356D01*
X675012Y6396D01*
X675027Y6431D01*
X675047Y6471D01*
X675062Y6511D01*
X675072Y6551D01*
X675087Y6596D01*
X675092Y6636D01*
X675102Y6676D01*
X675107Y6721D01*
Y6761D01*
X675112Y6806D01*
X675107Y6851D01*
Y6891D01*
X675102Y6936D01*
X675092Y6976D01*
X675087Y7016D01*
X675072Y7061D01*
X675062Y7101D01*
X675047Y7141D01*
X675027Y7181D01*
X675012Y7216D01*
X674992Y7256D01*
X674892Y7396D01*
X674862Y7426D01*
Y9556D01*
X674852Y9681D01*
X674812Y9806D01*
X674752Y9916D01*
X674672Y10016D01*
X674572Y10096D01*
X674462Y10156D01*
X674337Y10196D01*
X674212Y10206D01*
X674087Y10196D01*
X673962Y10156D01*
X673852Y10096D01*
X673752Y10016D01*
X673672Y9916D01*
X673612Y9806D01*
X673572Y9681D01*
X673562Y9556D01*
Y7431D01*
X673532Y7401D01*
X673507Y7366D01*
X673477Y7331D01*
X673457Y7296D01*
X673432Y7261D01*
X673392Y7181D01*
X673347Y7061D01*
X673337Y7021D01*
X673327Y6976D01*
X673322Y6936D01*
X673312Y6891D01*
Y6721D01*
X673322Y6676D01*
X673327Y6636D01*
X673337Y6591D01*
X673347Y6551D01*
X673392Y6431D01*
X673432Y6351D01*
X673457Y6316D01*
X673477Y6281D01*
X673507Y6246D01*
X673532Y6211D01*
X673562Y6181D01*
Y3756D01*
X673572Y3631D01*
X673612Y3506D01*
X673672Y3396D01*
X673752Y3296D01*
X673852Y3216D01*
X673962Y3156D01*
X674087Y3116D01*
X674212Y3106D01*
G37*
G36*
G01X669488D02*
X669613Y3116D01*
X669738Y3156D01*
X669848Y3216D01*
X669948Y3296D01*
X670028Y3396D01*
X670088Y3506D01*
X670128Y3631D01*
X670138Y3756D01*
Y6186D01*
X670168Y6216D01*
X670268Y6356D01*
X670288Y6396D01*
X670303Y6431D01*
X670323Y6471D01*
X670338Y6511D01*
X670348Y6551D01*
X670363Y6596D01*
X670368Y6636D01*
X670378Y6676D01*
X670383Y6721D01*
Y6761D01*
X670388Y6806D01*
X670383Y6851D01*
Y6891D01*
X670378Y6936D01*
X670368Y6976D01*
X670363Y7016D01*
X670348Y7061D01*
X670338Y7101D01*
X670323Y7141D01*
X670303Y7181D01*
X670288Y7216D01*
X670268Y7256D01*
X670168Y7396D01*
X670138Y7426D01*
Y9556D01*
X670128Y9681D01*
X670088Y9806D01*
X670028Y9916D01*
X669948Y10016D01*
X669848Y10096D01*
X669738Y10156D01*
X669613Y10196D01*
X669488Y10206D01*
X669363Y10196D01*
X669238Y10156D01*
X669128Y10096D01*
X669028Y10016D01*
X668948Y9916D01*
X668888Y9806D01*
X668848Y9681D01*
X668838Y9556D01*
Y7431D01*
X668808Y7401D01*
X668783Y7366D01*
X668753Y7331D01*
X668733Y7296D01*
X668708Y7261D01*
X668668Y7181D01*
X668623Y7061D01*
X668613Y7021D01*
X668603Y6976D01*
X668598Y6936D01*
X668588Y6891D01*
Y6721D01*
X668598Y6676D01*
X668603Y6636D01*
X668613Y6591D01*
X668623Y6551D01*
X668668Y6431D01*
X668708Y6351D01*
X668733Y6316D01*
X668753Y6281D01*
X668783Y6246D01*
X668808Y6211D01*
X668838Y6181D01*
Y3756D01*
X668848Y3631D01*
X668888Y3506D01*
X668948Y3396D01*
X669028Y3296D01*
X669128Y3216D01*
X669238Y3156D01*
X669363Y3116D01*
X669488Y3106D01*
G37*
G36*
G01X693110D02*
X693235Y3116D01*
X693360Y3156D01*
X693470Y3216D01*
X693570Y3296D01*
X693650Y3396D01*
X693710Y3506D01*
X693750Y3631D01*
X693760Y3756D01*
Y6186D01*
X693790Y6216D01*
X693890Y6356D01*
X693910Y6396D01*
X693925Y6431D01*
X693945Y6471D01*
X693960Y6511D01*
X693970Y6551D01*
X693985Y6596D01*
X693990Y6636D01*
X694000Y6676D01*
X694005Y6721D01*
Y6761D01*
X694010Y6806D01*
X694005Y6851D01*
Y6891D01*
X694000Y6936D01*
X693990Y6976D01*
X693985Y7016D01*
X693970Y7061D01*
X693960Y7101D01*
X693945Y7141D01*
X693925Y7181D01*
X693910Y7216D01*
X693890Y7256D01*
X693790Y7396D01*
X693760Y7426D01*
Y9556D01*
X693750Y9681D01*
X693710Y9806D01*
X693650Y9916D01*
X693570Y10016D01*
X693470Y10096D01*
X693360Y10156D01*
X693235Y10196D01*
X693110Y10206D01*
X692985Y10196D01*
X692860Y10156D01*
X692750Y10096D01*
X692650Y10016D01*
X692570Y9916D01*
X692510Y9806D01*
X692470Y9681D01*
X692460Y9556D01*
Y7431D01*
X692430Y7401D01*
X692405Y7366D01*
X692375Y7331D01*
X692355Y7296D01*
X692330Y7261D01*
X692290Y7181D01*
X692245Y7061D01*
X692235Y7021D01*
X692225Y6976D01*
X692220Y6936D01*
X692210Y6891D01*
Y6721D01*
X692220Y6676D01*
X692225Y6636D01*
X692235Y6591D01*
X692245Y6551D01*
X692290Y6431D01*
X692330Y6351D01*
X692355Y6316D01*
X692375Y6281D01*
X692405Y6246D01*
X692430Y6211D01*
X692460Y6181D01*
Y3756D01*
X692470Y3631D01*
X692510Y3506D01*
X692570Y3396D01*
X692650Y3296D01*
X692750Y3216D01*
X692860Y3156D01*
X692985Y3116D01*
X693110Y3106D01*
G37*
G36*
G01X688386D02*
X688511Y3116D01*
X688636Y3156D01*
X688746Y3216D01*
X688846Y3296D01*
X688926Y3396D01*
X688986Y3506D01*
X689026Y3631D01*
X689036Y3756D01*
Y6186D01*
X689066Y6216D01*
X689166Y6356D01*
X689186Y6396D01*
X689201Y6431D01*
X689221Y6471D01*
X689236Y6511D01*
X689246Y6551D01*
X689261Y6596D01*
X689266Y6636D01*
X689276Y6676D01*
X689281Y6721D01*
Y6761D01*
X689286Y6806D01*
X689281Y6851D01*
Y6891D01*
X689276Y6936D01*
X689266Y6976D01*
X689261Y7016D01*
X689246Y7061D01*
X689236Y7101D01*
X689221Y7141D01*
X689201Y7181D01*
X689186Y7216D01*
X689166Y7256D01*
X689066Y7396D01*
X689036Y7426D01*
Y9556D01*
X689026Y9681D01*
X688986Y9806D01*
X688926Y9916D01*
X688846Y10016D01*
X688746Y10096D01*
X688636Y10156D01*
X688511Y10196D01*
X688386Y10206D01*
X688261Y10196D01*
X688136Y10156D01*
X688026Y10096D01*
X687926Y10016D01*
X687846Y9916D01*
X687786Y9806D01*
X687746Y9681D01*
X687736Y9556D01*
Y7431D01*
X687706Y7401D01*
X687681Y7366D01*
X687651Y7331D01*
X687631Y7296D01*
X687606Y7261D01*
X687566Y7181D01*
X687521Y7061D01*
X687511Y7021D01*
X687501Y6976D01*
X687496Y6936D01*
X687486Y6891D01*
Y6721D01*
X687496Y6676D01*
X687501Y6636D01*
X687511Y6591D01*
X687521Y6551D01*
X687566Y6431D01*
X687606Y6351D01*
X687631Y6316D01*
X687651Y6281D01*
X687681Y6246D01*
X687706Y6211D01*
X687736Y6181D01*
Y3756D01*
X687746Y3631D01*
X687786Y3506D01*
X687846Y3396D01*
X687926Y3296D01*
X688026Y3216D01*
X688136Y3156D01*
X688261Y3116D01*
X688386Y3106D01*
G37*
G36*
G01X683661D02*
X683786Y3116D01*
X683911Y3156D01*
X684021Y3216D01*
X684121Y3296D01*
X684201Y3396D01*
X684261Y3506D01*
X684301Y3631D01*
X684311Y3756D01*
Y6186D01*
X684341Y6216D01*
X684441Y6356D01*
X684461Y6396D01*
X684476Y6431D01*
X684496Y6471D01*
X684511Y6511D01*
X684521Y6551D01*
X684536Y6596D01*
X684541Y6636D01*
X684551Y6676D01*
X684556Y6721D01*
Y6761D01*
X684561Y6806D01*
X684556Y6851D01*
Y6891D01*
X684551Y6936D01*
X684541Y6976D01*
X684536Y7016D01*
X684521Y7061D01*
X684511Y7101D01*
X684496Y7141D01*
X684476Y7181D01*
X684461Y7216D01*
X684441Y7256D01*
X684341Y7396D01*
X684311Y7426D01*
Y9556D01*
X684301Y9681D01*
X684261Y9806D01*
X684201Y9916D01*
X684121Y10016D01*
X684021Y10096D01*
X683911Y10156D01*
X683786Y10196D01*
X683661Y10206D01*
X683536Y10196D01*
X683411Y10156D01*
X683301Y10096D01*
X683201Y10016D01*
X683121Y9916D01*
X683061Y9806D01*
X683021Y9681D01*
X683011Y9556D01*
Y7431D01*
X682981Y7401D01*
X682956Y7366D01*
X682926Y7331D01*
X682906Y7296D01*
X682881Y7261D01*
X682841Y7181D01*
X682796Y7061D01*
X682786Y7021D01*
X682776Y6976D01*
X682771Y6936D01*
X682761Y6891D01*
Y6721D01*
X682771Y6676D01*
X682776Y6636D01*
X682786Y6591D01*
X682796Y6551D01*
X682841Y6431D01*
X682881Y6351D01*
X682906Y6316D01*
X682926Y6281D01*
X682956Y6246D01*
X682981Y6211D01*
X683011Y6181D01*
Y3756D01*
X683021Y3631D01*
X683061Y3506D01*
X683121Y3396D01*
X683201Y3296D01*
X683301Y3216D01*
X683411Y3156D01*
X683536Y3116D01*
X683661Y3106D01*
G37*
G36*
G01X707283D02*
X707408Y3116D01*
X707533Y3156D01*
X707643Y3216D01*
X707743Y3296D01*
X707823Y3396D01*
X707883Y3506D01*
X707923Y3631D01*
X707933Y3756D01*
Y6186D01*
X707963Y6216D01*
X708063Y6356D01*
X708083Y6396D01*
X708098Y6431D01*
X708118Y6471D01*
X708133Y6511D01*
X708143Y6551D01*
X708158Y6596D01*
X708163Y6636D01*
X708173Y6676D01*
X708178Y6721D01*
Y6761D01*
X708183Y6806D01*
X708178Y6851D01*
Y6891D01*
X708173Y6936D01*
X708163Y6976D01*
X708158Y7016D01*
X708143Y7061D01*
X708133Y7101D01*
X708118Y7141D01*
X708098Y7181D01*
X708083Y7216D01*
X708063Y7256D01*
X707963Y7396D01*
X707933Y7426D01*
Y9556D01*
X707923Y9681D01*
X707883Y9806D01*
X707823Y9916D01*
X707743Y10016D01*
X707643Y10096D01*
X707533Y10156D01*
X707408Y10196D01*
X707283Y10206D01*
X707158Y10196D01*
X707033Y10156D01*
X706923Y10096D01*
X706823Y10016D01*
X706743Y9916D01*
X706683Y9806D01*
X706643Y9681D01*
X706633Y9556D01*
Y7431D01*
X706603Y7401D01*
X706578Y7366D01*
X706548Y7331D01*
X706528Y7296D01*
X706503Y7261D01*
X706463Y7181D01*
X706418Y7061D01*
X706408Y7021D01*
X706398Y6976D01*
X706393Y6936D01*
X706383Y6891D01*
Y6721D01*
X706393Y6676D01*
X706398Y6636D01*
X706408Y6591D01*
X706418Y6551D01*
X706463Y6431D01*
X706503Y6351D01*
X706528Y6316D01*
X706548Y6281D01*
X706578Y6246D01*
X706603Y6211D01*
X706633Y6181D01*
Y3756D01*
X706643Y3631D01*
X706683Y3506D01*
X706743Y3396D01*
X706823Y3296D01*
X706923Y3216D01*
X707033Y3156D01*
X707158Y3116D01*
X707283Y3106D01*
G37*
G36*
G01X702559D02*
X702684Y3116D01*
X702809Y3156D01*
X702919Y3216D01*
X703019Y3296D01*
X703099Y3396D01*
X703159Y3506D01*
X703199Y3631D01*
X703209Y3756D01*
Y6186D01*
X703239Y6216D01*
X703339Y6356D01*
X703359Y6396D01*
X703374Y6431D01*
X703394Y6471D01*
X703409Y6511D01*
X703419Y6551D01*
X703434Y6596D01*
X703439Y6636D01*
X703449Y6676D01*
X703454Y6721D01*
Y6761D01*
X703459Y6806D01*
X703454Y6851D01*
Y6891D01*
X703449Y6936D01*
X703439Y6976D01*
X703434Y7016D01*
X703419Y7061D01*
X703409Y7101D01*
X703394Y7141D01*
X703374Y7181D01*
X703359Y7216D01*
X703339Y7256D01*
X703239Y7396D01*
X703209Y7426D01*
Y9556D01*
X703199Y9681D01*
X703159Y9806D01*
X703099Y9916D01*
X703019Y10016D01*
X702919Y10096D01*
X702809Y10156D01*
X702684Y10196D01*
X702559Y10206D01*
X702434Y10196D01*
X702309Y10156D01*
X702199Y10096D01*
X702099Y10016D01*
X702019Y9916D01*
X701959Y9806D01*
X701919Y9681D01*
X701909Y9556D01*
Y7431D01*
X701879Y7401D01*
X701854Y7366D01*
X701824Y7331D01*
X701804Y7296D01*
X701779Y7261D01*
X701739Y7181D01*
X701694Y7061D01*
X701684Y7021D01*
X701674Y6976D01*
X701669Y6936D01*
X701659Y6891D01*
Y6721D01*
X701669Y6676D01*
X701674Y6636D01*
X701684Y6591D01*
X701694Y6551D01*
X701739Y6431D01*
X701779Y6351D01*
X701804Y6316D01*
X701824Y6281D01*
X701854Y6246D01*
X701879Y6211D01*
X701909Y6181D01*
Y3756D01*
X701919Y3631D01*
X701959Y3506D01*
X702019Y3396D01*
X702099Y3296D01*
X702199Y3216D01*
X702309Y3156D01*
X702434Y3116D01*
X702559Y3106D01*
G37*
G36*
G01X697834D02*
X697959Y3116D01*
X698084Y3156D01*
X698194Y3216D01*
X698294Y3296D01*
X698374Y3396D01*
X698434Y3506D01*
X698474Y3631D01*
X698484Y3756D01*
Y6186D01*
X698514Y6216D01*
X698614Y6356D01*
X698634Y6396D01*
X698649Y6431D01*
X698669Y6471D01*
X698684Y6511D01*
X698694Y6551D01*
X698709Y6596D01*
X698714Y6636D01*
X698724Y6676D01*
X698729Y6721D01*
Y6761D01*
X698734Y6806D01*
X698729Y6851D01*
Y6891D01*
X698724Y6936D01*
X698714Y6976D01*
X698709Y7016D01*
X698694Y7061D01*
X698684Y7101D01*
X698669Y7141D01*
X698649Y7181D01*
X698634Y7216D01*
X698614Y7256D01*
X698514Y7396D01*
X698484Y7426D01*
Y9556D01*
X698474Y9681D01*
X698434Y9806D01*
X698374Y9916D01*
X698294Y10016D01*
X698194Y10096D01*
X698084Y10156D01*
X697959Y10196D01*
X697834Y10206D01*
X697709Y10196D01*
X697584Y10156D01*
X697474Y10096D01*
X697374Y10016D01*
X697294Y9916D01*
X697234Y9806D01*
X697194Y9681D01*
X697184Y9556D01*
Y7431D01*
X697154Y7401D01*
X697129Y7366D01*
X697099Y7331D01*
X697079Y7296D01*
X697054Y7261D01*
X697014Y7181D01*
X696969Y7061D01*
X696959Y7021D01*
X696949Y6976D01*
X696944Y6936D01*
X696934Y6891D01*
Y6721D01*
X696944Y6676D01*
X696949Y6636D01*
X696959Y6591D01*
X696969Y6551D01*
X697014Y6431D01*
X697054Y6351D01*
X697079Y6316D01*
X697099Y6281D01*
X697129Y6246D01*
X697154Y6211D01*
X697184Y6181D01*
Y3756D01*
X697194Y3631D01*
X697234Y3506D01*
X697294Y3396D01*
X697374Y3296D01*
X697474Y3216D01*
X697584Y3156D01*
X697709Y3116D01*
X697834Y3106D01*
G37*
G36*
G01X726181D02*
X726306Y3116D01*
X726431Y3156D01*
X726541Y3216D01*
X726641Y3296D01*
X726721Y3396D01*
X726781Y3506D01*
X726821Y3631D01*
X726831Y3756D01*
Y6186D01*
X726861Y6216D01*
X726961Y6356D01*
X726981Y6396D01*
X726996Y6431D01*
X727016Y6471D01*
X727031Y6511D01*
X727041Y6551D01*
X727056Y6596D01*
X727061Y6636D01*
X727071Y6676D01*
X727076Y6721D01*
Y6761D01*
X727081Y6806D01*
X727076Y6851D01*
Y6891D01*
X727071Y6936D01*
X727061Y6976D01*
X727056Y7016D01*
X727041Y7061D01*
X727031Y7101D01*
X727016Y7141D01*
X726996Y7181D01*
X726981Y7216D01*
X726961Y7256D01*
X726861Y7396D01*
X726831Y7426D01*
Y9556D01*
X726821Y9681D01*
X726781Y9806D01*
X726721Y9916D01*
X726641Y10016D01*
X726541Y10096D01*
X726431Y10156D01*
X726306Y10196D01*
X726181Y10206D01*
X726056Y10196D01*
X725931Y10156D01*
X725821Y10096D01*
X725721Y10016D01*
X725641Y9916D01*
X725581Y9806D01*
X725541Y9681D01*
X725531Y9556D01*
Y7431D01*
X725501Y7401D01*
X725476Y7366D01*
X725446Y7331D01*
X725426Y7296D01*
X725401Y7261D01*
X725361Y7181D01*
X725316Y7061D01*
X725306Y7021D01*
X725296Y6976D01*
X725291Y6936D01*
X725281Y6891D01*
Y6721D01*
X725291Y6676D01*
X725296Y6636D01*
X725306Y6591D01*
X725316Y6551D01*
X725361Y6431D01*
X725401Y6351D01*
X725426Y6316D01*
X725446Y6281D01*
X725476Y6246D01*
X725501Y6211D01*
X725531Y6181D01*
Y3756D01*
X725541Y3631D01*
X725581Y3506D01*
X725641Y3396D01*
X725721Y3296D01*
X725821Y3216D01*
X725931Y3156D01*
X726056Y3116D01*
X726181Y3106D01*
G37*
G36*
G01X721456D02*
X721581Y3116D01*
X721706Y3156D01*
X721816Y3216D01*
X721916Y3296D01*
X721996Y3396D01*
X722056Y3506D01*
X722096Y3631D01*
X722106Y3756D01*
Y6186D01*
X722136Y6216D01*
X722236Y6356D01*
X722256Y6396D01*
X722271Y6431D01*
X722291Y6471D01*
X722306Y6511D01*
X722316Y6551D01*
X722331Y6596D01*
X722336Y6636D01*
X722346Y6676D01*
X722351Y6721D01*
Y6761D01*
X722356Y6806D01*
X722351Y6851D01*
Y6891D01*
X722346Y6936D01*
X722336Y6976D01*
X722331Y7016D01*
X722316Y7061D01*
X722306Y7101D01*
X722291Y7141D01*
X722271Y7181D01*
X722256Y7216D01*
X722236Y7256D01*
X722136Y7396D01*
X722106Y7426D01*
Y9556D01*
X722096Y9681D01*
X722056Y9806D01*
X721996Y9916D01*
X721916Y10016D01*
X721816Y10096D01*
X721706Y10156D01*
X721581Y10196D01*
X721456Y10206D01*
X721331Y10196D01*
X721206Y10156D01*
X721096Y10096D01*
X720996Y10016D01*
X720916Y9916D01*
X720856Y9806D01*
X720816Y9681D01*
X720806Y9556D01*
Y7431D01*
X720776Y7401D01*
X720751Y7366D01*
X720721Y7331D01*
X720701Y7296D01*
X720676Y7261D01*
X720636Y7181D01*
X720591Y7061D01*
X720581Y7021D01*
X720571Y6976D01*
X720566Y6936D01*
X720556Y6891D01*
Y6721D01*
X720566Y6676D01*
X720571Y6636D01*
X720581Y6591D01*
X720591Y6551D01*
X720636Y6431D01*
X720676Y6351D01*
X720701Y6316D01*
X720721Y6281D01*
X720751Y6246D01*
X720776Y6211D01*
X720806Y6181D01*
Y3756D01*
X720816Y3631D01*
X720856Y3506D01*
X720916Y3396D01*
X720996Y3296D01*
X721096Y3216D01*
X721206Y3156D01*
X721331Y3116D01*
X721456Y3106D01*
G37*
G36*
G01X716732D02*
X716857Y3116D01*
X716982Y3156D01*
X717092Y3216D01*
X717192Y3296D01*
X717272Y3396D01*
X717332Y3506D01*
X717372Y3631D01*
X717382Y3756D01*
Y6186D01*
X717412Y6216D01*
X717512Y6356D01*
X717532Y6396D01*
X717547Y6431D01*
X717567Y6471D01*
X717582Y6511D01*
X717592Y6551D01*
X717607Y6596D01*
X717612Y6636D01*
X717622Y6676D01*
X717627Y6721D01*
Y6761D01*
X717632Y6806D01*
X717627Y6851D01*
Y6891D01*
X717622Y6936D01*
X717612Y6976D01*
X717607Y7016D01*
X717592Y7061D01*
X717582Y7101D01*
X717567Y7141D01*
X717547Y7181D01*
X717532Y7216D01*
X717512Y7256D01*
X717412Y7396D01*
X717382Y7426D01*
Y9556D01*
X717372Y9681D01*
X717332Y9806D01*
X717272Y9916D01*
X717192Y10016D01*
X717092Y10096D01*
X716982Y10156D01*
X716857Y10196D01*
X716732Y10206D01*
X716607Y10196D01*
X716482Y10156D01*
X716372Y10096D01*
X716272Y10016D01*
X716192Y9916D01*
X716132Y9806D01*
X716092Y9681D01*
X716082Y9556D01*
Y7431D01*
X716052Y7401D01*
X716027Y7366D01*
X715997Y7331D01*
X715977Y7296D01*
X715952Y7261D01*
X715912Y7181D01*
X715867Y7061D01*
X715857Y7021D01*
X715847Y6976D01*
X715842Y6936D01*
X715832Y6891D01*
Y6721D01*
X715842Y6676D01*
X715847Y6636D01*
X715857Y6591D01*
X715867Y6551D01*
X715912Y6431D01*
X715952Y6351D01*
X715977Y6316D01*
X715997Y6281D01*
X716027Y6246D01*
X716052Y6211D01*
X716082Y6181D01*
Y3756D01*
X716092Y3631D01*
X716132Y3506D01*
X716192Y3396D01*
X716272Y3296D01*
X716372Y3216D01*
X716482Y3156D01*
X716607Y3116D01*
X716732Y3106D01*
G37*
G36*
G01X712008D02*
X712133Y3116D01*
X712258Y3156D01*
X712368Y3216D01*
X712468Y3296D01*
X712548Y3396D01*
X712608Y3506D01*
X712648Y3631D01*
X712658Y3756D01*
Y6186D01*
X712688Y6216D01*
X712788Y6356D01*
X712808Y6396D01*
X712823Y6431D01*
X712843Y6471D01*
X712858Y6511D01*
X712868Y6551D01*
X712883Y6596D01*
X712888Y6636D01*
X712898Y6676D01*
X712903Y6721D01*
Y6761D01*
X712908Y6806D01*
X712903Y6851D01*
Y6891D01*
X712898Y6936D01*
X712888Y6976D01*
X712883Y7016D01*
X712868Y7061D01*
X712858Y7101D01*
X712843Y7141D01*
X712823Y7181D01*
X712808Y7216D01*
X712788Y7256D01*
X712688Y7396D01*
X712658Y7426D01*
Y9556D01*
X712648Y9681D01*
X712608Y9806D01*
X712548Y9916D01*
X712468Y10016D01*
X712368Y10096D01*
X712258Y10156D01*
X712133Y10196D01*
X712008Y10206D01*
X711883Y10196D01*
X711758Y10156D01*
X711648Y10096D01*
X711548Y10016D01*
X711468Y9916D01*
X711408Y9806D01*
X711368Y9681D01*
X711358Y9556D01*
Y7431D01*
X711328Y7401D01*
X711303Y7366D01*
X711273Y7331D01*
X711253Y7296D01*
X711228Y7261D01*
X711188Y7181D01*
X711143Y7061D01*
X711133Y7021D01*
X711123Y6976D01*
X711118Y6936D01*
X711108Y6891D01*
Y6721D01*
X711118Y6676D01*
X711123Y6636D01*
X711133Y6591D01*
X711143Y6551D01*
X711188Y6431D01*
X711228Y6351D01*
X711253Y6316D01*
X711273Y6281D01*
X711303Y6246D01*
X711328Y6211D01*
X711358Y6181D01*
Y3756D01*
X711368Y3631D01*
X711408Y3506D01*
X711468Y3396D01*
X711548Y3296D01*
X711648Y3216D01*
X711758Y3156D01*
X711883Y3116D01*
X712008Y3106D01*
G37*
G36*
G01X740354D02*
X740479Y3116D01*
X740604Y3156D01*
X740714Y3216D01*
X740814Y3296D01*
X740894Y3396D01*
X740954Y3506D01*
X740994Y3631D01*
X741004Y3756D01*
Y6186D01*
X741034Y6216D01*
X741134Y6356D01*
X741154Y6396D01*
X741169Y6431D01*
X741189Y6471D01*
X741204Y6511D01*
X741214Y6551D01*
X741229Y6596D01*
X741234Y6636D01*
X741244Y6676D01*
X741249Y6721D01*
Y6761D01*
X741254Y6806D01*
X741249Y6851D01*
Y6891D01*
X741244Y6936D01*
X741234Y6976D01*
X741229Y7016D01*
X741214Y7061D01*
X741204Y7101D01*
X741189Y7141D01*
X741169Y7181D01*
X741154Y7216D01*
X741134Y7256D01*
X741034Y7396D01*
X741004Y7426D01*
Y9556D01*
X740994Y9681D01*
X740954Y9806D01*
X740894Y9916D01*
X740814Y10016D01*
X740714Y10096D01*
X740604Y10156D01*
X740479Y10196D01*
X740354Y10206D01*
X740229Y10196D01*
X740104Y10156D01*
X739994Y10096D01*
X739894Y10016D01*
X739814Y9916D01*
X739754Y9806D01*
X739714Y9681D01*
X739704Y9556D01*
Y7431D01*
X739674Y7401D01*
X739649Y7366D01*
X739619Y7331D01*
X739599Y7296D01*
X739574Y7261D01*
X739534Y7181D01*
X739489Y7061D01*
X739479Y7021D01*
X739469Y6976D01*
X739464Y6936D01*
X739454Y6891D01*
Y6721D01*
X739464Y6676D01*
X739469Y6636D01*
X739479Y6591D01*
X739489Y6551D01*
X739534Y6431D01*
X739574Y6351D01*
X739599Y6316D01*
X739619Y6281D01*
X739649Y6246D01*
X739674Y6211D01*
X739704Y6181D01*
Y3756D01*
X739714Y3631D01*
X739754Y3506D01*
X739814Y3396D01*
X739894Y3296D01*
X739994Y3216D01*
X740104Y3156D01*
X740229Y3116D01*
X740354Y3106D01*
G37*
G36*
G01X735630D02*
X735755Y3116D01*
X735880Y3156D01*
X735990Y3216D01*
X736090Y3296D01*
X736170Y3396D01*
X736230Y3506D01*
X736270Y3631D01*
X736280Y3756D01*
Y6186D01*
X736310Y6216D01*
X736410Y6356D01*
X736430Y6396D01*
X736445Y6431D01*
X736465Y6471D01*
X736480Y6511D01*
X736490Y6551D01*
X736505Y6596D01*
X736510Y6636D01*
X736520Y6676D01*
X736525Y6721D01*
Y6761D01*
X736530Y6806D01*
X736525Y6851D01*
Y6891D01*
X736520Y6936D01*
X736510Y6976D01*
X736505Y7016D01*
X736490Y7061D01*
X736480Y7101D01*
X736465Y7141D01*
X736445Y7181D01*
X736430Y7216D01*
X736410Y7256D01*
X736310Y7396D01*
X736280Y7426D01*
Y9556D01*
X736270Y9681D01*
X736230Y9806D01*
X736170Y9916D01*
X736090Y10016D01*
X735990Y10096D01*
X735880Y10156D01*
X735755Y10196D01*
X735630Y10206D01*
X735505Y10196D01*
X735380Y10156D01*
X735270Y10096D01*
X735170Y10016D01*
X735090Y9916D01*
X735030Y9806D01*
X734990Y9681D01*
X734980Y9556D01*
Y7431D01*
X734950Y7401D01*
X734925Y7366D01*
X734895Y7331D01*
X734875Y7296D01*
X734850Y7261D01*
X734810Y7181D01*
X734765Y7061D01*
X734755Y7021D01*
X734745Y6976D01*
X734740Y6936D01*
X734730Y6891D01*
Y6721D01*
X734740Y6676D01*
X734745Y6636D01*
X734755Y6591D01*
X734765Y6551D01*
X734810Y6431D01*
X734850Y6351D01*
X734875Y6316D01*
X734895Y6281D01*
X734925Y6246D01*
X734950Y6211D01*
X734980Y6181D01*
Y3756D01*
X734990Y3631D01*
X735030Y3506D01*
X735090Y3396D01*
X735170Y3296D01*
X735270Y3216D01*
X735380Y3156D01*
X735505Y3116D01*
X735630Y3106D01*
G37*
G36*
G01X730905D02*
X731030Y3116D01*
X731155Y3156D01*
X731265Y3216D01*
X731365Y3296D01*
X731445Y3396D01*
X731505Y3506D01*
X731545Y3631D01*
X731555Y3756D01*
Y6186D01*
X731585Y6216D01*
X731685Y6356D01*
X731705Y6396D01*
X731720Y6431D01*
X731740Y6471D01*
X731755Y6511D01*
X731765Y6551D01*
X731780Y6596D01*
X731785Y6636D01*
X731795Y6676D01*
X731800Y6721D01*
Y6761D01*
X731805Y6806D01*
X731800Y6851D01*
Y6891D01*
X731795Y6936D01*
X731785Y6976D01*
X731780Y7016D01*
X731765Y7061D01*
X731755Y7101D01*
X731740Y7141D01*
X731720Y7181D01*
X731705Y7216D01*
X731685Y7256D01*
X731585Y7396D01*
X731555Y7426D01*
Y9556D01*
X731545Y9681D01*
X731505Y9806D01*
X731445Y9916D01*
X731365Y10016D01*
X731265Y10096D01*
X731155Y10156D01*
X731030Y10196D01*
X730905Y10206D01*
X730780Y10196D01*
X730655Y10156D01*
X730545Y10096D01*
X730445Y10016D01*
X730365Y9916D01*
X730305Y9806D01*
X730265Y9681D01*
X730255Y9556D01*
Y7431D01*
X730225Y7401D01*
X730200Y7366D01*
X730170Y7331D01*
X730150Y7296D01*
X730125Y7261D01*
X730085Y7181D01*
X730040Y7061D01*
X730030Y7021D01*
X730020Y6976D01*
X730015Y6936D01*
X730005Y6891D01*
Y6721D01*
X730015Y6676D01*
X730020Y6636D01*
X730030Y6591D01*
X730040Y6551D01*
X730085Y6431D01*
X730125Y6351D01*
X730150Y6316D01*
X730170Y6281D01*
X730200Y6246D01*
X730225Y6211D01*
X730255Y6181D01*
Y3756D01*
X730265Y3631D01*
X730305Y3506D01*
X730365Y3396D01*
X730445Y3296D01*
X730545Y3216D01*
X730655Y3156D01*
X730780Y3116D01*
X730905Y3106D01*
G37*
G36*
G01X754527D02*
X754652Y3116D01*
X754777Y3156D01*
X754887Y3216D01*
X754987Y3296D01*
X755067Y3396D01*
X755127Y3506D01*
X755167Y3631D01*
X755177Y3756D01*
Y6186D01*
X755207Y6216D01*
X755307Y6356D01*
X755327Y6396D01*
X755342Y6431D01*
X755362Y6471D01*
X755377Y6511D01*
X755387Y6551D01*
X755402Y6596D01*
X755407Y6636D01*
X755417Y6676D01*
X755422Y6721D01*
Y6761D01*
X755427Y6806D01*
X755422Y6851D01*
Y6891D01*
X755417Y6936D01*
X755407Y6976D01*
X755402Y7016D01*
X755387Y7061D01*
X755377Y7101D01*
X755362Y7141D01*
X755342Y7181D01*
X755327Y7216D01*
X755307Y7256D01*
X755207Y7396D01*
X755177Y7426D01*
Y9556D01*
X755167Y9681D01*
X755127Y9806D01*
X755067Y9916D01*
X754987Y10016D01*
X754887Y10096D01*
X754777Y10156D01*
X754652Y10196D01*
X754527Y10206D01*
X754402Y10196D01*
X754277Y10156D01*
X754167Y10096D01*
X754067Y10016D01*
X753987Y9916D01*
X753927Y9806D01*
X753887Y9681D01*
X753877Y9556D01*
Y7431D01*
X753847Y7401D01*
X753822Y7366D01*
X753792Y7331D01*
X753772Y7296D01*
X753747Y7261D01*
X753707Y7181D01*
X753662Y7061D01*
X753652Y7021D01*
X753642Y6976D01*
X753637Y6936D01*
X753627Y6891D01*
Y6721D01*
X753637Y6676D01*
X753642Y6636D01*
X753652Y6591D01*
X753662Y6551D01*
X753707Y6431D01*
X753747Y6351D01*
X753772Y6316D01*
X753792Y6281D01*
X753822Y6246D01*
X753847Y6211D01*
X753877Y6181D01*
Y3756D01*
X753887Y3631D01*
X753927Y3506D01*
X753987Y3396D01*
X754067Y3296D01*
X754167Y3216D01*
X754277Y3156D01*
X754402Y3116D01*
X754527Y3106D01*
G37*
G36*
G01X749803D02*
X749928Y3116D01*
X750053Y3156D01*
X750163Y3216D01*
X750263Y3296D01*
X750343Y3396D01*
X750403Y3506D01*
X750443Y3631D01*
X750453Y3756D01*
Y6186D01*
X750483Y6216D01*
X750583Y6356D01*
X750603Y6396D01*
X750618Y6431D01*
X750638Y6471D01*
X750653Y6511D01*
X750663Y6551D01*
X750678Y6596D01*
X750683Y6636D01*
X750693Y6676D01*
X750698Y6721D01*
Y6761D01*
X750703Y6806D01*
X750698Y6851D01*
Y6891D01*
X750693Y6936D01*
X750683Y6976D01*
X750678Y7016D01*
X750663Y7061D01*
X750653Y7101D01*
X750638Y7141D01*
X750618Y7181D01*
X750603Y7216D01*
X750583Y7256D01*
X750483Y7396D01*
X750453Y7426D01*
Y9556D01*
X750443Y9681D01*
X750403Y9806D01*
X750343Y9916D01*
X750263Y10016D01*
X750163Y10096D01*
X750053Y10156D01*
X749928Y10196D01*
X749803Y10206D01*
X749678Y10196D01*
X749553Y10156D01*
X749443Y10096D01*
X749343Y10016D01*
X749263Y9916D01*
X749203Y9806D01*
X749163Y9681D01*
X749153Y9556D01*
Y7431D01*
X749123Y7401D01*
X749098Y7366D01*
X749068Y7331D01*
X749048Y7296D01*
X749023Y7261D01*
X748983Y7181D01*
X748938Y7061D01*
X748928Y7021D01*
X748918Y6976D01*
X748913Y6936D01*
X748903Y6891D01*
Y6721D01*
X748913Y6676D01*
X748918Y6636D01*
X748928Y6591D01*
X748938Y6551D01*
X748983Y6431D01*
X749023Y6351D01*
X749048Y6316D01*
X749068Y6281D01*
X749098Y6246D01*
X749123Y6211D01*
X749153Y6181D01*
Y3756D01*
X749163Y3631D01*
X749203Y3506D01*
X749263Y3396D01*
X749343Y3296D01*
X749443Y3216D01*
X749553Y3156D01*
X749678Y3116D01*
X749803Y3106D01*
G37*
G36*
G01X745078D02*
X745203Y3116D01*
X745328Y3156D01*
X745438Y3216D01*
X745538Y3296D01*
X745618Y3396D01*
X745678Y3506D01*
X745718Y3631D01*
X745728Y3756D01*
Y6186D01*
X745758Y6216D01*
X745858Y6356D01*
X745878Y6396D01*
X745893Y6431D01*
X745913Y6471D01*
X745928Y6511D01*
X745938Y6551D01*
X745953Y6596D01*
X745958Y6636D01*
X745968Y6676D01*
X745973Y6721D01*
Y6761D01*
X745978Y6806D01*
X745973Y6851D01*
Y6891D01*
X745968Y6936D01*
X745958Y6976D01*
X745953Y7016D01*
X745938Y7061D01*
X745928Y7101D01*
X745913Y7141D01*
X745893Y7181D01*
X745878Y7216D01*
X745858Y7256D01*
X745758Y7396D01*
X745728Y7426D01*
Y9556D01*
X745718Y9681D01*
X745678Y9806D01*
X745618Y9916D01*
X745538Y10016D01*
X745438Y10096D01*
X745328Y10156D01*
X745203Y10196D01*
X745078Y10206D01*
X744953Y10196D01*
X744828Y10156D01*
X744718Y10096D01*
X744618Y10016D01*
X744538Y9916D01*
X744478Y9806D01*
X744438Y9681D01*
X744428Y9556D01*
Y7431D01*
X744398Y7401D01*
X744373Y7366D01*
X744343Y7331D01*
X744323Y7296D01*
X744298Y7261D01*
X744258Y7181D01*
X744213Y7061D01*
X744203Y7021D01*
X744193Y6976D01*
X744188Y6936D01*
X744178Y6891D01*
Y6721D01*
X744188Y6676D01*
X744193Y6636D01*
X744203Y6591D01*
X744213Y6551D01*
X744258Y6431D01*
X744298Y6351D01*
X744323Y6316D01*
X744343Y6281D01*
X744373Y6246D01*
X744398Y6211D01*
X744428Y6181D01*
Y3756D01*
X744438Y3631D01*
X744478Y3506D01*
X744538Y3396D01*
X744618Y3296D01*
X744718Y3216D01*
X744828Y3156D01*
X744953Y3116D01*
X745078Y3106D01*
G37*
G54D94*
X771791Y272260D03*
Y279740D03*
X780209Y276000D03*
G54D76*
X380000Y263461D03*
G54D67*
X314639Y74202D03*
Y71643D03*
Y69084D03*
Y66525D03*
Y76761D03*
X333125Y66525D03*
Y69084D03*
Y71643D03*
Y74202D03*
Y76761D03*
G54D49*
X169485Y198021D03*
Y196446D03*
Y194871D03*
Y193296D03*
Y191722D03*
Y190147D03*
Y188572D03*
Y186997D03*
Y185422D03*
Y199596D03*
X191607Y185422D03*
Y186997D03*
Y188572D03*
Y190147D03*
Y191722D03*
Y193296D03*
Y194871D03*
Y196446D03*
Y198021D03*
Y199596D03*
G54D58*
X249410Y67126D03*
Y182480D03*
G36*
G01X506496Y3106D02*
X506621Y3116D01*
X506746Y3156D01*
X506856Y3216D01*
X506956Y3296D01*
X507036Y3396D01*
X507096Y3506D01*
X507136Y3631D01*
X507146Y3756D01*
Y7186D01*
X507176Y7216D01*
X507276Y7356D01*
X507296Y7396D01*
X507311Y7431D01*
X507331Y7471D01*
X507346Y7511D01*
X507356Y7551D01*
X507371Y7596D01*
X507376Y7636D01*
X507386Y7676D01*
X507391Y7721D01*
Y7761D01*
X507396Y7806D01*
X507391Y7851D01*
Y7891D01*
X507386Y7936D01*
X507376Y7976D01*
X507371Y8016D01*
X507356Y8061D01*
X507346Y8101D01*
X507331Y8141D01*
X507311Y8181D01*
X507296Y8216D01*
X507276Y8256D01*
X507176Y8396D01*
X507146Y8426D01*
Y9556D01*
X507136Y9681D01*
X507096Y9806D01*
X507036Y9916D01*
X506956Y10016D01*
X506856Y10096D01*
X506746Y10156D01*
X506621Y10196D01*
X506496Y10206D01*
X506371Y10196D01*
X506246Y10156D01*
X506136Y10096D01*
X506036Y10016D01*
X505956Y9916D01*
X505896Y9806D01*
X505856Y9681D01*
X505846Y9556D01*
Y8426D01*
X505816Y8396D01*
X505716Y8256D01*
X505696Y8216D01*
X505681Y8181D01*
X505661Y8141D01*
X505646Y8101D01*
X505636Y8061D01*
X505621Y8016D01*
X505616Y7976D01*
X505606Y7936D01*
X505601Y7891D01*
Y7851D01*
X505596Y7806D01*
X505601Y7761D01*
Y7721D01*
X505606Y7676D01*
X505616Y7636D01*
X505621Y7596D01*
X505636Y7551D01*
X505646Y7511D01*
X505661Y7471D01*
X505681Y7431D01*
X505696Y7396D01*
X505716Y7356D01*
X505816Y7216D01*
X505846Y7186D01*
Y3756D01*
X505856Y3631D01*
X505896Y3506D01*
X505956Y3396D01*
X506036Y3296D01*
X506136Y3216D01*
X506246Y3156D01*
X506371Y3116D01*
X506496Y3106D01*
G37*
G36*
G01X525393D02*
X525518Y3116D01*
X525643Y3156D01*
X525753Y3216D01*
X525853Y3296D01*
X525933Y3396D01*
X525993Y3506D01*
X526033Y3631D01*
X526043Y3756D01*
Y7186D01*
X526073Y7216D01*
X526173Y7356D01*
X526193Y7396D01*
X526208Y7431D01*
X526228Y7471D01*
X526243Y7511D01*
X526253Y7551D01*
X526268Y7596D01*
X526273Y7636D01*
X526283Y7676D01*
X526288Y7721D01*
Y7761D01*
X526293Y7806D01*
X526288Y7851D01*
Y7891D01*
X526283Y7936D01*
X526273Y7976D01*
X526268Y8016D01*
X526253Y8061D01*
X526243Y8101D01*
X526228Y8141D01*
X526208Y8181D01*
X526193Y8216D01*
X526173Y8256D01*
X526073Y8396D01*
X526043Y8426D01*
Y9556D01*
X526033Y9681D01*
X525993Y9806D01*
X525933Y9916D01*
X525853Y10016D01*
X525753Y10096D01*
X525643Y10156D01*
X525518Y10196D01*
X525393Y10206D01*
X525268Y10196D01*
X525143Y10156D01*
X525033Y10096D01*
X524933Y10016D01*
X524853Y9916D01*
X524793Y9806D01*
X524753Y9681D01*
X524743Y9556D01*
Y8426D01*
X524713Y8396D01*
X524613Y8256D01*
X524593Y8216D01*
X524578Y8181D01*
X524558Y8141D01*
X524543Y8101D01*
X524533Y8061D01*
X524518Y8016D01*
X524513Y7976D01*
X524503Y7936D01*
X524498Y7891D01*
Y7851D01*
X524493Y7806D01*
X524498Y7761D01*
Y7721D01*
X524503Y7676D01*
X524513Y7636D01*
X524518Y7596D01*
X524533Y7551D01*
X524543Y7511D01*
X524558Y7471D01*
X524578Y7431D01*
X524593Y7396D01*
X524613Y7356D01*
X524713Y7216D01*
X524743Y7186D01*
Y3756D01*
X524753Y3631D01*
X524793Y3506D01*
X524853Y3396D01*
X524933Y3296D01*
X525033Y3216D01*
X525143Y3156D01*
X525268Y3116D01*
X525393Y3106D01*
G37*
G36*
G01X520669D02*
X520794Y3116D01*
X520919Y3156D01*
X521029Y3216D01*
X521129Y3296D01*
X521209Y3396D01*
X521269Y3506D01*
X521309Y3631D01*
X521319Y3756D01*
Y7186D01*
X521349Y7216D01*
X521449Y7356D01*
X521469Y7396D01*
X521484Y7431D01*
X521504Y7471D01*
X521519Y7511D01*
X521529Y7551D01*
X521544Y7596D01*
X521549Y7636D01*
X521559Y7676D01*
X521564Y7721D01*
Y7761D01*
X521569Y7806D01*
X521564Y7851D01*
Y7891D01*
X521559Y7936D01*
X521549Y7976D01*
X521544Y8016D01*
X521529Y8061D01*
X521519Y8101D01*
X521504Y8141D01*
X521484Y8181D01*
X521469Y8216D01*
X521449Y8256D01*
X521349Y8396D01*
X521319Y8426D01*
Y9556D01*
X521309Y9681D01*
X521269Y9806D01*
X521209Y9916D01*
X521129Y10016D01*
X521029Y10096D01*
X520919Y10156D01*
X520794Y10196D01*
X520669Y10206D01*
X520544Y10196D01*
X520419Y10156D01*
X520309Y10096D01*
X520209Y10016D01*
X520129Y9916D01*
X520069Y9806D01*
X520029Y9681D01*
X520019Y9556D01*
Y8426D01*
X519989Y8396D01*
X519889Y8256D01*
X519869Y8216D01*
X519854Y8181D01*
X519834Y8141D01*
X519819Y8101D01*
X519809Y8061D01*
X519794Y8016D01*
X519789Y7976D01*
X519779Y7936D01*
X519774Y7891D01*
Y7851D01*
X519769Y7806D01*
X519774Y7761D01*
Y7721D01*
X519779Y7676D01*
X519789Y7636D01*
X519794Y7596D01*
X519809Y7551D01*
X519819Y7511D01*
X519834Y7471D01*
X519854Y7431D01*
X519869Y7396D01*
X519889Y7356D01*
X519989Y7216D01*
X520019Y7186D01*
Y3756D01*
X520029Y3631D01*
X520069Y3506D01*
X520129Y3396D01*
X520209Y3296D01*
X520309Y3216D01*
X520419Y3156D01*
X520544Y3116D01*
X520669Y3106D01*
G37*
G36*
G01X515945D02*
X516070Y3116D01*
X516195Y3156D01*
X516305Y3216D01*
X516405Y3296D01*
X516485Y3396D01*
X516545Y3506D01*
X516585Y3631D01*
X516595Y3756D01*
Y7186D01*
X516625Y7216D01*
X516725Y7356D01*
X516745Y7396D01*
X516760Y7431D01*
X516780Y7471D01*
X516795Y7511D01*
X516805Y7551D01*
X516820Y7596D01*
X516825Y7636D01*
X516835Y7676D01*
X516840Y7721D01*
Y7761D01*
X516845Y7806D01*
X516840Y7851D01*
Y7891D01*
X516835Y7936D01*
X516825Y7976D01*
X516820Y8016D01*
X516805Y8061D01*
X516795Y8101D01*
X516780Y8141D01*
X516760Y8181D01*
X516745Y8216D01*
X516725Y8256D01*
X516625Y8396D01*
X516595Y8426D01*
Y9556D01*
X516585Y9681D01*
X516545Y9806D01*
X516485Y9916D01*
X516405Y10016D01*
X516305Y10096D01*
X516195Y10156D01*
X516070Y10196D01*
X515945Y10206D01*
X515820Y10196D01*
X515695Y10156D01*
X515585Y10096D01*
X515485Y10016D01*
X515405Y9916D01*
X515345Y9806D01*
X515305Y9681D01*
X515295Y9556D01*
Y8426D01*
X515265Y8396D01*
X515165Y8256D01*
X515145Y8216D01*
X515130Y8181D01*
X515110Y8141D01*
X515095Y8101D01*
X515085Y8061D01*
X515070Y8016D01*
X515065Y7976D01*
X515055Y7936D01*
X515050Y7891D01*
Y7851D01*
X515045Y7806D01*
X515050Y7761D01*
Y7721D01*
X515055Y7676D01*
X515065Y7636D01*
X515070Y7596D01*
X515085Y7551D01*
X515095Y7511D01*
X515110Y7471D01*
X515130Y7431D01*
X515145Y7396D01*
X515165Y7356D01*
X515265Y7216D01*
X515295Y7186D01*
Y3756D01*
X515305Y3631D01*
X515345Y3506D01*
X515405Y3396D01*
X515485Y3296D01*
X515585Y3216D01*
X515695Y3156D01*
X515820Y3116D01*
X515945Y3106D01*
G37*
G36*
G01X511220D02*
X511345Y3116D01*
X511470Y3156D01*
X511580Y3216D01*
X511680Y3296D01*
X511760Y3396D01*
X511820Y3506D01*
X511860Y3631D01*
X511870Y3756D01*
Y7186D01*
X511900Y7216D01*
X512000Y7356D01*
X512020Y7396D01*
X512035Y7431D01*
X512055Y7471D01*
X512070Y7511D01*
X512080Y7551D01*
X512095Y7596D01*
X512100Y7636D01*
X512110Y7676D01*
X512115Y7721D01*
Y7761D01*
X512120Y7806D01*
X512115Y7851D01*
Y7891D01*
X512110Y7936D01*
X512100Y7976D01*
X512095Y8016D01*
X512080Y8061D01*
X512070Y8101D01*
X512055Y8141D01*
X512035Y8181D01*
X512020Y8216D01*
X512000Y8256D01*
X511900Y8396D01*
X511870Y8426D01*
Y9556D01*
X511860Y9681D01*
X511820Y9806D01*
X511760Y9916D01*
X511680Y10016D01*
X511580Y10096D01*
X511470Y10156D01*
X511345Y10196D01*
X511220Y10206D01*
X511095Y10196D01*
X510970Y10156D01*
X510860Y10096D01*
X510760Y10016D01*
X510680Y9916D01*
X510620Y9806D01*
X510580Y9681D01*
X510570Y9556D01*
Y8426D01*
X510540Y8396D01*
X510440Y8256D01*
X510420Y8216D01*
X510405Y8181D01*
X510385Y8141D01*
X510370Y8101D01*
X510360Y8061D01*
X510345Y8016D01*
X510340Y7976D01*
X510330Y7936D01*
X510325Y7891D01*
Y7851D01*
X510320Y7806D01*
X510325Y7761D01*
Y7721D01*
X510330Y7676D01*
X510340Y7636D01*
X510345Y7596D01*
X510360Y7551D01*
X510370Y7511D01*
X510385Y7471D01*
X510405Y7431D01*
X510420Y7396D01*
X510440Y7356D01*
X510540Y7216D01*
X510570Y7186D01*
Y3756D01*
X510580Y3631D01*
X510620Y3506D01*
X510680Y3396D01*
X510760Y3296D01*
X510860Y3216D01*
X510970Y3156D01*
X511095Y3116D01*
X511220Y3106D01*
G37*
G36*
G01X539567D02*
X539692Y3116D01*
X539817Y3156D01*
X539927Y3216D01*
X540027Y3296D01*
X540107Y3396D01*
X540167Y3506D01*
X540207Y3631D01*
X540217Y3756D01*
Y7186D01*
X540247Y7216D01*
X540347Y7356D01*
X540367Y7396D01*
X540382Y7431D01*
X540402Y7471D01*
X540417Y7511D01*
X540427Y7551D01*
X540442Y7596D01*
X540447Y7636D01*
X540457Y7676D01*
X540462Y7721D01*
Y7761D01*
X540467Y7806D01*
X540462Y7851D01*
Y7891D01*
X540457Y7936D01*
X540447Y7976D01*
X540442Y8016D01*
X540427Y8061D01*
X540417Y8101D01*
X540402Y8141D01*
X540382Y8181D01*
X540367Y8216D01*
X540347Y8256D01*
X540247Y8396D01*
X540217Y8426D01*
Y9556D01*
X540207Y9681D01*
X540167Y9806D01*
X540107Y9916D01*
X540027Y10016D01*
X539927Y10096D01*
X539817Y10156D01*
X539692Y10196D01*
X539567Y10206D01*
X539442Y10196D01*
X539317Y10156D01*
X539207Y10096D01*
X539107Y10016D01*
X539027Y9916D01*
X538967Y9806D01*
X538927Y9681D01*
X538917Y9556D01*
Y8426D01*
X538887Y8396D01*
X538787Y8256D01*
X538767Y8216D01*
X538752Y8181D01*
X538732Y8141D01*
X538717Y8101D01*
X538707Y8061D01*
X538692Y8016D01*
X538687Y7976D01*
X538677Y7936D01*
X538672Y7891D01*
Y7851D01*
X538667Y7806D01*
X538672Y7761D01*
Y7721D01*
X538677Y7676D01*
X538687Y7636D01*
X538692Y7596D01*
X538707Y7551D01*
X538717Y7511D01*
X538732Y7471D01*
X538752Y7431D01*
X538767Y7396D01*
X538787Y7356D01*
X538887Y7216D01*
X538917Y7186D01*
Y3756D01*
X538927Y3631D01*
X538967Y3506D01*
X539027Y3396D01*
X539107Y3296D01*
X539207Y3216D01*
X539317Y3156D01*
X539442Y3116D01*
X539567Y3106D01*
G37*
G36*
G01X534842D02*
X534967Y3116D01*
X535092Y3156D01*
X535202Y3216D01*
X535302Y3296D01*
X535382Y3396D01*
X535442Y3506D01*
X535482Y3631D01*
X535492Y3756D01*
Y7186D01*
X535522Y7216D01*
X535622Y7356D01*
X535642Y7396D01*
X535657Y7431D01*
X535677Y7471D01*
X535692Y7511D01*
X535702Y7551D01*
X535717Y7596D01*
X535722Y7636D01*
X535732Y7676D01*
X535737Y7721D01*
Y7761D01*
X535742Y7806D01*
X535737Y7851D01*
Y7891D01*
X535732Y7936D01*
X535722Y7976D01*
X535717Y8016D01*
X535702Y8061D01*
X535692Y8101D01*
X535677Y8141D01*
X535657Y8181D01*
X535642Y8216D01*
X535622Y8256D01*
X535522Y8396D01*
X535492Y8426D01*
Y9556D01*
X535482Y9681D01*
X535442Y9806D01*
X535382Y9916D01*
X535302Y10016D01*
X535202Y10096D01*
X535092Y10156D01*
X534967Y10196D01*
X534842Y10206D01*
X534717Y10196D01*
X534592Y10156D01*
X534482Y10096D01*
X534382Y10016D01*
X534302Y9916D01*
X534242Y9806D01*
X534202Y9681D01*
X534192Y9556D01*
Y8426D01*
X534162Y8396D01*
X534062Y8256D01*
X534042Y8216D01*
X534027Y8181D01*
X534007Y8141D01*
X533992Y8101D01*
X533982Y8061D01*
X533967Y8016D01*
X533962Y7976D01*
X533952Y7936D01*
X533947Y7891D01*
Y7851D01*
X533942Y7806D01*
X533947Y7761D01*
Y7721D01*
X533952Y7676D01*
X533962Y7636D01*
X533967Y7596D01*
X533982Y7551D01*
X533992Y7511D01*
X534007Y7471D01*
X534027Y7431D01*
X534042Y7396D01*
X534062Y7356D01*
X534162Y7216D01*
X534192Y7186D01*
Y3756D01*
X534202Y3631D01*
X534242Y3506D01*
X534302Y3396D01*
X534382Y3296D01*
X534482Y3216D01*
X534592Y3156D01*
X534717Y3116D01*
X534842Y3106D01*
G37*
G36*
G01X530118D02*
X530243Y3116D01*
X530368Y3156D01*
X530478Y3216D01*
X530578Y3296D01*
X530658Y3396D01*
X530718Y3506D01*
X530758Y3631D01*
X530768Y3756D01*
Y7186D01*
X530798Y7216D01*
X530898Y7356D01*
X530918Y7396D01*
X530933Y7431D01*
X530953Y7471D01*
X530968Y7511D01*
X530978Y7551D01*
X530993Y7596D01*
X530998Y7636D01*
X531008Y7676D01*
X531013Y7721D01*
Y7761D01*
X531018Y7806D01*
X531013Y7851D01*
Y7891D01*
X531008Y7936D01*
X530998Y7976D01*
X530993Y8016D01*
X530978Y8061D01*
X530968Y8101D01*
X530953Y8141D01*
X530933Y8181D01*
X530918Y8216D01*
X530898Y8256D01*
X530798Y8396D01*
X530768Y8426D01*
Y9556D01*
X530758Y9681D01*
X530718Y9806D01*
X530658Y9916D01*
X530578Y10016D01*
X530478Y10096D01*
X530368Y10156D01*
X530243Y10196D01*
X530118Y10206D01*
X529993Y10196D01*
X529868Y10156D01*
X529758Y10096D01*
X529658Y10016D01*
X529578Y9916D01*
X529518Y9806D01*
X529478Y9681D01*
X529468Y9556D01*
Y8426D01*
X529438Y8396D01*
X529338Y8256D01*
X529318Y8216D01*
X529303Y8181D01*
X529283Y8141D01*
X529268Y8101D01*
X529258Y8061D01*
X529243Y8016D01*
X529238Y7976D01*
X529228Y7936D01*
X529223Y7891D01*
Y7851D01*
X529218Y7806D01*
X529223Y7761D01*
Y7721D01*
X529228Y7676D01*
X529238Y7636D01*
X529243Y7596D01*
X529258Y7551D01*
X529268Y7511D01*
X529283Y7471D01*
X529303Y7431D01*
X529318Y7396D01*
X529338Y7356D01*
X529438Y7216D01*
X529468Y7186D01*
Y3756D01*
X529478Y3631D01*
X529518Y3506D01*
X529578Y3396D01*
X529658Y3296D01*
X529758Y3216D01*
X529868Y3156D01*
X529993Y3116D01*
X530118Y3106D01*
G37*
G36*
G01X553740D02*
X553865Y3116D01*
X553990Y3156D01*
X554100Y3216D01*
X554200Y3296D01*
X554280Y3396D01*
X554340Y3506D01*
X554380Y3631D01*
X554390Y3756D01*
Y7186D01*
X554420Y7216D01*
X554520Y7356D01*
X554540Y7396D01*
X554555Y7431D01*
X554575Y7471D01*
X554590Y7511D01*
X554600Y7551D01*
X554615Y7596D01*
X554620Y7636D01*
X554630Y7676D01*
X554635Y7721D01*
Y7761D01*
X554640Y7806D01*
X554635Y7851D01*
Y7891D01*
X554630Y7936D01*
X554620Y7976D01*
X554615Y8016D01*
X554600Y8061D01*
X554590Y8101D01*
X554575Y8141D01*
X554555Y8181D01*
X554540Y8216D01*
X554520Y8256D01*
X554420Y8396D01*
X554390Y8426D01*
Y9556D01*
X554380Y9681D01*
X554340Y9806D01*
X554280Y9916D01*
X554200Y10016D01*
X554100Y10096D01*
X553990Y10156D01*
X553865Y10196D01*
X553740Y10206D01*
X553615Y10196D01*
X553490Y10156D01*
X553380Y10096D01*
X553280Y10016D01*
X553200Y9916D01*
X553140Y9806D01*
X553100Y9681D01*
X553090Y9556D01*
Y8426D01*
X553060Y8396D01*
X552960Y8256D01*
X552940Y8216D01*
X552925Y8181D01*
X552905Y8141D01*
X552890Y8101D01*
X552880Y8061D01*
X552865Y8016D01*
X552860Y7976D01*
X552850Y7936D01*
X552845Y7891D01*
Y7851D01*
X552840Y7806D01*
X552845Y7761D01*
Y7721D01*
X552850Y7676D01*
X552860Y7636D01*
X552865Y7596D01*
X552880Y7551D01*
X552890Y7511D01*
X552905Y7471D01*
X552925Y7431D01*
X552940Y7396D01*
X552960Y7356D01*
X553060Y7216D01*
X553090Y7186D01*
Y3756D01*
X553100Y3631D01*
X553140Y3506D01*
X553200Y3396D01*
X553280Y3296D01*
X553380Y3216D01*
X553490Y3156D01*
X553615Y3116D01*
X553740Y3106D01*
G37*
G36*
G01X549015D02*
X549140Y3116D01*
X549265Y3156D01*
X549375Y3216D01*
X549475Y3296D01*
X549555Y3396D01*
X549615Y3506D01*
X549655Y3631D01*
X549665Y3756D01*
Y7186D01*
X549695Y7216D01*
X549795Y7356D01*
X549815Y7396D01*
X549830Y7431D01*
X549850Y7471D01*
X549865Y7511D01*
X549875Y7551D01*
X549890Y7596D01*
X549895Y7636D01*
X549905Y7676D01*
X549910Y7721D01*
Y7761D01*
X549915Y7806D01*
X549910Y7851D01*
Y7891D01*
X549905Y7936D01*
X549895Y7976D01*
X549890Y8016D01*
X549875Y8061D01*
X549865Y8101D01*
X549850Y8141D01*
X549830Y8181D01*
X549815Y8216D01*
X549795Y8256D01*
X549695Y8396D01*
X549665Y8426D01*
Y9556D01*
X549655Y9681D01*
X549615Y9806D01*
X549555Y9916D01*
X549475Y10016D01*
X549375Y10096D01*
X549265Y10156D01*
X549140Y10196D01*
X549015Y10206D01*
X548890Y10196D01*
X548765Y10156D01*
X548655Y10096D01*
X548555Y10016D01*
X548475Y9916D01*
X548415Y9806D01*
X548375Y9681D01*
X548365Y9556D01*
Y8426D01*
X548335Y8396D01*
X548235Y8256D01*
X548215Y8216D01*
X548200Y8181D01*
X548180Y8141D01*
X548165Y8101D01*
X548155Y8061D01*
X548140Y8016D01*
X548135Y7976D01*
X548125Y7936D01*
X548120Y7891D01*
Y7851D01*
X548115Y7806D01*
X548120Y7761D01*
Y7721D01*
X548125Y7676D01*
X548135Y7636D01*
X548140Y7596D01*
X548155Y7551D01*
X548165Y7511D01*
X548180Y7471D01*
X548200Y7431D01*
X548215Y7396D01*
X548235Y7356D01*
X548335Y7216D01*
X548365Y7186D01*
Y3756D01*
X548375Y3631D01*
X548415Y3506D01*
X548475Y3396D01*
X548555Y3296D01*
X548655Y3216D01*
X548765Y3156D01*
X548890Y3116D01*
X549015Y3106D01*
G37*
G36*
G01X544291D02*
X544416Y3116D01*
X544541Y3156D01*
X544651Y3216D01*
X544751Y3296D01*
X544831Y3396D01*
X544891Y3506D01*
X544931Y3631D01*
X544941Y3756D01*
Y7186D01*
X544971Y7216D01*
X545071Y7356D01*
X545091Y7396D01*
X545106Y7431D01*
X545126Y7471D01*
X545141Y7511D01*
X545151Y7551D01*
X545166Y7596D01*
X545171Y7636D01*
X545181Y7676D01*
X545186Y7721D01*
Y7761D01*
X545191Y7806D01*
X545186Y7851D01*
Y7891D01*
X545181Y7936D01*
X545171Y7976D01*
X545166Y8016D01*
X545151Y8061D01*
X545141Y8101D01*
X545126Y8141D01*
X545106Y8181D01*
X545091Y8216D01*
X545071Y8256D01*
X544971Y8396D01*
X544941Y8426D01*
Y9556D01*
X544931Y9681D01*
X544891Y9806D01*
X544831Y9916D01*
X544751Y10016D01*
X544651Y10096D01*
X544541Y10156D01*
X544416Y10196D01*
X544291Y10206D01*
X544166Y10196D01*
X544041Y10156D01*
X543931Y10096D01*
X543831Y10016D01*
X543751Y9916D01*
X543691Y9806D01*
X543651Y9681D01*
X543641Y9556D01*
Y8426D01*
X543611Y8396D01*
X543511Y8256D01*
X543491Y8216D01*
X543476Y8181D01*
X543456Y8141D01*
X543441Y8101D01*
X543431Y8061D01*
X543416Y8016D01*
X543411Y7976D01*
X543401Y7936D01*
X543396Y7891D01*
Y7851D01*
X543391Y7806D01*
X543396Y7761D01*
Y7721D01*
X543401Y7676D01*
X543411Y7636D01*
X543416Y7596D01*
X543431Y7551D01*
X543441Y7511D01*
X543456Y7471D01*
X543476Y7431D01*
X543491Y7396D01*
X543511Y7356D01*
X543611Y7216D01*
X543641Y7186D01*
Y3756D01*
X543651Y3631D01*
X543691Y3506D01*
X543751Y3396D01*
X543831Y3296D01*
X543931Y3216D01*
X544041Y3156D01*
X544166Y3116D01*
X544291Y3106D01*
G37*
G36*
G01X572638D02*
X572763Y3116D01*
X572888Y3156D01*
X572998Y3216D01*
X573098Y3296D01*
X573178Y3396D01*
X573238Y3506D01*
X573278Y3631D01*
X573288Y3756D01*
Y7186D01*
X573318Y7216D01*
X573418Y7356D01*
X573438Y7396D01*
X573453Y7431D01*
X573473Y7471D01*
X573488Y7511D01*
X573498Y7551D01*
X573513Y7596D01*
X573518Y7636D01*
X573528Y7676D01*
X573533Y7721D01*
Y7761D01*
X573538Y7806D01*
X573533Y7851D01*
Y7891D01*
X573528Y7936D01*
X573518Y7976D01*
X573513Y8016D01*
X573498Y8061D01*
X573488Y8101D01*
X573473Y8141D01*
X573453Y8181D01*
X573438Y8216D01*
X573418Y8256D01*
X573318Y8396D01*
X573288Y8426D01*
Y9556D01*
X573278Y9681D01*
X573238Y9806D01*
X573178Y9916D01*
X573098Y10016D01*
X572998Y10096D01*
X572888Y10156D01*
X572763Y10196D01*
X572638Y10206D01*
X572513Y10196D01*
X572388Y10156D01*
X572278Y10096D01*
X572178Y10016D01*
X572098Y9916D01*
X572038Y9806D01*
X571998Y9681D01*
X571988Y9556D01*
Y8426D01*
X571958Y8396D01*
X571858Y8256D01*
X571838Y8216D01*
X571823Y8181D01*
X571803Y8141D01*
X571788Y8101D01*
X571778Y8061D01*
X571763Y8016D01*
X571758Y7976D01*
X571748Y7936D01*
X571743Y7891D01*
Y7851D01*
X571738Y7806D01*
X571743Y7761D01*
Y7721D01*
X571748Y7676D01*
X571758Y7636D01*
X571763Y7596D01*
X571778Y7551D01*
X571788Y7511D01*
X571803Y7471D01*
X571823Y7431D01*
X571838Y7396D01*
X571858Y7356D01*
X571958Y7216D01*
X571988Y7186D01*
Y3756D01*
X571998Y3631D01*
X572038Y3506D01*
X572098Y3396D01*
X572178Y3296D01*
X572278Y3216D01*
X572388Y3156D01*
X572513Y3116D01*
X572638Y3106D01*
G37*
G36*
G01X567913D02*
X568038Y3116D01*
X568163Y3156D01*
X568273Y3216D01*
X568373Y3296D01*
X568453Y3396D01*
X568513Y3506D01*
X568553Y3631D01*
X568563Y3756D01*
Y7186D01*
X568593Y7216D01*
X568693Y7356D01*
X568713Y7396D01*
X568728Y7431D01*
X568748Y7471D01*
X568763Y7511D01*
X568773Y7551D01*
X568788Y7596D01*
X568793Y7636D01*
X568803Y7676D01*
X568808Y7721D01*
Y7761D01*
X568813Y7806D01*
X568808Y7851D01*
Y7891D01*
X568803Y7936D01*
X568793Y7976D01*
X568788Y8016D01*
X568773Y8061D01*
X568763Y8101D01*
X568748Y8141D01*
X568728Y8181D01*
X568713Y8216D01*
X568693Y8256D01*
X568593Y8396D01*
X568563Y8426D01*
Y9556D01*
X568553Y9681D01*
X568513Y9806D01*
X568453Y9916D01*
X568373Y10016D01*
X568273Y10096D01*
X568163Y10156D01*
X568038Y10196D01*
X567913Y10206D01*
X567788Y10196D01*
X567663Y10156D01*
X567553Y10096D01*
X567453Y10016D01*
X567373Y9916D01*
X567313Y9806D01*
X567273Y9681D01*
X567263Y9556D01*
Y8426D01*
X567233Y8396D01*
X567133Y8256D01*
X567113Y8216D01*
X567098Y8181D01*
X567078Y8141D01*
X567063Y8101D01*
X567053Y8061D01*
X567038Y8016D01*
X567033Y7976D01*
X567023Y7936D01*
X567018Y7891D01*
Y7851D01*
X567013Y7806D01*
X567018Y7761D01*
Y7721D01*
X567023Y7676D01*
X567033Y7636D01*
X567038Y7596D01*
X567053Y7551D01*
X567063Y7511D01*
X567078Y7471D01*
X567098Y7431D01*
X567113Y7396D01*
X567133Y7356D01*
X567233Y7216D01*
X567263Y7186D01*
Y3756D01*
X567273Y3631D01*
X567313Y3506D01*
X567373Y3396D01*
X567453Y3296D01*
X567553Y3216D01*
X567663Y3156D01*
X567788Y3116D01*
X567913Y3106D01*
G37*
G36*
G01X563189D02*
X563314Y3116D01*
X563439Y3156D01*
X563549Y3216D01*
X563649Y3296D01*
X563729Y3396D01*
X563789Y3506D01*
X563829Y3631D01*
X563839Y3756D01*
Y7186D01*
X563869Y7216D01*
X563969Y7356D01*
X563989Y7396D01*
X564004Y7431D01*
X564024Y7471D01*
X564039Y7511D01*
X564049Y7551D01*
X564064Y7596D01*
X564069Y7636D01*
X564079Y7676D01*
X564084Y7721D01*
Y7761D01*
X564089Y7806D01*
X564084Y7851D01*
Y7891D01*
X564079Y7936D01*
X564069Y7976D01*
X564064Y8016D01*
X564049Y8061D01*
X564039Y8101D01*
X564024Y8141D01*
X564004Y8181D01*
X563989Y8216D01*
X563969Y8256D01*
X563869Y8396D01*
X563839Y8426D01*
Y9556D01*
X563829Y9681D01*
X563789Y9806D01*
X563729Y9916D01*
X563649Y10016D01*
X563549Y10096D01*
X563439Y10156D01*
X563314Y10196D01*
X563189Y10206D01*
X563064Y10196D01*
X562939Y10156D01*
X562829Y10096D01*
X562729Y10016D01*
X562649Y9916D01*
X562589Y9806D01*
X562549Y9681D01*
X562539Y9556D01*
Y8426D01*
X562509Y8396D01*
X562409Y8256D01*
X562389Y8216D01*
X562374Y8181D01*
X562354Y8141D01*
X562339Y8101D01*
X562329Y8061D01*
X562314Y8016D01*
X562309Y7976D01*
X562299Y7936D01*
X562294Y7891D01*
Y7851D01*
X562289Y7806D01*
X562294Y7761D01*
Y7721D01*
X562299Y7676D01*
X562309Y7636D01*
X562314Y7596D01*
X562329Y7551D01*
X562339Y7511D01*
X562354Y7471D01*
X562374Y7431D01*
X562389Y7396D01*
X562409Y7356D01*
X562509Y7216D01*
X562539Y7186D01*
Y3756D01*
X562549Y3631D01*
X562589Y3506D01*
X562649Y3396D01*
X562729Y3296D01*
X562829Y3216D01*
X562939Y3156D01*
X563064Y3116D01*
X563189Y3106D01*
G37*
G36*
G01X558464D02*
X558589Y3116D01*
X558714Y3156D01*
X558824Y3216D01*
X558924Y3296D01*
X559004Y3396D01*
X559064Y3506D01*
X559104Y3631D01*
X559114Y3756D01*
Y7186D01*
X559144Y7216D01*
X559244Y7356D01*
X559264Y7396D01*
X559279Y7431D01*
X559299Y7471D01*
X559314Y7511D01*
X559324Y7551D01*
X559339Y7596D01*
X559344Y7636D01*
X559354Y7676D01*
X559359Y7721D01*
Y7761D01*
X559364Y7806D01*
X559359Y7851D01*
Y7891D01*
X559354Y7936D01*
X559344Y7976D01*
X559339Y8016D01*
X559324Y8061D01*
X559314Y8101D01*
X559299Y8141D01*
X559279Y8181D01*
X559264Y8216D01*
X559244Y8256D01*
X559144Y8396D01*
X559114Y8426D01*
Y9556D01*
X559104Y9681D01*
X559064Y9806D01*
X559004Y9916D01*
X558924Y10016D01*
X558824Y10096D01*
X558714Y10156D01*
X558589Y10196D01*
X558464Y10206D01*
X558339Y10196D01*
X558214Y10156D01*
X558104Y10096D01*
X558004Y10016D01*
X557924Y9916D01*
X557864Y9806D01*
X557824Y9681D01*
X557814Y9556D01*
Y8426D01*
X557784Y8396D01*
X557684Y8256D01*
X557664Y8216D01*
X557649Y8181D01*
X557629Y8141D01*
X557614Y8101D01*
X557604Y8061D01*
X557589Y8016D01*
X557584Y7976D01*
X557574Y7936D01*
X557569Y7891D01*
Y7851D01*
X557564Y7806D01*
X557569Y7761D01*
Y7721D01*
X557574Y7676D01*
X557584Y7636D01*
X557589Y7596D01*
X557604Y7551D01*
X557614Y7511D01*
X557629Y7471D01*
X557649Y7431D01*
X557664Y7396D01*
X557684Y7356D01*
X557784Y7216D01*
X557814Y7186D01*
Y3756D01*
X557824Y3631D01*
X557864Y3506D01*
X557924Y3396D01*
X558004Y3296D01*
X558104Y3216D01*
X558214Y3156D01*
X558339Y3116D01*
X558464Y3106D01*
G37*
G36*
G01X586811D02*
X586936Y3116D01*
X587061Y3156D01*
X587171Y3216D01*
X587271Y3296D01*
X587351Y3396D01*
X587411Y3506D01*
X587451Y3631D01*
X587461Y3756D01*
Y7186D01*
X587491Y7216D01*
X587591Y7356D01*
X587611Y7396D01*
X587626Y7431D01*
X587646Y7471D01*
X587661Y7511D01*
X587671Y7551D01*
X587686Y7596D01*
X587691Y7636D01*
X587701Y7676D01*
X587706Y7721D01*
Y7761D01*
X587711Y7806D01*
X587706Y7851D01*
Y7891D01*
X587701Y7936D01*
X587691Y7976D01*
X587686Y8016D01*
X587671Y8061D01*
X587661Y8101D01*
X587646Y8141D01*
X587626Y8181D01*
X587611Y8216D01*
X587591Y8256D01*
X587491Y8396D01*
X587461Y8426D01*
Y9556D01*
X587451Y9681D01*
X587411Y9806D01*
X587351Y9916D01*
X587271Y10016D01*
X587171Y10096D01*
X587061Y10156D01*
X586936Y10196D01*
X586811Y10206D01*
X586686Y10196D01*
X586561Y10156D01*
X586451Y10096D01*
X586351Y10016D01*
X586271Y9916D01*
X586211Y9806D01*
X586171Y9681D01*
X586161Y9556D01*
Y8426D01*
X586131Y8396D01*
X586031Y8256D01*
X586011Y8216D01*
X585996Y8181D01*
X585976Y8141D01*
X585961Y8101D01*
X585951Y8061D01*
X585936Y8016D01*
X585931Y7976D01*
X585921Y7936D01*
X585916Y7891D01*
Y7851D01*
X585911Y7806D01*
X585916Y7761D01*
Y7721D01*
X585921Y7676D01*
X585931Y7636D01*
X585936Y7596D01*
X585951Y7551D01*
X585961Y7511D01*
X585976Y7471D01*
X585996Y7431D01*
X586011Y7396D01*
X586031Y7356D01*
X586131Y7216D01*
X586161Y7186D01*
Y3756D01*
X586171Y3631D01*
X586211Y3506D01*
X586271Y3396D01*
X586351Y3296D01*
X586451Y3216D01*
X586561Y3156D01*
X586686Y3116D01*
X586811Y3106D01*
G37*
G36*
G01X582086D02*
X582211Y3116D01*
X582336Y3156D01*
X582446Y3216D01*
X582546Y3296D01*
X582626Y3396D01*
X582686Y3506D01*
X582726Y3631D01*
X582736Y3756D01*
Y7186D01*
X582766Y7216D01*
X582866Y7356D01*
X582886Y7396D01*
X582901Y7431D01*
X582921Y7471D01*
X582936Y7511D01*
X582946Y7551D01*
X582961Y7596D01*
X582966Y7636D01*
X582976Y7676D01*
X582981Y7721D01*
Y7761D01*
X582986Y7806D01*
X582981Y7851D01*
Y7891D01*
X582976Y7936D01*
X582966Y7976D01*
X582961Y8016D01*
X582946Y8061D01*
X582936Y8101D01*
X582921Y8141D01*
X582901Y8181D01*
X582886Y8216D01*
X582866Y8256D01*
X582766Y8396D01*
X582736Y8426D01*
Y9556D01*
X582726Y9681D01*
X582686Y9806D01*
X582626Y9916D01*
X582546Y10016D01*
X582446Y10096D01*
X582336Y10156D01*
X582211Y10196D01*
X582086Y10206D01*
X581961Y10196D01*
X581836Y10156D01*
X581726Y10096D01*
X581626Y10016D01*
X581546Y9916D01*
X581486Y9806D01*
X581446Y9681D01*
X581436Y9556D01*
Y8426D01*
X581406Y8396D01*
X581306Y8256D01*
X581286Y8216D01*
X581271Y8181D01*
X581251Y8141D01*
X581236Y8101D01*
X581226Y8061D01*
X581211Y8016D01*
X581206Y7976D01*
X581196Y7936D01*
X581191Y7891D01*
Y7851D01*
X581186Y7806D01*
X581191Y7761D01*
Y7721D01*
X581196Y7676D01*
X581206Y7636D01*
X581211Y7596D01*
X581226Y7551D01*
X581236Y7511D01*
X581251Y7471D01*
X581271Y7431D01*
X581286Y7396D01*
X581306Y7356D01*
X581406Y7216D01*
X581436Y7186D01*
Y3756D01*
X581446Y3631D01*
X581486Y3506D01*
X581546Y3396D01*
X581626Y3296D01*
X581726Y3216D01*
X581836Y3156D01*
X581961Y3116D01*
X582086Y3106D01*
G37*
G36*
G01X577362D02*
X577487Y3116D01*
X577612Y3156D01*
X577722Y3216D01*
X577822Y3296D01*
X577902Y3396D01*
X577962Y3506D01*
X578002Y3631D01*
X578012Y3756D01*
Y7186D01*
X578042Y7216D01*
X578142Y7356D01*
X578162Y7396D01*
X578177Y7431D01*
X578197Y7471D01*
X578212Y7511D01*
X578222Y7551D01*
X578237Y7596D01*
X578242Y7636D01*
X578252Y7676D01*
X578257Y7721D01*
Y7761D01*
X578262Y7806D01*
X578257Y7851D01*
Y7891D01*
X578252Y7936D01*
X578242Y7976D01*
X578237Y8016D01*
X578222Y8061D01*
X578212Y8101D01*
X578197Y8141D01*
X578177Y8181D01*
X578162Y8216D01*
X578142Y8256D01*
X578042Y8396D01*
X578012Y8426D01*
Y9556D01*
X578002Y9681D01*
X577962Y9806D01*
X577902Y9916D01*
X577822Y10016D01*
X577722Y10096D01*
X577612Y10156D01*
X577487Y10196D01*
X577362Y10206D01*
X577237Y10196D01*
X577112Y10156D01*
X577002Y10096D01*
X576902Y10016D01*
X576822Y9916D01*
X576762Y9806D01*
X576722Y9681D01*
X576712Y9556D01*
Y8426D01*
X576682Y8396D01*
X576582Y8256D01*
X576562Y8216D01*
X576547Y8181D01*
X576527Y8141D01*
X576512Y8101D01*
X576502Y8061D01*
X576487Y8016D01*
X576482Y7976D01*
X576472Y7936D01*
X576467Y7891D01*
Y7851D01*
X576462Y7806D01*
X576467Y7761D01*
Y7721D01*
X576472Y7676D01*
X576482Y7636D01*
X576487Y7596D01*
X576502Y7551D01*
X576512Y7511D01*
X576527Y7471D01*
X576547Y7431D01*
X576562Y7396D01*
X576582Y7356D01*
X576682Y7216D01*
X576712Y7186D01*
Y3756D01*
X576722Y3631D01*
X576762Y3506D01*
X576822Y3396D01*
X576902Y3296D01*
X577002Y3216D01*
X577112Y3156D01*
X577237Y3116D01*
X577362Y3106D01*
G37*
G36*
G01X600984D02*
X601109Y3116D01*
X601234Y3156D01*
X601344Y3216D01*
X601444Y3296D01*
X601524Y3396D01*
X601584Y3506D01*
X601624Y3631D01*
X601634Y3756D01*
Y7186D01*
X601664Y7216D01*
X601764Y7356D01*
X601784Y7396D01*
X601799Y7431D01*
X601819Y7471D01*
X601834Y7511D01*
X601844Y7551D01*
X601859Y7596D01*
X601864Y7636D01*
X601874Y7676D01*
X601879Y7721D01*
Y7761D01*
X601884Y7806D01*
X601879Y7851D01*
Y7891D01*
X601874Y7936D01*
X601864Y7976D01*
X601859Y8016D01*
X601844Y8061D01*
X601834Y8101D01*
X601819Y8141D01*
X601799Y8181D01*
X601784Y8216D01*
X601764Y8256D01*
X601664Y8396D01*
X601634Y8426D01*
Y9556D01*
X601624Y9681D01*
X601584Y9806D01*
X601524Y9916D01*
X601444Y10016D01*
X601344Y10096D01*
X601234Y10156D01*
X601109Y10196D01*
X600984Y10206D01*
X600859Y10196D01*
X600734Y10156D01*
X600624Y10096D01*
X600524Y10016D01*
X600444Y9916D01*
X600384Y9806D01*
X600344Y9681D01*
X600334Y9556D01*
Y8426D01*
X600304Y8396D01*
X600204Y8256D01*
X600184Y8216D01*
X600169Y8181D01*
X600149Y8141D01*
X600134Y8101D01*
X600124Y8061D01*
X600109Y8016D01*
X600104Y7976D01*
X600094Y7936D01*
X600089Y7891D01*
Y7851D01*
X600084Y7806D01*
X600089Y7761D01*
Y7721D01*
X600094Y7676D01*
X600104Y7636D01*
X600109Y7596D01*
X600124Y7551D01*
X600134Y7511D01*
X600149Y7471D01*
X600169Y7431D01*
X600184Y7396D01*
X600204Y7356D01*
X600304Y7216D01*
X600334Y7186D01*
Y3756D01*
X600344Y3631D01*
X600384Y3506D01*
X600444Y3396D01*
X600524Y3296D01*
X600624Y3216D01*
X600734Y3156D01*
X600859Y3116D01*
X600984Y3106D01*
G37*
G36*
G01X615157D02*
X615282Y3116D01*
X615407Y3156D01*
X615517Y3216D01*
X615617Y3296D01*
X615697Y3396D01*
X615757Y3506D01*
X615797Y3631D01*
X615807Y3756D01*
Y7186D01*
X615837Y7216D01*
X615937Y7356D01*
X615957Y7396D01*
X615972Y7431D01*
X615992Y7471D01*
X616007Y7511D01*
X616017Y7551D01*
X616032Y7596D01*
X616037Y7636D01*
X616047Y7676D01*
X616052Y7721D01*
Y7761D01*
X616057Y7806D01*
X616052Y7851D01*
Y7891D01*
X616047Y7936D01*
X616037Y7976D01*
X616032Y8016D01*
X616017Y8061D01*
X616007Y8101D01*
X615992Y8141D01*
X615972Y8181D01*
X615957Y8216D01*
X615937Y8256D01*
X615837Y8396D01*
X615807Y8426D01*
Y9556D01*
X615797Y9681D01*
X615757Y9806D01*
X615697Y9916D01*
X615617Y10016D01*
X615517Y10096D01*
X615407Y10156D01*
X615282Y10196D01*
X615157Y10206D01*
X615032Y10196D01*
X614907Y10156D01*
X614797Y10096D01*
X614697Y10016D01*
X614617Y9916D01*
X614557Y9806D01*
X614517Y9681D01*
X614507Y9556D01*
Y8426D01*
X614477Y8396D01*
X614377Y8256D01*
X614357Y8216D01*
X614342Y8181D01*
X614322Y8141D01*
X614307Y8101D01*
X614297Y8061D01*
X614282Y8016D01*
X614277Y7976D01*
X614267Y7936D01*
X614262Y7891D01*
Y7851D01*
X614257Y7806D01*
X614262Y7761D01*
Y7721D01*
X614267Y7676D01*
X614277Y7636D01*
X614282Y7596D01*
X614297Y7551D01*
X614307Y7511D01*
X614322Y7471D01*
X614342Y7431D01*
X614357Y7396D01*
X614377Y7356D01*
X614477Y7216D01*
X614507Y7186D01*
Y3756D01*
X614517Y3631D01*
X614557Y3506D01*
X614617Y3396D01*
X614697Y3296D01*
X614797Y3216D01*
X614907Y3156D01*
X615032Y3116D01*
X615157Y3106D01*
G37*
G36*
G01X610433D02*
X610558Y3116D01*
X610683Y3156D01*
X610793Y3216D01*
X610893Y3296D01*
X610973Y3396D01*
X611033Y3506D01*
X611073Y3631D01*
X611083Y3756D01*
Y7186D01*
X611113Y7216D01*
X611213Y7356D01*
X611233Y7396D01*
X611248Y7431D01*
X611268Y7471D01*
X611283Y7511D01*
X611293Y7551D01*
X611308Y7596D01*
X611313Y7636D01*
X611323Y7676D01*
X611328Y7721D01*
Y7761D01*
X611333Y7806D01*
X611328Y7851D01*
Y7891D01*
X611323Y7936D01*
X611313Y7976D01*
X611308Y8016D01*
X611293Y8061D01*
X611283Y8101D01*
X611268Y8141D01*
X611248Y8181D01*
X611233Y8216D01*
X611213Y8256D01*
X611113Y8396D01*
X611083Y8426D01*
Y9556D01*
X611073Y9681D01*
X611033Y9806D01*
X610973Y9916D01*
X610893Y10016D01*
X610793Y10096D01*
X610683Y10156D01*
X610558Y10196D01*
X610433Y10206D01*
X610308Y10196D01*
X610183Y10156D01*
X610073Y10096D01*
X609973Y10016D01*
X609893Y9916D01*
X609833Y9806D01*
X609793Y9681D01*
X609783Y9556D01*
Y8426D01*
X609753Y8396D01*
X609653Y8256D01*
X609633Y8216D01*
X609618Y8181D01*
X609598Y8141D01*
X609583Y8101D01*
X609573Y8061D01*
X609558Y8016D01*
X609553Y7976D01*
X609543Y7936D01*
X609538Y7891D01*
Y7851D01*
X609533Y7806D01*
X609538Y7761D01*
Y7721D01*
X609543Y7676D01*
X609553Y7636D01*
X609558Y7596D01*
X609573Y7551D01*
X609583Y7511D01*
X609598Y7471D01*
X609618Y7431D01*
X609633Y7396D01*
X609653Y7356D01*
X609753Y7216D01*
X609783Y7186D01*
Y3756D01*
X609793Y3631D01*
X609833Y3506D01*
X609893Y3396D01*
X609973Y3296D01*
X610073Y3216D01*
X610183Y3156D01*
X610308Y3116D01*
X610433Y3106D01*
G37*
G36*
G01X605708D02*
X605833Y3116D01*
X605958Y3156D01*
X606068Y3216D01*
X606168Y3296D01*
X606248Y3396D01*
X606308Y3506D01*
X606348Y3631D01*
X606358Y3756D01*
Y7186D01*
X606388Y7216D01*
X606488Y7356D01*
X606508Y7396D01*
X606523Y7431D01*
X606543Y7471D01*
X606558Y7511D01*
X606568Y7551D01*
X606583Y7596D01*
X606588Y7636D01*
X606598Y7676D01*
X606603Y7721D01*
Y7761D01*
X606608Y7806D01*
X606603Y7851D01*
Y7891D01*
X606598Y7936D01*
X606588Y7976D01*
X606583Y8016D01*
X606568Y8061D01*
X606558Y8101D01*
X606543Y8141D01*
X606523Y8181D01*
X606508Y8216D01*
X606488Y8256D01*
X606388Y8396D01*
X606358Y8426D01*
Y9556D01*
X606348Y9681D01*
X606308Y9806D01*
X606248Y9916D01*
X606168Y10016D01*
X606068Y10096D01*
X605958Y10156D01*
X605833Y10196D01*
X605708Y10206D01*
X605583Y10196D01*
X605458Y10156D01*
X605348Y10096D01*
X605248Y10016D01*
X605168Y9916D01*
X605108Y9806D01*
X605068Y9681D01*
X605058Y9556D01*
Y8426D01*
X605028Y8396D01*
X604928Y8256D01*
X604908Y8216D01*
X604893Y8181D01*
X604873Y8141D01*
X604858Y8101D01*
X604848Y8061D01*
X604833Y8016D01*
X604828Y7976D01*
X604818Y7936D01*
X604813Y7891D01*
Y7851D01*
X604808Y7806D01*
X604813Y7761D01*
Y7721D01*
X604818Y7676D01*
X604828Y7636D01*
X604833Y7596D01*
X604848Y7551D01*
X604858Y7511D01*
X604873Y7471D01*
X604893Y7431D01*
X604908Y7396D01*
X604928Y7356D01*
X605028Y7216D01*
X605058Y7186D01*
Y3756D01*
X605068Y3631D01*
X605108Y3506D01*
X605168Y3396D01*
X605248Y3296D01*
X605348Y3216D01*
X605458Y3156D01*
X605583Y3116D01*
X605708Y3106D01*
G37*
G36*
G01X634055D02*
X634180Y3116D01*
X634305Y3156D01*
X634415Y3216D01*
X634515Y3296D01*
X634595Y3396D01*
X634655Y3506D01*
X634695Y3631D01*
X634705Y3756D01*
Y7186D01*
X634735Y7216D01*
X634835Y7356D01*
X634855Y7396D01*
X634870Y7431D01*
X634890Y7471D01*
X634905Y7511D01*
X634915Y7551D01*
X634930Y7596D01*
X634935Y7636D01*
X634945Y7676D01*
X634950Y7721D01*
Y7761D01*
X634955Y7806D01*
X634950Y7851D01*
Y7891D01*
X634945Y7936D01*
X634935Y7976D01*
X634930Y8016D01*
X634915Y8061D01*
X634905Y8101D01*
X634890Y8141D01*
X634870Y8181D01*
X634855Y8216D01*
X634835Y8256D01*
X634735Y8396D01*
X634705Y8426D01*
Y9556D01*
X634695Y9681D01*
X634655Y9806D01*
X634595Y9916D01*
X634515Y10016D01*
X634415Y10096D01*
X634305Y10156D01*
X634180Y10196D01*
X634055Y10206D01*
X633930Y10196D01*
X633805Y10156D01*
X633695Y10096D01*
X633595Y10016D01*
X633515Y9916D01*
X633455Y9806D01*
X633415Y9681D01*
X633405Y9556D01*
Y8426D01*
X633375Y8396D01*
X633275Y8256D01*
X633255Y8216D01*
X633240Y8181D01*
X633220Y8141D01*
X633205Y8101D01*
X633195Y8061D01*
X633180Y8016D01*
X633175Y7976D01*
X633165Y7936D01*
X633160Y7891D01*
Y7851D01*
X633155Y7806D01*
X633160Y7761D01*
Y7721D01*
X633165Y7676D01*
X633175Y7636D01*
X633180Y7596D01*
X633195Y7551D01*
X633205Y7511D01*
X633220Y7471D01*
X633240Y7431D01*
X633255Y7396D01*
X633275Y7356D01*
X633375Y7216D01*
X633405Y7186D01*
Y3756D01*
X633415Y3631D01*
X633455Y3506D01*
X633515Y3396D01*
X633595Y3296D01*
X633695Y3216D01*
X633805Y3156D01*
X633930Y3116D01*
X634055Y3106D01*
G37*
G36*
G01X629330D02*
X629455Y3116D01*
X629580Y3156D01*
X629690Y3216D01*
X629790Y3296D01*
X629870Y3396D01*
X629930Y3506D01*
X629970Y3631D01*
X629980Y3756D01*
Y7186D01*
X630010Y7216D01*
X630110Y7356D01*
X630130Y7396D01*
X630145Y7431D01*
X630165Y7471D01*
X630180Y7511D01*
X630190Y7551D01*
X630205Y7596D01*
X630210Y7636D01*
X630220Y7676D01*
X630225Y7721D01*
Y7761D01*
X630230Y7806D01*
X630225Y7851D01*
Y7891D01*
X630220Y7936D01*
X630210Y7976D01*
X630205Y8016D01*
X630190Y8061D01*
X630180Y8101D01*
X630165Y8141D01*
X630145Y8181D01*
X630130Y8216D01*
X630110Y8256D01*
X630010Y8396D01*
X629980Y8426D01*
Y9556D01*
X629970Y9681D01*
X629930Y9806D01*
X629870Y9916D01*
X629790Y10016D01*
X629690Y10096D01*
X629580Y10156D01*
X629455Y10196D01*
X629330Y10206D01*
X629205Y10196D01*
X629080Y10156D01*
X628970Y10096D01*
X628870Y10016D01*
X628790Y9916D01*
X628730Y9806D01*
X628690Y9681D01*
X628680Y9556D01*
Y8426D01*
X628650Y8396D01*
X628550Y8256D01*
X628530Y8216D01*
X628515Y8181D01*
X628495Y8141D01*
X628480Y8101D01*
X628470Y8061D01*
X628455Y8016D01*
X628450Y7976D01*
X628440Y7936D01*
X628435Y7891D01*
Y7851D01*
X628430Y7806D01*
X628435Y7761D01*
Y7721D01*
X628440Y7676D01*
X628450Y7636D01*
X628455Y7596D01*
X628470Y7551D01*
X628480Y7511D01*
X628495Y7471D01*
X628515Y7431D01*
X628530Y7396D01*
X628550Y7356D01*
X628650Y7216D01*
X628680Y7186D01*
Y3756D01*
X628690Y3631D01*
X628730Y3506D01*
X628790Y3396D01*
X628870Y3296D01*
X628970Y3216D01*
X629080Y3156D01*
X629205Y3116D01*
X629330Y3106D01*
G37*
G36*
G01X624606D02*
X624731Y3116D01*
X624856Y3156D01*
X624966Y3216D01*
X625066Y3296D01*
X625146Y3396D01*
X625206Y3506D01*
X625246Y3631D01*
X625256Y3756D01*
Y7186D01*
X625286Y7216D01*
X625386Y7356D01*
X625406Y7396D01*
X625421Y7431D01*
X625441Y7471D01*
X625456Y7511D01*
X625466Y7551D01*
X625481Y7596D01*
X625486Y7636D01*
X625496Y7676D01*
X625501Y7721D01*
Y7761D01*
X625506Y7806D01*
X625501Y7851D01*
Y7891D01*
X625496Y7936D01*
X625486Y7976D01*
X625481Y8016D01*
X625466Y8061D01*
X625456Y8101D01*
X625441Y8141D01*
X625421Y8181D01*
X625406Y8216D01*
X625386Y8256D01*
X625286Y8396D01*
X625256Y8426D01*
Y9556D01*
X625246Y9681D01*
X625206Y9806D01*
X625146Y9916D01*
X625066Y10016D01*
X624966Y10096D01*
X624856Y10156D01*
X624731Y10196D01*
X624606Y10206D01*
X624481Y10196D01*
X624356Y10156D01*
X624246Y10096D01*
X624146Y10016D01*
X624066Y9916D01*
X624006Y9806D01*
X623966Y9681D01*
X623956Y9556D01*
Y8426D01*
X623926Y8396D01*
X623826Y8256D01*
X623806Y8216D01*
X623791Y8181D01*
X623771Y8141D01*
X623756Y8101D01*
X623746Y8061D01*
X623731Y8016D01*
X623726Y7976D01*
X623716Y7936D01*
X623711Y7891D01*
Y7851D01*
X623706Y7806D01*
X623711Y7761D01*
Y7721D01*
X623716Y7676D01*
X623726Y7636D01*
X623731Y7596D01*
X623746Y7551D01*
X623756Y7511D01*
X623771Y7471D01*
X623791Y7431D01*
X623806Y7396D01*
X623826Y7356D01*
X623926Y7216D01*
X623956Y7186D01*
Y3756D01*
X623966Y3631D01*
X624006Y3506D01*
X624066Y3396D01*
X624146Y3296D01*
X624246Y3216D01*
X624356Y3156D01*
X624481Y3116D01*
X624606Y3106D01*
G37*
G36*
G01X619882D02*
X620007Y3116D01*
X620132Y3156D01*
X620242Y3216D01*
X620342Y3296D01*
X620422Y3396D01*
X620482Y3506D01*
X620522Y3631D01*
X620532Y3756D01*
Y7186D01*
X620562Y7216D01*
X620662Y7356D01*
X620682Y7396D01*
X620697Y7431D01*
X620717Y7471D01*
X620732Y7511D01*
X620742Y7551D01*
X620757Y7596D01*
X620762Y7636D01*
X620772Y7676D01*
X620777Y7721D01*
Y7761D01*
X620782Y7806D01*
X620777Y7851D01*
Y7891D01*
X620772Y7936D01*
X620762Y7976D01*
X620757Y8016D01*
X620742Y8061D01*
X620732Y8101D01*
X620717Y8141D01*
X620697Y8181D01*
X620682Y8216D01*
X620662Y8256D01*
X620562Y8396D01*
X620532Y8426D01*
Y9556D01*
X620522Y9681D01*
X620482Y9806D01*
X620422Y9916D01*
X620342Y10016D01*
X620242Y10096D01*
X620132Y10156D01*
X620007Y10196D01*
X619882Y10206D01*
X619757Y10196D01*
X619632Y10156D01*
X619522Y10096D01*
X619422Y10016D01*
X619342Y9916D01*
X619282Y9806D01*
X619242Y9681D01*
X619232Y9556D01*
Y8426D01*
X619202Y8396D01*
X619102Y8256D01*
X619082Y8216D01*
X619067Y8181D01*
X619047Y8141D01*
X619032Y8101D01*
X619022Y8061D01*
X619007Y8016D01*
X619002Y7976D01*
X618992Y7936D01*
X618987Y7891D01*
Y7851D01*
X618982Y7806D01*
X618987Y7761D01*
Y7721D01*
X618992Y7676D01*
X619002Y7636D01*
X619007Y7596D01*
X619022Y7551D01*
X619032Y7511D01*
X619047Y7471D01*
X619067Y7431D01*
X619082Y7396D01*
X619102Y7356D01*
X619202Y7216D01*
X619232Y7186D01*
Y3756D01*
X619242Y3631D01*
X619282Y3506D01*
X619342Y3396D01*
X619422Y3296D01*
X619522Y3216D01*
X619632Y3156D01*
X619757Y3116D01*
X619882Y3106D01*
G37*
G36*
G01X648228D02*
X648353Y3116D01*
X648478Y3156D01*
X648588Y3216D01*
X648688Y3296D01*
X648768Y3396D01*
X648828Y3506D01*
X648868Y3631D01*
X648878Y3756D01*
Y7186D01*
X648908Y7216D01*
X649008Y7356D01*
X649028Y7396D01*
X649043Y7431D01*
X649063Y7471D01*
X649078Y7511D01*
X649088Y7551D01*
X649103Y7596D01*
X649108Y7636D01*
X649118Y7676D01*
X649123Y7721D01*
Y7761D01*
X649128Y7806D01*
X649123Y7851D01*
Y7891D01*
X649118Y7936D01*
X649108Y7976D01*
X649103Y8016D01*
X649088Y8061D01*
X649078Y8101D01*
X649063Y8141D01*
X649043Y8181D01*
X649028Y8216D01*
X649008Y8256D01*
X648908Y8396D01*
X648878Y8426D01*
Y9556D01*
X648868Y9681D01*
X648828Y9806D01*
X648768Y9916D01*
X648688Y10016D01*
X648588Y10096D01*
X648478Y10156D01*
X648353Y10196D01*
X648228Y10206D01*
X648103Y10196D01*
X647978Y10156D01*
X647868Y10096D01*
X647768Y10016D01*
X647688Y9916D01*
X647628Y9806D01*
X647588Y9681D01*
X647578Y9556D01*
Y8426D01*
X647548Y8396D01*
X647448Y8256D01*
X647428Y8216D01*
X647413Y8181D01*
X647393Y8141D01*
X647378Y8101D01*
X647368Y8061D01*
X647353Y8016D01*
X647348Y7976D01*
X647338Y7936D01*
X647333Y7891D01*
Y7851D01*
X647328Y7806D01*
X647333Y7761D01*
Y7721D01*
X647338Y7676D01*
X647348Y7636D01*
X647353Y7596D01*
X647368Y7551D01*
X647378Y7511D01*
X647393Y7471D01*
X647413Y7431D01*
X647428Y7396D01*
X647448Y7356D01*
X647548Y7216D01*
X647578Y7186D01*
Y3756D01*
X647588Y3631D01*
X647628Y3506D01*
X647688Y3396D01*
X647768Y3296D01*
X647868Y3216D01*
X647978Y3156D01*
X648103Y3116D01*
X648228Y3106D01*
G37*
G36*
G01X643504D02*
X643629Y3116D01*
X643754Y3156D01*
X643864Y3216D01*
X643964Y3296D01*
X644044Y3396D01*
X644104Y3506D01*
X644144Y3631D01*
X644154Y3756D01*
Y7186D01*
X644184Y7216D01*
X644284Y7356D01*
X644304Y7396D01*
X644319Y7431D01*
X644339Y7471D01*
X644354Y7511D01*
X644364Y7551D01*
X644379Y7596D01*
X644384Y7636D01*
X644394Y7676D01*
X644399Y7721D01*
Y7761D01*
X644404Y7806D01*
X644399Y7851D01*
Y7891D01*
X644394Y7936D01*
X644384Y7976D01*
X644379Y8016D01*
X644364Y8061D01*
X644354Y8101D01*
X644339Y8141D01*
X644319Y8181D01*
X644304Y8216D01*
X644284Y8256D01*
X644184Y8396D01*
X644154Y8426D01*
Y9556D01*
X644144Y9681D01*
X644104Y9806D01*
X644044Y9916D01*
X643964Y10016D01*
X643864Y10096D01*
X643754Y10156D01*
X643629Y10196D01*
X643504Y10206D01*
X643379Y10196D01*
X643254Y10156D01*
X643144Y10096D01*
X643044Y10016D01*
X642964Y9916D01*
X642904Y9806D01*
X642864Y9681D01*
X642854Y9556D01*
Y8426D01*
X642824Y8396D01*
X642724Y8256D01*
X642704Y8216D01*
X642689Y8181D01*
X642669Y8141D01*
X642654Y8101D01*
X642644Y8061D01*
X642629Y8016D01*
X642624Y7976D01*
X642614Y7936D01*
X642609Y7891D01*
Y7851D01*
X642604Y7806D01*
X642609Y7761D01*
Y7721D01*
X642614Y7676D01*
X642624Y7636D01*
X642629Y7596D01*
X642644Y7551D01*
X642654Y7511D01*
X642669Y7471D01*
X642689Y7431D01*
X642704Y7396D01*
X642724Y7356D01*
X642824Y7216D01*
X642854Y7186D01*
Y3756D01*
X642864Y3631D01*
X642904Y3506D01*
X642964Y3396D01*
X643044Y3296D01*
X643144Y3216D01*
X643254Y3156D01*
X643379Y3116D01*
X643504Y3106D01*
G37*
G36*
G01X638779D02*
X638904Y3116D01*
X639029Y3156D01*
X639139Y3216D01*
X639239Y3296D01*
X639319Y3396D01*
X639379Y3506D01*
X639419Y3631D01*
X639429Y3756D01*
Y7186D01*
X639459Y7216D01*
X639559Y7356D01*
X639579Y7396D01*
X639594Y7431D01*
X639614Y7471D01*
X639629Y7511D01*
X639639Y7551D01*
X639654Y7596D01*
X639659Y7636D01*
X639669Y7676D01*
X639674Y7721D01*
Y7761D01*
X639679Y7806D01*
X639674Y7851D01*
Y7891D01*
X639669Y7936D01*
X639659Y7976D01*
X639654Y8016D01*
X639639Y8061D01*
X639629Y8101D01*
X639614Y8141D01*
X639594Y8181D01*
X639579Y8216D01*
X639559Y8256D01*
X639459Y8396D01*
X639429Y8426D01*
Y9556D01*
X639419Y9681D01*
X639379Y9806D01*
X639319Y9916D01*
X639239Y10016D01*
X639139Y10096D01*
X639029Y10156D01*
X638904Y10196D01*
X638779Y10206D01*
X638654Y10196D01*
X638529Y10156D01*
X638419Y10096D01*
X638319Y10016D01*
X638239Y9916D01*
X638179Y9806D01*
X638139Y9681D01*
X638129Y9556D01*
Y8426D01*
X638099Y8396D01*
X637999Y8256D01*
X637979Y8216D01*
X637964Y8181D01*
X637944Y8141D01*
X637929Y8101D01*
X637919Y8061D01*
X637904Y8016D01*
X637899Y7976D01*
X637889Y7936D01*
X637884Y7891D01*
Y7851D01*
X637879Y7806D01*
X637884Y7761D01*
Y7721D01*
X637889Y7676D01*
X637899Y7636D01*
X637904Y7596D01*
X637919Y7551D01*
X637929Y7511D01*
X637944Y7471D01*
X637964Y7431D01*
X637979Y7396D01*
X637999Y7356D01*
X638099Y7216D01*
X638129Y7186D01*
Y3756D01*
X638139Y3631D01*
X638179Y3506D01*
X638239Y3396D01*
X638319Y3296D01*
X638419Y3216D01*
X638529Y3156D01*
X638654Y3116D01*
X638779Y3106D01*
G37*
G36*
G01X662401D02*
X662526Y3116D01*
X662651Y3156D01*
X662761Y3216D01*
X662861Y3296D01*
X662941Y3396D01*
X663001Y3506D01*
X663041Y3631D01*
X663051Y3756D01*
Y7186D01*
X663081Y7216D01*
X663181Y7356D01*
X663201Y7396D01*
X663216Y7431D01*
X663236Y7471D01*
X663251Y7511D01*
X663261Y7551D01*
X663276Y7596D01*
X663281Y7636D01*
X663291Y7676D01*
X663296Y7721D01*
Y7761D01*
X663301Y7806D01*
X663296Y7851D01*
Y7891D01*
X663291Y7936D01*
X663281Y7976D01*
X663276Y8016D01*
X663261Y8061D01*
X663251Y8101D01*
X663236Y8141D01*
X663216Y8181D01*
X663201Y8216D01*
X663181Y8256D01*
X663081Y8396D01*
X663051Y8426D01*
Y9556D01*
X663041Y9681D01*
X663001Y9806D01*
X662941Y9916D01*
X662861Y10016D01*
X662761Y10096D01*
X662651Y10156D01*
X662526Y10196D01*
X662401Y10206D01*
X662276Y10196D01*
X662151Y10156D01*
X662041Y10096D01*
X661941Y10016D01*
X661861Y9916D01*
X661801Y9806D01*
X661761Y9681D01*
X661751Y9556D01*
Y8426D01*
X661721Y8396D01*
X661621Y8256D01*
X661601Y8216D01*
X661586Y8181D01*
X661566Y8141D01*
X661551Y8101D01*
X661541Y8061D01*
X661526Y8016D01*
X661521Y7976D01*
X661511Y7936D01*
X661506Y7891D01*
Y7851D01*
X661501Y7806D01*
X661506Y7761D01*
Y7721D01*
X661511Y7676D01*
X661521Y7636D01*
X661526Y7596D01*
X661541Y7551D01*
X661551Y7511D01*
X661566Y7471D01*
X661586Y7431D01*
X661601Y7396D01*
X661621Y7356D01*
X661721Y7216D01*
X661751Y7186D01*
Y3756D01*
X661761Y3631D01*
X661801Y3506D01*
X661861Y3396D01*
X661941Y3296D01*
X662041Y3216D01*
X662151Y3156D01*
X662276Y3116D01*
X662401Y3106D01*
G37*
G36*
G01X657677D02*
X657802Y3116D01*
X657927Y3156D01*
X658037Y3216D01*
X658137Y3296D01*
X658217Y3396D01*
X658277Y3506D01*
X658317Y3631D01*
X658327Y3756D01*
Y7186D01*
X658357Y7216D01*
X658457Y7356D01*
X658477Y7396D01*
X658492Y7431D01*
X658512Y7471D01*
X658527Y7511D01*
X658537Y7551D01*
X658552Y7596D01*
X658557Y7636D01*
X658567Y7676D01*
X658572Y7721D01*
Y7761D01*
X658577Y7806D01*
X658572Y7851D01*
Y7891D01*
X658567Y7936D01*
X658557Y7976D01*
X658552Y8016D01*
X658537Y8061D01*
X658527Y8101D01*
X658512Y8141D01*
X658492Y8181D01*
X658477Y8216D01*
X658457Y8256D01*
X658357Y8396D01*
X658327Y8426D01*
Y9556D01*
X658317Y9681D01*
X658277Y9806D01*
X658217Y9916D01*
X658137Y10016D01*
X658037Y10096D01*
X657927Y10156D01*
X657802Y10196D01*
X657677Y10206D01*
X657552Y10196D01*
X657427Y10156D01*
X657317Y10096D01*
X657217Y10016D01*
X657137Y9916D01*
X657077Y9806D01*
X657037Y9681D01*
X657027Y9556D01*
Y8426D01*
X656997Y8396D01*
X656897Y8256D01*
X656877Y8216D01*
X656862Y8181D01*
X656842Y8141D01*
X656827Y8101D01*
X656817Y8061D01*
X656802Y8016D01*
X656797Y7976D01*
X656787Y7936D01*
X656782Y7891D01*
Y7851D01*
X656777Y7806D01*
X656782Y7761D01*
Y7721D01*
X656787Y7676D01*
X656797Y7636D01*
X656802Y7596D01*
X656817Y7551D01*
X656827Y7511D01*
X656842Y7471D01*
X656862Y7431D01*
X656877Y7396D01*
X656897Y7356D01*
X656997Y7216D01*
X657027Y7186D01*
Y3756D01*
X657037Y3631D01*
X657077Y3506D01*
X657137Y3396D01*
X657217Y3296D01*
X657317Y3216D01*
X657427Y3156D01*
X657552Y3116D01*
X657677Y3106D01*
G37*
G36*
G01X652952D02*
X653077Y3116D01*
X653202Y3156D01*
X653312Y3216D01*
X653412Y3296D01*
X653492Y3396D01*
X653552Y3506D01*
X653592Y3631D01*
X653602Y3756D01*
Y7186D01*
X653632Y7216D01*
X653732Y7356D01*
X653752Y7396D01*
X653767Y7431D01*
X653787Y7471D01*
X653802Y7511D01*
X653812Y7551D01*
X653827Y7596D01*
X653832Y7636D01*
X653842Y7676D01*
X653847Y7721D01*
Y7761D01*
X653852Y7806D01*
X653847Y7851D01*
Y7891D01*
X653842Y7936D01*
X653832Y7976D01*
X653827Y8016D01*
X653812Y8061D01*
X653802Y8101D01*
X653787Y8141D01*
X653767Y8181D01*
X653752Y8216D01*
X653732Y8256D01*
X653632Y8396D01*
X653602Y8426D01*
Y9556D01*
X653592Y9681D01*
X653552Y9806D01*
X653492Y9916D01*
X653412Y10016D01*
X653312Y10096D01*
X653202Y10156D01*
X653077Y10196D01*
X652952Y10206D01*
X652827Y10196D01*
X652702Y10156D01*
X652592Y10096D01*
X652492Y10016D01*
X652412Y9916D01*
X652352Y9806D01*
X652312Y9681D01*
X652302Y9556D01*
Y8426D01*
X652272Y8396D01*
X652172Y8256D01*
X652152Y8216D01*
X652137Y8181D01*
X652117Y8141D01*
X652102Y8101D01*
X652092Y8061D01*
X652077Y8016D01*
X652072Y7976D01*
X652062Y7936D01*
X652057Y7891D01*
Y7851D01*
X652052Y7806D01*
X652057Y7761D01*
Y7721D01*
X652062Y7676D01*
X652072Y7636D01*
X652077Y7596D01*
X652092Y7551D01*
X652102Y7511D01*
X652117Y7471D01*
X652137Y7431D01*
X652152Y7396D01*
X652172Y7356D01*
X652272Y7216D01*
X652302Y7186D01*
Y3756D01*
X652312Y3631D01*
X652352Y3506D01*
X652412Y3396D01*
X652492Y3296D01*
X652592Y3216D01*
X652702Y3156D01*
X652827Y3116D01*
X652952Y3106D01*
G37*
G36*
G01X676575D02*
X676700Y3116D01*
X676825Y3156D01*
X676935Y3216D01*
X677035Y3296D01*
X677115Y3396D01*
X677175Y3506D01*
X677215Y3631D01*
X677225Y3756D01*
Y7186D01*
X677255Y7216D01*
X677355Y7356D01*
X677375Y7396D01*
X677390Y7431D01*
X677410Y7471D01*
X677425Y7511D01*
X677435Y7551D01*
X677450Y7596D01*
X677455Y7636D01*
X677465Y7676D01*
X677470Y7721D01*
Y7761D01*
X677475Y7806D01*
X677470Y7851D01*
Y7891D01*
X677465Y7936D01*
X677455Y7976D01*
X677450Y8016D01*
X677435Y8061D01*
X677425Y8101D01*
X677410Y8141D01*
X677390Y8181D01*
X677375Y8216D01*
X677355Y8256D01*
X677255Y8396D01*
X677225Y8426D01*
Y9556D01*
X677215Y9681D01*
X677175Y9806D01*
X677115Y9916D01*
X677035Y10016D01*
X676935Y10096D01*
X676825Y10156D01*
X676700Y10196D01*
X676575Y10206D01*
X676450Y10196D01*
X676325Y10156D01*
X676215Y10096D01*
X676115Y10016D01*
X676035Y9916D01*
X675975Y9806D01*
X675935Y9681D01*
X675925Y9556D01*
Y8426D01*
X675895Y8396D01*
X675795Y8256D01*
X675775Y8216D01*
X675760Y8181D01*
X675740Y8141D01*
X675725Y8101D01*
X675715Y8061D01*
X675700Y8016D01*
X675695Y7976D01*
X675685Y7936D01*
X675680Y7891D01*
Y7851D01*
X675675Y7806D01*
X675680Y7761D01*
Y7721D01*
X675685Y7676D01*
X675695Y7636D01*
X675700Y7596D01*
X675715Y7551D01*
X675725Y7511D01*
X675740Y7471D01*
X675760Y7431D01*
X675775Y7396D01*
X675795Y7356D01*
X675895Y7216D01*
X675925Y7186D01*
Y3756D01*
X675935Y3631D01*
X675975Y3506D01*
X676035Y3396D01*
X676115Y3296D01*
X676215Y3216D01*
X676325Y3156D01*
X676450Y3116D01*
X676575Y3106D01*
G37*
G36*
G01X671850D02*
X671975Y3116D01*
X672100Y3156D01*
X672210Y3216D01*
X672310Y3296D01*
X672390Y3396D01*
X672450Y3506D01*
X672490Y3631D01*
X672500Y3756D01*
Y7186D01*
X672530Y7216D01*
X672630Y7356D01*
X672650Y7396D01*
X672665Y7431D01*
X672685Y7471D01*
X672700Y7511D01*
X672710Y7551D01*
X672725Y7596D01*
X672730Y7636D01*
X672740Y7676D01*
X672745Y7721D01*
Y7761D01*
X672750Y7806D01*
X672745Y7851D01*
Y7891D01*
X672740Y7936D01*
X672730Y7976D01*
X672725Y8016D01*
X672710Y8061D01*
X672700Y8101D01*
X672685Y8141D01*
X672665Y8181D01*
X672650Y8216D01*
X672630Y8256D01*
X672530Y8396D01*
X672500Y8426D01*
Y9556D01*
X672490Y9681D01*
X672450Y9806D01*
X672390Y9916D01*
X672310Y10016D01*
X672210Y10096D01*
X672100Y10156D01*
X671975Y10196D01*
X671850Y10206D01*
X671725Y10196D01*
X671600Y10156D01*
X671490Y10096D01*
X671390Y10016D01*
X671310Y9916D01*
X671250Y9806D01*
X671210Y9681D01*
X671200Y9556D01*
Y8426D01*
X671170Y8396D01*
X671070Y8256D01*
X671050Y8216D01*
X671035Y8181D01*
X671015Y8141D01*
X671000Y8101D01*
X670990Y8061D01*
X670975Y8016D01*
X670970Y7976D01*
X670960Y7936D01*
X670955Y7891D01*
Y7851D01*
X670950Y7806D01*
X670955Y7761D01*
Y7721D01*
X670960Y7676D01*
X670970Y7636D01*
X670975Y7596D01*
X670990Y7551D01*
X671000Y7511D01*
X671015Y7471D01*
X671035Y7431D01*
X671050Y7396D01*
X671070Y7356D01*
X671170Y7216D01*
X671200Y7186D01*
Y3756D01*
X671210Y3631D01*
X671250Y3506D01*
X671310Y3396D01*
X671390Y3296D01*
X671490Y3216D01*
X671600Y3156D01*
X671725Y3116D01*
X671850Y3106D01*
G37*
G36*
G01X667126D02*
X667251Y3116D01*
X667376Y3156D01*
X667486Y3216D01*
X667586Y3296D01*
X667666Y3396D01*
X667726Y3506D01*
X667766Y3631D01*
X667776Y3756D01*
Y7186D01*
X667806Y7216D01*
X667906Y7356D01*
X667926Y7396D01*
X667941Y7431D01*
X667961Y7471D01*
X667976Y7511D01*
X667986Y7551D01*
X668001Y7596D01*
X668006Y7636D01*
X668016Y7676D01*
X668021Y7721D01*
Y7761D01*
X668026Y7806D01*
X668021Y7851D01*
Y7891D01*
X668016Y7936D01*
X668006Y7976D01*
X668001Y8016D01*
X667986Y8061D01*
X667976Y8101D01*
X667961Y8141D01*
X667941Y8181D01*
X667926Y8216D01*
X667906Y8256D01*
X667806Y8396D01*
X667776Y8426D01*
Y9556D01*
X667766Y9681D01*
X667726Y9806D01*
X667666Y9916D01*
X667586Y10016D01*
X667486Y10096D01*
X667376Y10156D01*
X667251Y10196D01*
X667126Y10206D01*
X667001Y10196D01*
X666876Y10156D01*
X666766Y10096D01*
X666666Y10016D01*
X666586Y9916D01*
X666526Y9806D01*
X666486Y9681D01*
X666476Y9556D01*
Y8426D01*
X666446Y8396D01*
X666346Y8256D01*
X666326Y8216D01*
X666311Y8181D01*
X666291Y8141D01*
X666276Y8101D01*
X666266Y8061D01*
X666251Y8016D01*
X666246Y7976D01*
X666236Y7936D01*
X666231Y7891D01*
Y7851D01*
X666226Y7806D01*
X666231Y7761D01*
Y7721D01*
X666236Y7676D01*
X666246Y7636D01*
X666251Y7596D01*
X666266Y7551D01*
X666276Y7511D01*
X666291Y7471D01*
X666311Y7431D01*
X666326Y7396D01*
X666346Y7356D01*
X666446Y7216D01*
X666476Y7186D01*
Y3756D01*
X666486Y3631D01*
X666526Y3506D01*
X666586Y3396D01*
X666666Y3296D01*
X666766Y3216D01*
X666876Y3156D01*
X667001Y3116D01*
X667126Y3106D01*
G37*
G36*
G01X695472D02*
X695597Y3116D01*
X695722Y3156D01*
X695832Y3216D01*
X695932Y3296D01*
X696012Y3396D01*
X696072Y3506D01*
X696112Y3631D01*
X696122Y3756D01*
Y7186D01*
X696152Y7216D01*
X696252Y7356D01*
X696272Y7396D01*
X696287Y7431D01*
X696307Y7471D01*
X696322Y7511D01*
X696332Y7551D01*
X696347Y7596D01*
X696352Y7636D01*
X696362Y7676D01*
X696367Y7721D01*
Y7761D01*
X696372Y7806D01*
X696367Y7851D01*
Y7891D01*
X696362Y7936D01*
X696352Y7976D01*
X696347Y8016D01*
X696332Y8061D01*
X696322Y8101D01*
X696307Y8141D01*
X696287Y8181D01*
X696272Y8216D01*
X696252Y8256D01*
X696152Y8396D01*
X696122Y8426D01*
Y9556D01*
X696112Y9681D01*
X696072Y9806D01*
X696012Y9916D01*
X695932Y10016D01*
X695832Y10096D01*
X695722Y10156D01*
X695597Y10196D01*
X695472Y10206D01*
X695347Y10196D01*
X695222Y10156D01*
X695112Y10096D01*
X695012Y10016D01*
X694932Y9916D01*
X694872Y9806D01*
X694832Y9681D01*
X694822Y9556D01*
Y8426D01*
X694792Y8396D01*
X694692Y8256D01*
X694672Y8216D01*
X694657Y8181D01*
X694637Y8141D01*
X694622Y8101D01*
X694612Y8061D01*
X694597Y8016D01*
X694592Y7976D01*
X694582Y7936D01*
X694577Y7891D01*
Y7851D01*
X694572Y7806D01*
X694577Y7761D01*
Y7721D01*
X694582Y7676D01*
X694592Y7636D01*
X694597Y7596D01*
X694612Y7551D01*
X694622Y7511D01*
X694637Y7471D01*
X694657Y7431D01*
X694672Y7396D01*
X694692Y7356D01*
X694792Y7216D01*
X694822Y7186D01*
Y3756D01*
X694832Y3631D01*
X694872Y3506D01*
X694932Y3396D01*
X695012Y3296D01*
X695112Y3216D01*
X695222Y3156D01*
X695347Y3116D01*
X695472Y3106D01*
G37*
G36*
G01X690748D02*
X690873Y3116D01*
X690998Y3156D01*
X691108Y3216D01*
X691208Y3296D01*
X691288Y3396D01*
X691348Y3506D01*
X691388Y3631D01*
X691398Y3756D01*
Y7186D01*
X691428Y7216D01*
X691528Y7356D01*
X691548Y7396D01*
X691563Y7431D01*
X691583Y7471D01*
X691598Y7511D01*
X691608Y7551D01*
X691623Y7596D01*
X691628Y7636D01*
X691638Y7676D01*
X691643Y7721D01*
Y7761D01*
X691648Y7806D01*
X691643Y7851D01*
Y7891D01*
X691638Y7936D01*
X691628Y7976D01*
X691623Y8016D01*
X691608Y8061D01*
X691598Y8101D01*
X691583Y8141D01*
X691563Y8181D01*
X691548Y8216D01*
X691528Y8256D01*
X691428Y8396D01*
X691398Y8426D01*
Y9556D01*
X691388Y9681D01*
X691348Y9806D01*
X691288Y9916D01*
X691208Y10016D01*
X691108Y10096D01*
X690998Y10156D01*
X690873Y10196D01*
X690748Y10206D01*
X690623Y10196D01*
X690498Y10156D01*
X690388Y10096D01*
X690288Y10016D01*
X690208Y9916D01*
X690148Y9806D01*
X690108Y9681D01*
X690098Y9556D01*
Y8426D01*
X690068Y8396D01*
X689968Y8256D01*
X689948Y8216D01*
X689933Y8181D01*
X689913Y8141D01*
X689898Y8101D01*
X689888Y8061D01*
X689873Y8016D01*
X689868Y7976D01*
X689858Y7936D01*
X689853Y7891D01*
Y7851D01*
X689848Y7806D01*
X689853Y7761D01*
Y7721D01*
X689858Y7676D01*
X689868Y7636D01*
X689873Y7596D01*
X689888Y7551D01*
X689898Y7511D01*
X689913Y7471D01*
X689933Y7431D01*
X689948Y7396D01*
X689968Y7356D01*
X690068Y7216D01*
X690098Y7186D01*
Y3756D01*
X690108Y3631D01*
X690148Y3506D01*
X690208Y3396D01*
X690288Y3296D01*
X690388Y3216D01*
X690498Y3156D01*
X690623Y3116D01*
X690748Y3106D01*
G37*
G36*
G01X686023D02*
X686148Y3116D01*
X686273Y3156D01*
X686383Y3216D01*
X686483Y3296D01*
X686563Y3396D01*
X686623Y3506D01*
X686663Y3631D01*
X686673Y3756D01*
Y7186D01*
X686703Y7216D01*
X686803Y7356D01*
X686823Y7396D01*
X686838Y7431D01*
X686858Y7471D01*
X686873Y7511D01*
X686883Y7551D01*
X686898Y7596D01*
X686903Y7636D01*
X686913Y7676D01*
X686918Y7721D01*
Y7761D01*
X686923Y7806D01*
X686918Y7851D01*
Y7891D01*
X686913Y7936D01*
X686903Y7976D01*
X686898Y8016D01*
X686883Y8061D01*
X686873Y8101D01*
X686858Y8141D01*
X686838Y8181D01*
X686823Y8216D01*
X686803Y8256D01*
X686703Y8396D01*
X686673Y8426D01*
Y9556D01*
X686663Y9681D01*
X686623Y9806D01*
X686563Y9916D01*
X686483Y10016D01*
X686383Y10096D01*
X686273Y10156D01*
X686148Y10196D01*
X686023Y10206D01*
X685898Y10196D01*
X685773Y10156D01*
X685663Y10096D01*
X685563Y10016D01*
X685483Y9916D01*
X685423Y9806D01*
X685383Y9681D01*
X685373Y9556D01*
Y8426D01*
X685343Y8396D01*
X685243Y8256D01*
X685223Y8216D01*
X685208Y8181D01*
X685188Y8141D01*
X685173Y8101D01*
X685163Y8061D01*
X685148Y8016D01*
X685143Y7976D01*
X685133Y7936D01*
X685128Y7891D01*
Y7851D01*
X685123Y7806D01*
X685128Y7761D01*
Y7721D01*
X685133Y7676D01*
X685143Y7636D01*
X685148Y7596D01*
X685163Y7551D01*
X685173Y7511D01*
X685188Y7471D01*
X685208Y7431D01*
X685223Y7396D01*
X685243Y7356D01*
X685343Y7216D01*
X685373Y7186D01*
Y3756D01*
X685383Y3631D01*
X685423Y3506D01*
X685483Y3396D01*
X685563Y3296D01*
X685663Y3216D01*
X685773Y3156D01*
X685898Y3116D01*
X686023Y3106D01*
G37*
G36*
G01X681299D02*
X681424Y3116D01*
X681549Y3156D01*
X681659Y3216D01*
X681759Y3296D01*
X681839Y3396D01*
X681899Y3506D01*
X681939Y3631D01*
X681949Y3756D01*
Y7186D01*
X681979Y7216D01*
X682079Y7356D01*
X682099Y7396D01*
X682114Y7431D01*
X682134Y7471D01*
X682149Y7511D01*
X682159Y7551D01*
X682174Y7596D01*
X682179Y7636D01*
X682189Y7676D01*
X682194Y7721D01*
Y7761D01*
X682199Y7806D01*
X682194Y7851D01*
Y7891D01*
X682189Y7936D01*
X682179Y7976D01*
X682174Y8016D01*
X682159Y8061D01*
X682149Y8101D01*
X682134Y8141D01*
X682114Y8181D01*
X682099Y8216D01*
X682079Y8256D01*
X681979Y8396D01*
X681949Y8426D01*
Y9556D01*
X681939Y9681D01*
X681899Y9806D01*
X681839Y9916D01*
X681759Y10016D01*
X681659Y10096D01*
X681549Y10156D01*
X681424Y10196D01*
X681299Y10206D01*
X681174Y10196D01*
X681049Y10156D01*
X680939Y10096D01*
X680839Y10016D01*
X680759Y9916D01*
X680699Y9806D01*
X680659Y9681D01*
X680649Y9556D01*
Y8426D01*
X680619Y8396D01*
X680519Y8256D01*
X680499Y8216D01*
X680484Y8181D01*
X680464Y8141D01*
X680449Y8101D01*
X680439Y8061D01*
X680424Y8016D01*
X680419Y7976D01*
X680409Y7936D01*
X680404Y7891D01*
Y7851D01*
X680399Y7806D01*
X680404Y7761D01*
Y7721D01*
X680409Y7676D01*
X680419Y7636D01*
X680424Y7596D01*
X680439Y7551D01*
X680449Y7511D01*
X680464Y7471D01*
X680484Y7431D01*
X680499Y7396D01*
X680519Y7356D01*
X680619Y7216D01*
X680649Y7186D01*
Y3756D01*
X680659Y3631D01*
X680699Y3506D01*
X680759Y3396D01*
X680839Y3296D01*
X680939Y3216D01*
X681049Y3156D01*
X681174Y3116D01*
X681299Y3106D01*
G37*
G36*
G01X709645D02*
X709770Y3116D01*
X709895Y3156D01*
X710005Y3216D01*
X710105Y3296D01*
X710185Y3396D01*
X710245Y3506D01*
X710285Y3631D01*
X710295Y3756D01*
Y7186D01*
X710325Y7216D01*
X710425Y7356D01*
X710445Y7396D01*
X710460Y7431D01*
X710480Y7471D01*
X710495Y7511D01*
X710505Y7551D01*
X710520Y7596D01*
X710525Y7636D01*
X710535Y7676D01*
X710540Y7721D01*
Y7761D01*
X710545Y7806D01*
X710540Y7851D01*
Y7891D01*
X710535Y7936D01*
X710525Y7976D01*
X710520Y8016D01*
X710505Y8061D01*
X710495Y8101D01*
X710480Y8141D01*
X710460Y8181D01*
X710445Y8216D01*
X710425Y8256D01*
X710325Y8396D01*
X710295Y8426D01*
Y9556D01*
X710285Y9681D01*
X710245Y9806D01*
X710185Y9916D01*
X710105Y10016D01*
X710005Y10096D01*
X709895Y10156D01*
X709770Y10196D01*
X709645Y10206D01*
X709520Y10196D01*
X709395Y10156D01*
X709285Y10096D01*
X709185Y10016D01*
X709105Y9916D01*
X709045Y9806D01*
X709005Y9681D01*
X708995Y9556D01*
Y8426D01*
X708965Y8396D01*
X708865Y8256D01*
X708845Y8216D01*
X708830Y8181D01*
X708810Y8141D01*
X708795Y8101D01*
X708785Y8061D01*
X708770Y8016D01*
X708765Y7976D01*
X708755Y7936D01*
X708750Y7891D01*
Y7851D01*
X708745Y7806D01*
X708750Y7761D01*
Y7721D01*
X708755Y7676D01*
X708765Y7636D01*
X708770Y7596D01*
X708785Y7551D01*
X708795Y7511D01*
X708810Y7471D01*
X708830Y7431D01*
X708845Y7396D01*
X708865Y7356D01*
X708965Y7216D01*
X708995Y7186D01*
Y3756D01*
X709005Y3631D01*
X709045Y3506D01*
X709105Y3396D01*
X709185Y3296D01*
X709285Y3216D01*
X709395Y3156D01*
X709520Y3116D01*
X709645Y3106D01*
G37*
G36*
G01X704921D02*
X705046Y3116D01*
X705171Y3156D01*
X705281Y3216D01*
X705381Y3296D01*
X705461Y3396D01*
X705521Y3506D01*
X705561Y3631D01*
X705571Y3756D01*
Y7186D01*
X705601Y7216D01*
X705701Y7356D01*
X705721Y7396D01*
X705736Y7431D01*
X705756Y7471D01*
X705771Y7511D01*
X705781Y7551D01*
X705796Y7596D01*
X705801Y7636D01*
X705811Y7676D01*
X705816Y7721D01*
Y7761D01*
X705821Y7806D01*
X705816Y7851D01*
Y7891D01*
X705811Y7936D01*
X705801Y7976D01*
X705796Y8016D01*
X705781Y8061D01*
X705771Y8101D01*
X705756Y8141D01*
X705736Y8181D01*
X705721Y8216D01*
X705701Y8256D01*
X705601Y8396D01*
X705571Y8426D01*
Y9556D01*
X705561Y9681D01*
X705521Y9806D01*
X705461Y9916D01*
X705381Y10016D01*
X705281Y10096D01*
X705171Y10156D01*
X705046Y10196D01*
X704921Y10206D01*
X704796Y10196D01*
X704671Y10156D01*
X704561Y10096D01*
X704461Y10016D01*
X704381Y9916D01*
X704321Y9806D01*
X704281Y9681D01*
X704271Y9556D01*
Y8426D01*
X704241Y8396D01*
X704141Y8256D01*
X704121Y8216D01*
X704106Y8181D01*
X704086Y8141D01*
X704071Y8101D01*
X704061Y8061D01*
X704046Y8016D01*
X704041Y7976D01*
X704031Y7936D01*
X704026Y7891D01*
Y7851D01*
X704021Y7806D01*
X704026Y7761D01*
Y7721D01*
X704031Y7676D01*
X704041Y7636D01*
X704046Y7596D01*
X704061Y7551D01*
X704071Y7511D01*
X704086Y7471D01*
X704106Y7431D01*
X704121Y7396D01*
X704141Y7356D01*
X704241Y7216D01*
X704271Y7186D01*
Y3756D01*
X704281Y3631D01*
X704321Y3506D01*
X704381Y3396D01*
X704461Y3296D01*
X704561Y3216D01*
X704671Y3156D01*
X704796Y3116D01*
X704921Y3106D01*
G37*
G36*
G01X700197D02*
X700322Y3116D01*
X700447Y3156D01*
X700557Y3216D01*
X700657Y3296D01*
X700737Y3396D01*
X700797Y3506D01*
X700837Y3631D01*
X700847Y3756D01*
Y7186D01*
X700877Y7216D01*
X700977Y7356D01*
X700997Y7396D01*
X701012Y7431D01*
X701032Y7471D01*
X701047Y7511D01*
X701057Y7551D01*
X701072Y7596D01*
X701077Y7636D01*
X701087Y7676D01*
X701092Y7721D01*
Y7761D01*
X701097Y7806D01*
X701092Y7851D01*
Y7891D01*
X701087Y7936D01*
X701077Y7976D01*
X701072Y8016D01*
X701057Y8061D01*
X701047Y8101D01*
X701032Y8141D01*
X701012Y8181D01*
X700997Y8216D01*
X700977Y8256D01*
X700877Y8396D01*
X700847Y8426D01*
Y9556D01*
X700837Y9681D01*
X700797Y9806D01*
X700737Y9916D01*
X700657Y10016D01*
X700557Y10096D01*
X700447Y10156D01*
X700322Y10196D01*
X700197Y10206D01*
X700072Y10196D01*
X699947Y10156D01*
X699837Y10096D01*
X699737Y10016D01*
X699657Y9916D01*
X699597Y9806D01*
X699557Y9681D01*
X699547Y9556D01*
Y8426D01*
X699517Y8396D01*
X699417Y8256D01*
X699397Y8216D01*
X699382Y8181D01*
X699362Y8141D01*
X699347Y8101D01*
X699337Y8061D01*
X699322Y8016D01*
X699317Y7976D01*
X699307Y7936D01*
X699302Y7891D01*
Y7851D01*
X699297Y7806D01*
X699302Y7761D01*
Y7721D01*
X699307Y7676D01*
X699317Y7636D01*
X699322Y7596D01*
X699337Y7551D01*
X699347Y7511D01*
X699362Y7471D01*
X699382Y7431D01*
X699397Y7396D01*
X699417Y7356D01*
X699517Y7216D01*
X699547Y7186D01*
Y3756D01*
X699557Y3631D01*
X699597Y3506D01*
X699657Y3396D01*
X699737Y3296D01*
X699837Y3216D01*
X699947Y3156D01*
X700072Y3116D01*
X700197Y3106D01*
G37*
G36*
G01X723819D02*
X723944Y3116D01*
X724069Y3156D01*
X724179Y3216D01*
X724279Y3296D01*
X724359Y3396D01*
X724419Y3506D01*
X724459Y3631D01*
X724469Y3756D01*
Y7186D01*
X724499Y7216D01*
X724599Y7356D01*
X724619Y7396D01*
X724634Y7431D01*
X724654Y7471D01*
X724669Y7511D01*
X724679Y7551D01*
X724694Y7596D01*
X724699Y7636D01*
X724709Y7676D01*
X724714Y7721D01*
Y7761D01*
X724719Y7806D01*
X724714Y7851D01*
Y7891D01*
X724709Y7936D01*
X724699Y7976D01*
X724694Y8016D01*
X724679Y8061D01*
X724669Y8101D01*
X724654Y8141D01*
X724634Y8181D01*
X724619Y8216D01*
X724599Y8256D01*
X724499Y8396D01*
X724469Y8426D01*
Y9556D01*
X724459Y9681D01*
X724419Y9806D01*
X724359Y9916D01*
X724279Y10016D01*
X724179Y10096D01*
X724069Y10156D01*
X723944Y10196D01*
X723819Y10206D01*
X723694Y10196D01*
X723569Y10156D01*
X723459Y10096D01*
X723359Y10016D01*
X723279Y9916D01*
X723219Y9806D01*
X723179Y9681D01*
X723169Y9556D01*
Y8426D01*
X723139Y8396D01*
X723039Y8256D01*
X723019Y8216D01*
X723004Y8181D01*
X722984Y8141D01*
X722969Y8101D01*
X722959Y8061D01*
X722944Y8016D01*
X722939Y7976D01*
X722929Y7936D01*
X722924Y7891D01*
Y7851D01*
X722919Y7806D01*
X722924Y7761D01*
Y7721D01*
X722929Y7676D01*
X722939Y7636D01*
X722944Y7596D01*
X722959Y7551D01*
X722969Y7511D01*
X722984Y7471D01*
X723004Y7431D01*
X723019Y7396D01*
X723039Y7356D01*
X723139Y7216D01*
X723169Y7186D01*
Y3756D01*
X723179Y3631D01*
X723219Y3506D01*
X723279Y3396D01*
X723359Y3296D01*
X723459Y3216D01*
X723569Y3156D01*
X723694Y3116D01*
X723819Y3106D01*
G37*
G36*
G01X719094D02*
X719219Y3116D01*
X719344Y3156D01*
X719454Y3216D01*
X719554Y3296D01*
X719634Y3396D01*
X719694Y3506D01*
X719734Y3631D01*
X719744Y3756D01*
Y7186D01*
X719774Y7216D01*
X719874Y7356D01*
X719894Y7396D01*
X719909Y7431D01*
X719929Y7471D01*
X719944Y7511D01*
X719954Y7551D01*
X719969Y7596D01*
X719974Y7636D01*
X719984Y7676D01*
X719989Y7721D01*
Y7761D01*
X719994Y7806D01*
X719989Y7851D01*
Y7891D01*
X719984Y7936D01*
X719974Y7976D01*
X719969Y8016D01*
X719954Y8061D01*
X719944Y8101D01*
X719929Y8141D01*
X719909Y8181D01*
X719894Y8216D01*
X719874Y8256D01*
X719774Y8396D01*
X719744Y8426D01*
Y9556D01*
X719734Y9681D01*
X719694Y9806D01*
X719634Y9916D01*
X719554Y10016D01*
X719454Y10096D01*
X719344Y10156D01*
X719219Y10196D01*
X719094Y10206D01*
X718969Y10196D01*
X718844Y10156D01*
X718734Y10096D01*
X718634Y10016D01*
X718554Y9916D01*
X718494Y9806D01*
X718454Y9681D01*
X718444Y9556D01*
Y8426D01*
X718414Y8396D01*
X718314Y8256D01*
X718294Y8216D01*
X718279Y8181D01*
X718259Y8141D01*
X718244Y8101D01*
X718234Y8061D01*
X718219Y8016D01*
X718214Y7976D01*
X718204Y7936D01*
X718199Y7891D01*
Y7851D01*
X718194Y7806D01*
X718199Y7761D01*
Y7721D01*
X718204Y7676D01*
X718214Y7636D01*
X718219Y7596D01*
X718234Y7551D01*
X718244Y7511D01*
X718259Y7471D01*
X718279Y7431D01*
X718294Y7396D01*
X718314Y7356D01*
X718414Y7216D01*
X718444Y7186D01*
Y3756D01*
X718454Y3631D01*
X718494Y3506D01*
X718554Y3396D01*
X718634Y3296D01*
X718734Y3216D01*
X718844Y3156D01*
X718969Y3116D01*
X719094Y3106D01*
G37*
G36*
G01X714370D02*
X714495Y3116D01*
X714620Y3156D01*
X714730Y3216D01*
X714830Y3296D01*
X714910Y3396D01*
X714970Y3506D01*
X715010Y3631D01*
X715020Y3756D01*
Y7186D01*
X715050Y7216D01*
X715150Y7356D01*
X715170Y7396D01*
X715185Y7431D01*
X715205Y7471D01*
X715220Y7511D01*
X715230Y7551D01*
X715245Y7596D01*
X715250Y7636D01*
X715260Y7676D01*
X715265Y7721D01*
Y7761D01*
X715270Y7806D01*
X715265Y7851D01*
Y7891D01*
X715260Y7936D01*
X715250Y7976D01*
X715245Y8016D01*
X715230Y8061D01*
X715220Y8101D01*
X715205Y8141D01*
X715185Y8181D01*
X715170Y8216D01*
X715150Y8256D01*
X715050Y8396D01*
X715020Y8426D01*
Y9556D01*
X715010Y9681D01*
X714970Y9806D01*
X714910Y9916D01*
X714830Y10016D01*
X714730Y10096D01*
X714620Y10156D01*
X714495Y10196D01*
X714370Y10206D01*
X714245Y10196D01*
X714120Y10156D01*
X714010Y10096D01*
X713910Y10016D01*
X713830Y9916D01*
X713770Y9806D01*
X713730Y9681D01*
X713720Y9556D01*
Y8426D01*
X713690Y8396D01*
X713590Y8256D01*
X713570Y8216D01*
X713555Y8181D01*
X713535Y8141D01*
X713520Y8101D01*
X713510Y8061D01*
X713495Y8016D01*
X713490Y7976D01*
X713480Y7936D01*
X713475Y7891D01*
Y7851D01*
X713470Y7806D01*
X713475Y7761D01*
Y7721D01*
X713480Y7676D01*
X713490Y7636D01*
X713495Y7596D01*
X713510Y7551D01*
X713520Y7511D01*
X713535Y7471D01*
X713555Y7431D01*
X713570Y7396D01*
X713590Y7356D01*
X713690Y7216D01*
X713720Y7186D01*
Y3756D01*
X713730Y3631D01*
X713770Y3506D01*
X713830Y3396D01*
X713910Y3296D01*
X714010Y3216D01*
X714120Y3156D01*
X714245Y3116D01*
X714370Y3106D01*
G37*
G36*
G01X737992D02*
X738117Y3116D01*
X738242Y3156D01*
X738352Y3216D01*
X738452Y3296D01*
X738532Y3396D01*
X738592Y3506D01*
X738632Y3631D01*
X738642Y3756D01*
Y7186D01*
X738672Y7216D01*
X738772Y7356D01*
X738792Y7396D01*
X738807Y7431D01*
X738827Y7471D01*
X738842Y7511D01*
X738852Y7551D01*
X738867Y7596D01*
X738872Y7636D01*
X738882Y7676D01*
X738887Y7721D01*
Y7761D01*
X738892Y7806D01*
X738887Y7851D01*
Y7891D01*
X738882Y7936D01*
X738872Y7976D01*
X738867Y8016D01*
X738852Y8061D01*
X738842Y8101D01*
X738827Y8141D01*
X738807Y8181D01*
X738792Y8216D01*
X738772Y8256D01*
X738672Y8396D01*
X738642Y8426D01*
Y9556D01*
X738632Y9681D01*
X738592Y9806D01*
X738532Y9916D01*
X738452Y10016D01*
X738352Y10096D01*
X738242Y10156D01*
X738117Y10196D01*
X737992Y10206D01*
X737867Y10196D01*
X737742Y10156D01*
X737632Y10096D01*
X737532Y10016D01*
X737452Y9916D01*
X737392Y9806D01*
X737352Y9681D01*
X737342Y9556D01*
Y8426D01*
X737312Y8396D01*
X737212Y8256D01*
X737192Y8216D01*
X737177Y8181D01*
X737157Y8141D01*
X737142Y8101D01*
X737132Y8061D01*
X737117Y8016D01*
X737112Y7976D01*
X737102Y7936D01*
X737097Y7891D01*
Y7851D01*
X737092Y7806D01*
X737097Y7761D01*
Y7721D01*
X737102Y7676D01*
X737112Y7636D01*
X737117Y7596D01*
X737132Y7551D01*
X737142Y7511D01*
X737157Y7471D01*
X737177Y7431D01*
X737192Y7396D01*
X737212Y7356D01*
X737312Y7216D01*
X737342Y7186D01*
Y3756D01*
X737352Y3631D01*
X737392Y3506D01*
X737452Y3396D01*
X737532Y3296D01*
X737632Y3216D01*
X737742Y3156D01*
X737867Y3116D01*
X737992Y3106D01*
G37*
G36*
G01X733267D02*
X733392Y3116D01*
X733517Y3156D01*
X733627Y3216D01*
X733727Y3296D01*
X733807Y3396D01*
X733867Y3506D01*
X733907Y3631D01*
X733917Y3756D01*
Y7186D01*
X733947Y7216D01*
X734047Y7356D01*
X734067Y7396D01*
X734082Y7431D01*
X734102Y7471D01*
X734117Y7511D01*
X734127Y7551D01*
X734142Y7596D01*
X734147Y7636D01*
X734157Y7676D01*
X734162Y7721D01*
Y7761D01*
X734167Y7806D01*
X734162Y7851D01*
Y7891D01*
X734157Y7936D01*
X734147Y7976D01*
X734142Y8016D01*
X734127Y8061D01*
X734117Y8101D01*
X734102Y8141D01*
X734082Y8181D01*
X734067Y8216D01*
X734047Y8256D01*
X733947Y8396D01*
X733917Y8426D01*
Y9556D01*
X733907Y9681D01*
X733867Y9806D01*
X733807Y9916D01*
X733727Y10016D01*
X733627Y10096D01*
X733517Y10156D01*
X733392Y10196D01*
X733267Y10206D01*
X733142Y10196D01*
X733017Y10156D01*
X732907Y10096D01*
X732807Y10016D01*
X732727Y9916D01*
X732667Y9806D01*
X732627Y9681D01*
X732617Y9556D01*
Y8426D01*
X732587Y8396D01*
X732487Y8256D01*
X732467Y8216D01*
X732452Y8181D01*
X732432Y8141D01*
X732417Y8101D01*
X732407Y8061D01*
X732392Y8016D01*
X732387Y7976D01*
X732377Y7936D01*
X732372Y7891D01*
Y7851D01*
X732367Y7806D01*
X732372Y7761D01*
Y7721D01*
X732377Y7676D01*
X732387Y7636D01*
X732392Y7596D01*
X732407Y7551D01*
X732417Y7511D01*
X732432Y7471D01*
X732452Y7431D01*
X732467Y7396D01*
X732487Y7356D01*
X732587Y7216D01*
X732617Y7186D01*
Y3756D01*
X732627Y3631D01*
X732667Y3506D01*
X732727Y3396D01*
X732807Y3296D01*
X732907Y3216D01*
X733017Y3156D01*
X733142Y3116D01*
X733267Y3106D01*
G37*
G36*
G01X728543D02*
X728668Y3116D01*
X728793Y3156D01*
X728903Y3216D01*
X729003Y3296D01*
X729083Y3396D01*
X729143Y3506D01*
X729183Y3631D01*
X729193Y3756D01*
Y7186D01*
X729223Y7216D01*
X729323Y7356D01*
X729343Y7396D01*
X729358Y7431D01*
X729378Y7471D01*
X729393Y7511D01*
X729403Y7551D01*
X729418Y7596D01*
X729423Y7636D01*
X729433Y7676D01*
X729438Y7721D01*
Y7761D01*
X729443Y7806D01*
X729438Y7851D01*
Y7891D01*
X729433Y7936D01*
X729423Y7976D01*
X729418Y8016D01*
X729403Y8061D01*
X729393Y8101D01*
X729378Y8141D01*
X729358Y8181D01*
X729343Y8216D01*
X729323Y8256D01*
X729223Y8396D01*
X729193Y8426D01*
Y9556D01*
X729183Y9681D01*
X729143Y9806D01*
X729083Y9916D01*
X729003Y10016D01*
X728903Y10096D01*
X728793Y10156D01*
X728668Y10196D01*
X728543Y10206D01*
X728418Y10196D01*
X728293Y10156D01*
X728183Y10096D01*
X728083Y10016D01*
X728003Y9916D01*
X727943Y9806D01*
X727903Y9681D01*
X727893Y9556D01*
Y8426D01*
X727863Y8396D01*
X727763Y8256D01*
X727743Y8216D01*
X727728Y8181D01*
X727708Y8141D01*
X727693Y8101D01*
X727683Y8061D01*
X727668Y8016D01*
X727663Y7976D01*
X727653Y7936D01*
X727648Y7891D01*
Y7851D01*
X727643Y7806D01*
X727648Y7761D01*
Y7721D01*
X727653Y7676D01*
X727663Y7636D01*
X727668Y7596D01*
X727683Y7551D01*
X727693Y7511D01*
X727708Y7471D01*
X727728Y7431D01*
X727743Y7396D01*
X727763Y7356D01*
X727863Y7216D01*
X727893Y7186D01*
Y3756D01*
X727903Y3631D01*
X727943Y3506D01*
X728003Y3396D01*
X728083Y3296D01*
X728183Y3216D01*
X728293Y3156D01*
X728418Y3116D01*
X728543Y3106D01*
G37*
G36*
G01X752165D02*
X752290Y3116D01*
X752415Y3156D01*
X752525Y3216D01*
X752625Y3296D01*
X752705Y3396D01*
X752765Y3506D01*
X752805Y3631D01*
X752815Y3756D01*
Y7186D01*
X752845Y7216D01*
X752945Y7356D01*
X752965Y7396D01*
X752980Y7431D01*
X753000Y7471D01*
X753015Y7511D01*
X753025Y7551D01*
X753040Y7596D01*
X753045Y7636D01*
X753055Y7676D01*
X753060Y7721D01*
Y7761D01*
X753065Y7806D01*
X753060Y7851D01*
Y7891D01*
X753055Y7936D01*
X753045Y7976D01*
X753040Y8016D01*
X753025Y8061D01*
X753015Y8101D01*
X753000Y8141D01*
X752980Y8181D01*
X752965Y8216D01*
X752945Y8256D01*
X752845Y8396D01*
X752815Y8426D01*
Y9556D01*
X752805Y9681D01*
X752765Y9806D01*
X752705Y9916D01*
X752625Y10016D01*
X752525Y10096D01*
X752415Y10156D01*
X752290Y10196D01*
X752165Y10206D01*
X752040Y10196D01*
X751915Y10156D01*
X751805Y10096D01*
X751705Y10016D01*
X751625Y9916D01*
X751565Y9806D01*
X751525Y9681D01*
X751515Y9556D01*
Y8426D01*
X751485Y8396D01*
X751385Y8256D01*
X751365Y8216D01*
X751350Y8181D01*
X751330Y8141D01*
X751315Y8101D01*
X751305Y8061D01*
X751290Y8016D01*
X751285Y7976D01*
X751275Y7936D01*
X751270Y7891D01*
Y7851D01*
X751265Y7806D01*
X751270Y7761D01*
Y7721D01*
X751275Y7676D01*
X751285Y7636D01*
X751290Y7596D01*
X751305Y7551D01*
X751315Y7511D01*
X751330Y7471D01*
X751350Y7431D01*
X751365Y7396D01*
X751385Y7356D01*
X751485Y7216D01*
X751515Y7186D01*
Y3756D01*
X751525Y3631D01*
X751565Y3506D01*
X751625Y3396D01*
X751705Y3296D01*
X751805Y3216D01*
X751915Y3156D01*
X752040Y3116D01*
X752165Y3106D01*
G37*
G36*
G01X747441D02*
X747566Y3116D01*
X747691Y3156D01*
X747801Y3216D01*
X747901Y3296D01*
X747981Y3396D01*
X748041Y3506D01*
X748081Y3631D01*
X748091Y3756D01*
Y7186D01*
X748121Y7216D01*
X748221Y7356D01*
X748241Y7396D01*
X748256Y7431D01*
X748276Y7471D01*
X748291Y7511D01*
X748301Y7551D01*
X748316Y7596D01*
X748321Y7636D01*
X748331Y7676D01*
X748336Y7721D01*
Y7761D01*
X748341Y7806D01*
X748336Y7851D01*
Y7891D01*
X748331Y7936D01*
X748321Y7976D01*
X748316Y8016D01*
X748301Y8061D01*
X748291Y8101D01*
X748276Y8141D01*
X748256Y8181D01*
X748241Y8216D01*
X748221Y8256D01*
X748121Y8396D01*
X748091Y8426D01*
Y9556D01*
X748081Y9681D01*
X748041Y9806D01*
X747981Y9916D01*
X747901Y10016D01*
X747801Y10096D01*
X747691Y10156D01*
X747566Y10196D01*
X747441Y10206D01*
X747316Y10196D01*
X747191Y10156D01*
X747081Y10096D01*
X746981Y10016D01*
X746901Y9916D01*
X746841Y9806D01*
X746801Y9681D01*
X746791Y9556D01*
Y8426D01*
X746761Y8396D01*
X746661Y8256D01*
X746641Y8216D01*
X746626Y8181D01*
X746606Y8141D01*
X746591Y8101D01*
X746581Y8061D01*
X746566Y8016D01*
X746561Y7976D01*
X746551Y7936D01*
X746546Y7891D01*
Y7851D01*
X746541Y7806D01*
X746546Y7761D01*
Y7721D01*
X746551Y7676D01*
X746561Y7636D01*
X746566Y7596D01*
X746581Y7551D01*
X746591Y7511D01*
X746606Y7471D01*
X746626Y7431D01*
X746641Y7396D01*
X746661Y7356D01*
X746761Y7216D01*
X746791Y7186D01*
Y3756D01*
X746801Y3631D01*
X746841Y3506D01*
X746901Y3396D01*
X746981Y3296D01*
X747081Y3216D01*
X747191Y3156D01*
X747316Y3116D01*
X747441Y3106D01*
G37*
G36*
G01X742716D02*
X742841Y3116D01*
X742966Y3156D01*
X743076Y3216D01*
X743176Y3296D01*
X743256Y3396D01*
X743316Y3506D01*
X743356Y3631D01*
X743366Y3756D01*
Y7186D01*
X743396Y7216D01*
X743496Y7356D01*
X743516Y7396D01*
X743531Y7431D01*
X743551Y7471D01*
X743566Y7511D01*
X743576Y7551D01*
X743591Y7596D01*
X743596Y7636D01*
X743606Y7676D01*
X743611Y7721D01*
Y7761D01*
X743616Y7806D01*
X743611Y7851D01*
Y7891D01*
X743606Y7936D01*
X743596Y7976D01*
X743591Y8016D01*
X743576Y8061D01*
X743566Y8101D01*
X743551Y8141D01*
X743531Y8181D01*
X743516Y8216D01*
X743496Y8256D01*
X743396Y8396D01*
X743366Y8426D01*
Y9556D01*
X743356Y9681D01*
X743316Y9806D01*
X743256Y9916D01*
X743176Y10016D01*
X743076Y10096D01*
X742966Y10156D01*
X742841Y10196D01*
X742716Y10206D01*
X742591Y10196D01*
X742466Y10156D01*
X742356Y10096D01*
X742256Y10016D01*
X742176Y9916D01*
X742116Y9806D01*
X742076Y9681D01*
X742066Y9556D01*
Y8426D01*
X742036Y8396D01*
X741936Y8256D01*
X741916Y8216D01*
X741901Y8181D01*
X741881Y8141D01*
X741866Y8101D01*
X741856Y8061D01*
X741841Y8016D01*
X741836Y7976D01*
X741826Y7936D01*
X741821Y7891D01*
Y7851D01*
X741816Y7806D01*
X741821Y7761D01*
Y7721D01*
X741826Y7676D01*
X741836Y7636D01*
X741841Y7596D01*
X741856Y7551D01*
X741866Y7511D01*
X741881Y7471D01*
X741901Y7431D01*
X741916Y7396D01*
X741936Y7356D01*
X742036Y7216D01*
X742066Y7186D01*
Y3756D01*
X742076Y3631D01*
X742116Y3506D01*
X742176Y3396D01*
X742256Y3296D01*
X742356Y3216D01*
X742466Y3156D01*
X742591Y3116D01*
X742716Y3106D01*
G37*
G54D77*
X402250Y254500D03*
G54D59*
X272079Y73795D03*
X274047D03*
X276016D03*
X277984D03*
Y84205D03*
X276016D03*
X274047D03*
X272079D03*
X279953Y73795D03*
X281921D03*
Y84205D03*
X279953D03*
G54D68*
X318764Y62400D03*
X321323D03*
X323882D03*
Y80886D03*
X321323D03*
X318764D03*
X326441Y62400D03*
X329000D03*
Y80886D03*
X326441D03*
G54D95*
X787215Y261024D03*
X782077D03*
X787215Y270866D03*
X782077D03*
X794969Y134600D03*
X789831D03*
X794969Y129300D03*
X789831D03*
X794969Y124000D03*
X789831D03*
X795069Y152300D03*
X789931D03*
X794969Y139900D03*
X789831D03*
X795069Y157500D03*
X789931D03*
X795069Y162700D03*
X789931D03*
X795069Y167900D03*
X789931D03*
G36*
G01X507677Y35390D02*
X507802Y35400D01*
X507927Y35440D01*
X508037Y35500D01*
X508137Y35580D01*
X508217Y35680D01*
X508277Y35790D01*
X508317Y35915D01*
X508327Y36040D01*
Y38165D01*
X508357Y38195D01*
X508382Y38230D01*
X508412Y38265D01*
X508432Y38300D01*
X508457Y38335D01*
X508497Y38415D01*
X508542Y38535D01*
X508552Y38575D01*
X508562Y38620D01*
X508567Y38660D01*
X508577Y38705D01*
Y38875D01*
X508567Y38920D01*
X508562Y38960D01*
X508552Y39005D01*
X508542Y39045D01*
X508497Y39165D01*
X508457Y39245D01*
X508432Y39280D01*
X508412Y39315D01*
X508382Y39350D01*
X508357Y39385D01*
X508327Y39415D01*
Y41840D01*
X508317Y41965D01*
X508277Y42090D01*
X508217Y42200D01*
X508137Y42300D01*
X508037Y42380D01*
X507927Y42440D01*
X507802Y42480D01*
X507677Y42490D01*
X507552Y42480D01*
X507427Y42440D01*
X507317Y42380D01*
X507217Y42300D01*
X507137Y42200D01*
X507077Y42090D01*
X507037Y41965D01*
X507027Y41840D01*
Y39410D01*
X506997Y39380D01*
X506897Y39240D01*
X506877Y39200D01*
X506862Y39165D01*
X506842Y39125D01*
X506827Y39085D01*
X506817Y39045D01*
X506802Y39000D01*
X506797Y38960D01*
X506787Y38920D01*
X506782Y38875D01*
Y38835D01*
X506777Y38790D01*
X506782Y38745D01*
Y38705D01*
X506787Y38660D01*
X506797Y38620D01*
X506802Y38580D01*
X506817Y38535D01*
X506827Y38495D01*
X506842Y38455D01*
X506862Y38415D01*
X506877Y38380D01*
X506897Y38340D01*
X506997Y38200D01*
X507027Y38170D01*
Y36040D01*
X507037Y35915D01*
X507077Y35790D01*
X507137Y35680D01*
X507217Y35580D01*
X507317Y35500D01*
X507427Y35440D01*
X507552Y35400D01*
X507677Y35390D01*
G37*
G36*
G01X521850D02*
X521975Y35400D01*
X522100Y35440D01*
X522210Y35500D01*
X522310Y35580D01*
X522390Y35680D01*
X522450Y35790D01*
X522490Y35915D01*
X522500Y36040D01*
Y38165D01*
X522530Y38195D01*
X522555Y38230D01*
X522585Y38265D01*
X522605Y38300D01*
X522630Y38335D01*
X522670Y38415D01*
X522715Y38535D01*
X522725Y38575D01*
X522735Y38620D01*
X522740Y38660D01*
X522750Y38705D01*
Y38875D01*
X522740Y38920D01*
X522735Y38960D01*
X522725Y39005D01*
X522715Y39045D01*
X522670Y39165D01*
X522630Y39245D01*
X522605Y39280D01*
X522585Y39315D01*
X522555Y39350D01*
X522530Y39385D01*
X522500Y39415D01*
Y41840D01*
X522490Y41965D01*
X522450Y42090D01*
X522390Y42200D01*
X522310Y42300D01*
X522210Y42380D01*
X522100Y42440D01*
X521975Y42480D01*
X521850Y42490D01*
X521725Y42480D01*
X521600Y42440D01*
X521490Y42380D01*
X521390Y42300D01*
X521310Y42200D01*
X521250Y42090D01*
X521210Y41965D01*
X521200Y41840D01*
Y39410D01*
X521170Y39380D01*
X521070Y39240D01*
X521050Y39200D01*
X521035Y39165D01*
X521015Y39125D01*
X521000Y39085D01*
X520990Y39045D01*
X520975Y39000D01*
X520970Y38960D01*
X520960Y38920D01*
X520955Y38875D01*
Y38835D01*
X520950Y38790D01*
X520955Y38745D01*
Y38705D01*
X520960Y38660D01*
X520970Y38620D01*
X520975Y38580D01*
X520990Y38535D01*
X521000Y38495D01*
X521015Y38455D01*
X521035Y38415D01*
X521050Y38380D01*
X521070Y38340D01*
X521170Y38200D01*
X521200Y38170D01*
Y36040D01*
X521210Y35915D01*
X521250Y35790D01*
X521310Y35680D01*
X521390Y35580D01*
X521490Y35500D01*
X521600Y35440D01*
X521725Y35400D01*
X521850Y35390D01*
G37*
G36*
G01X517126D02*
X517251Y35400D01*
X517376Y35440D01*
X517486Y35500D01*
X517586Y35580D01*
X517666Y35680D01*
X517726Y35790D01*
X517766Y35915D01*
X517776Y36040D01*
Y38165D01*
X517806Y38195D01*
X517831Y38230D01*
X517861Y38265D01*
X517881Y38300D01*
X517906Y38335D01*
X517946Y38415D01*
X517991Y38535D01*
X518001Y38575D01*
X518011Y38620D01*
X518016Y38660D01*
X518026Y38705D01*
Y38875D01*
X518016Y38920D01*
X518011Y38960D01*
X518001Y39005D01*
X517991Y39045D01*
X517946Y39165D01*
X517906Y39245D01*
X517881Y39280D01*
X517861Y39315D01*
X517831Y39350D01*
X517806Y39385D01*
X517776Y39415D01*
Y41840D01*
X517766Y41965D01*
X517726Y42090D01*
X517666Y42200D01*
X517586Y42300D01*
X517486Y42380D01*
X517376Y42440D01*
X517251Y42480D01*
X517126Y42490D01*
X517001Y42480D01*
X516876Y42440D01*
X516766Y42380D01*
X516666Y42300D01*
X516586Y42200D01*
X516526Y42090D01*
X516486Y41965D01*
X516476Y41840D01*
Y39410D01*
X516446Y39380D01*
X516346Y39240D01*
X516326Y39200D01*
X516311Y39165D01*
X516291Y39125D01*
X516276Y39085D01*
X516266Y39045D01*
X516251Y39000D01*
X516246Y38960D01*
X516236Y38920D01*
X516231Y38875D01*
Y38835D01*
X516226Y38790D01*
X516231Y38745D01*
Y38705D01*
X516236Y38660D01*
X516246Y38620D01*
X516251Y38580D01*
X516266Y38535D01*
X516276Y38495D01*
X516291Y38455D01*
X516311Y38415D01*
X516326Y38380D01*
X516346Y38340D01*
X516446Y38200D01*
X516476Y38170D01*
Y36040D01*
X516486Y35915D01*
X516526Y35790D01*
X516586Y35680D01*
X516666Y35580D01*
X516766Y35500D01*
X516876Y35440D01*
X517001Y35400D01*
X517126Y35390D01*
G37*
G36*
G01X512401D02*
X512526Y35400D01*
X512651Y35440D01*
X512761Y35500D01*
X512861Y35580D01*
X512941Y35680D01*
X513001Y35790D01*
X513041Y35915D01*
X513051Y36040D01*
Y38165D01*
X513081Y38195D01*
X513106Y38230D01*
X513136Y38265D01*
X513156Y38300D01*
X513181Y38335D01*
X513221Y38415D01*
X513266Y38535D01*
X513276Y38575D01*
X513286Y38620D01*
X513291Y38660D01*
X513301Y38705D01*
Y38875D01*
X513291Y38920D01*
X513286Y38960D01*
X513276Y39005D01*
X513266Y39045D01*
X513221Y39165D01*
X513181Y39245D01*
X513156Y39280D01*
X513136Y39315D01*
X513106Y39350D01*
X513081Y39385D01*
X513051Y39415D01*
Y41840D01*
X513041Y41965D01*
X513001Y42090D01*
X512941Y42200D01*
X512861Y42300D01*
X512761Y42380D01*
X512651Y42440D01*
X512526Y42480D01*
X512401Y42490D01*
X512276Y42480D01*
X512151Y42440D01*
X512041Y42380D01*
X511941Y42300D01*
X511861Y42200D01*
X511801Y42090D01*
X511761Y41965D01*
X511751Y41840D01*
Y39410D01*
X511721Y39380D01*
X511621Y39240D01*
X511601Y39200D01*
X511586Y39165D01*
X511566Y39125D01*
X511551Y39085D01*
X511541Y39045D01*
X511526Y39000D01*
X511521Y38960D01*
X511511Y38920D01*
X511506Y38875D01*
Y38835D01*
X511501Y38790D01*
X511506Y38745D01*
Y38705D01*
X511511Y38660D01*
X511521Y38620D01*
X511526Y38580D01*
X511541Y38535D01*
X511551Y38495D01*
X511566Y38455D01*
X511586Y38415D01*
X511601Y38380D01*
X511621Y38340D01*
X511721Y38200D01*
X511751Y38170D01*
Y36040D01*
X511761Y35915D01*
X511801Y35790D01*
X511861Y35680D01*
X511941Y35580D01*
X512041Y35500D01*
X512151Y35440D01*
X512276Y35400D01*
X512401Y35390D01*
G37*
G36*
G01X540748D02*
X540873Y35400D01*
X540998Y35440D01*
X541108Y35500D01*
X541208Y35580D01*
X541288Y35680D01*
X541348Y35790D01*
X541388Y35915D01*
X541398Y36040D01*
Y38165D01*
X541428Y38195D01*
X541453Y38230D01*
X541483Y38265D01*
X541503Y38300D01*
X541528Y38335D01*
X541568Y38415D01*
X541613Y38535D01*
X541623Y38575D01*
X541633Y38620D01*
X541638Y38660D01*
X541648Y38705D01*
Y38875D01*
X541638Y38920D01*
X541633Y38960D01*
X541623Y39005D01*
X541613Y39045D01*
X541568Y39165D01*
X541528Y39245D01*
X541503Y39280D01*
X541483Y39315D01*
X541453Y39350D01*
X541428Y39385D01*
X541398Y39415D01*
Y41840D01*
X541388Y41965D01*
X541348Y42090D01*
X541288Y42200D01*
X541208Y42300D01*
X541108Y42380D01*
X540998Y42440D01*
X540873Y42480D01*
X540748Y42490D01*
X540623Y42480D01*
X540498Y42440D01*
X540388Y42380D01*
X540288Y42300D01*
X540208Y42200D01*
X540148Y42090D01*
X540108Y41965D01*
X540098Y41840D01*
Y39410D01*
X540068Y39380D01*
X539968Y39240D01*
X539948Y39200D01*
X539933Y39165D01*
X539913Y39125D01*
X539898Y39085D01*
X539888Y39045D01*
X539873Y39000D01*
X539868Y38960D01*
X539858Y38920D01*
X539853Y38875D01*
Y38835D01*
X539848Y38790D01*
X539853Y38745D01*
Y38705D01*
X539858Y38660D01*
X539868Y38620D01*
X539873Y38580D01*
X539888Y38535D01*
X539898Y38495D01*
X539913Y38455D01*
X539933Y38415D01*
X539948Y38380D01*
X539968Y38340D01*
X540068Y38200D01*
X540098Y38170D01*
Y36040D01*
X540108Y35915D01*
X540148Y35790D01*
X540208Y35680D01*
X540288Y35580D01*
X540388Y35500D01*
X540498Y35440D01*
X540623Y35400D01*
X540748Y35390D01*
G37*
G36*
G01X536023D02*
X536148Y35400D01*
X536273Y35440D01*
X536383Y35500D01*
X536483Y35580D01*
X536563Y35680D01*
X536623Y35790D01*
X536663Y35915D01*
X536673Y36040D01*
Y38165D01*
X536703Y38195D01*
X536728Y38230D01*
X536758Y38265D01*
X536778Y38300D01*
X536803Y38335D01*
X536843Y38415D01*
X536888Y38535D01*
X536898Y38575D01*
X536908Y38620D01*
X536913Y38660D01*
X536923Y38705D01*
Y38875D01*
X536913Y38920D01*
X536908Y38960D01*
X536898Y39005D01*
X536888Y39045D01*
X536843Y39165D01*
X536803Y39245D01*
X536778Y39280D01*
X536758Y39315D01*
X536728Y39350D01*
X536703Y39385D01*
X536673Y39415D01*
Y41840D01*
X536663Y41965D01*
X536623Y42090D01*
X536563Y42200D01*
X536483Y42300D01*
X536383Y42380D01*
X536273Y42440D01*
X536148Y42480D01*
X536023Y42490D01*
X535898Y42480D01*
X535773Y42440D01*
X535663Y42380D01*
X535563Y42300D01*
X535483Y42200D01*
X535423Y42090D01*
X535383Y41965D01*
X535373Y41840D01*
Y39410D01*
X535343Y39380D01*
X535243Y39240D01*
X535223Y39200D01*
X535208Y39165D01*
X535188Y39125D01*
X535173Y39085D01*
X535163Y39045D01*
X535148Y39000D01*
X535143Y38960D01*
X535133Y38920D01*
X535128Y38875D01*
Y38835D01*
X535123Y38790D01*
X535128Y38745D01*
Y38705D01*
X535133Y38660D01*
X535143Y38620D01*
X535148Y38580D01*
X535163Y38535D01*
X535173Y38495D01*
X535188Y38455D01*
X535208Y38415D01*
X535223Y38380D01*
X535243Y38340D01*
X535343Y38200D01*
X535373Y38170D01*
Y36040D01*
X535383Y35915D01*
X535423Y35790D01*
X535483Y35680D01*
X535563Y35580D01*
X535663Y35500D01*
X535773Y35440D01*
X535898Y35400D01*
X536023Y35390D01*
G37*
G36*
G01X531299D02*
X531424Y35400D01*
X531549Y35440D01*
X531659Y35500D01*
X531759Y35580D01*
X531839Y35680D01*
X531899Y35790D01*
X531939Y35915D01*
X531949Y36040D01*
Y38165D01*
X531979Y38195D01*
X532004Y38230D01*
X532034Y38265D01*
X532054Y38300D01*
X532079Y38335D01*
X532119Y38415D01*
X532164Y38535D01*
X532174Y38575D01*
X532184Y38620D01*
X532189Y38660D01*
X532199Y38705D01*
Y38875D01*
X532189Y38920D01*
X532184Y38960D01*
X532174Y39005D01*
X532164Y39045D01*
X532119Y39165D01*
X532079Y39245D01*
X532054Y39280D01*
X532034Y39315D01*
X532004Y39350D01*
X531979Y39385D01*
X531949Y39415D01*
Y41840D01*
X531939Y41965D01*
X531899Y42090D01*
X531839Y42200D01*
X531759Y42300D01*
X531659Y42380D01*
X531549Y42440D01*
X531424Y42480D01*
X531299Y42490D01*
X531174Y42480D01*
X531049Y42440D01*
X530939Y42380D01*
X530839Y42300D01*
X530759Y42200D01*
X530699Y42090D01*
X530659Y41965D01*
X530649Y41840D01*
Y39410D01*
X530619Y39380D01*
X530519Y39240D01*
X530499Y39200D01*
X530484Y39165D01*
X530464Y39125D01*
X530449Y39085D01*
X530439Y39045D01*
X530424Y39000D01*
X530419Y38960D01*
X530409Y38920D01*
X530404Y38875D01*
Y38835D01*
X530399Y38790D01*
X530404Y38745D01*
Y38705D01*
X530409Y38660D01*
X530419Y38620D01*
X530424Y38580D01*
X530439Y38535D01*
X530449Y38495D01*
X530464Y38455D01*
X530484Y38415D01*
X530499Y38380D01*
X530519Y38340D01*
X530619Y38200D01*
X530649Y38170D01*
Y36040D01*
X530659Y35915D01*
X530699Y35790D01*
X530759Y35680D01*
X530839Y35580D01*
X530939Y35500D01*
X531049Y35440D01*
X531174Y35400D01*
X531299Y35390D01*
G37*
G36*
G01X526575D02*
X526700Y35400D01*
X526825Y35440D01*
X526935Y35500D01*
X527035Y35580D01*
X527115Y35680D01*
X527175Y35790D01*
X527215Y35915D01*
X527225Y36040D01*
Y38165D01*
X527255Y38195D01*
X527280Y38230D01*
X527310Y38265D01*
X527330Y38300D01*
X527355Y38335D01*
X527395Y38415D01*
X527440Y38535D01*
X527450Y38575D01*
X527460Y38620D01*
X527465Y38660D01*
X527475Y38705D01*
Y38875D01*
X527465Y38920D01*
X527460Y38960D01*
X527450Y39005D01*
X527440Y39045D01*
X527395Y39165D01*
X527355Y39245D01*
X527330Y39280D01*
X527310Y39315D01*
X527280Y39350D01*
X527255Y39385D01*
X527225Y39415D01*
Y41840D01*
X527215Y41965D01*
X527175Y42090D01*
X527115Y42200D01*
X527035Y42300D01*
X526935Y42380D01*
X526825Y42440D01*
X526700Y42480D01*
X526575Y42490D01*
X526450Y42480D01*
X526325Y42440D01*
X526215Y42380D01*
X526115Y42300D01*
X526035Y42200D01*
X525975Y42090D01*
X525935Y41965D01*
X525925Y41840D01*
Y39410D01*
X525895Y39380D01*
X525795Y39240D01*
X525775Y39200D01*
X525760Y39165D01*
X525740Y39125D01*
X525725Y39085D01*
X525715Y39045D01*
X525700Y39000D01*
X525695Y38960D01*
X525685Y38920D01*
X525680Y38875D01*
Y38835D01*
X525675Y38790D01*
X525680Y38745D01*
Y38705D01*
X525685Y38660D01*
X525695Y38620D01*
X525700Y38580D01*
X525715Y38535D01*
X525725Y38495D01*
X525740Y38455D01*
X525760Y38415D01*
X525775Y38380D01*
X525795Y38340D01*
X525895Y38200D01*
X525925Y38170D01*
Y36040D01*
X525935Y35915D01*
X525975Y35790D01*
X526035Y35680D01*
X526115Y35580D01*
X526215Y35500D01*
X526325Y35440D01*
X526450Y35400D01*
X526575Y35390D01*
G37*
G36*
G01X554921D02*
X555046Y35400D01*
X555171Y35440D01*
X555281Y35500D01*
X555381Y35580D01*
X555461Y35680D01*
X555521Y35790D01*
X555561Y35915D01*
X555571Y36040D01*
Y38165D01*
X555601Y38195D01*
X555626Y38230D01*
X555656Y38265D01*
X555676Y38300D01*
X555701Y38335D01*
X555741Y38415D01*
X555786Y38535D01*
X555796Y38575D01*
X555806Y38620D01*
X555811Y38660D01*
X555821Y38705D01*
Y38875D01*
X555811Y38920D01*
X555806Y38960D01*
X555796Y39005D01*
X555786Y39045D01*
X555741Y39165D01*
X555701Y39245D01*
X555676Y39280D01*
X555656Y39315D01*
X555626Y39350D01*
X555601Y39385D01*
X555571Y39415D01*
Y41840D01*
X555561Y41965D01*
X555521Y42090D01*
X555461Y42200D01*
X555381Y42300D01*
X555281Y42380D01*
X555171Y42440D01*
X555046Y42480D01*
X554921Y42490D01*
X554796Y42480D01*
X554671Y42440D01*
X554561Y42380D01*
X554461Y42300D01*
X554381Y42200D01*
X554321Y42090D01*
X554281Y41965D01*
X554271Y41840D01*
Y39410D01*
X554241Y39380D01*
X554141Y39240D01*
X554121Y39200D01*
X554106Y39165D01*
X554086Y39125D01*
X554071Y39085D01*
X554061Y39045D01*
X554046Y39000D01*
X554041Y38960D01*
X554031Y38920D01*
X554026Y38875D01*
Y38835D01*
X554021Y38790D01*
X554026Y38745D01*
Y38705D01*
X554031Y38660D01*
X554041Y38620D01*
X554046Y38580D01*
X554061Y38535D01*
X554071Y38495D01*
X554086Y38455D01*
X554106Y38415D01*
X554121Y38380D01*
X554141Y38340D01*
X554241Y38200D01*
X554271Y38170D01*
Y36040D01*
X554281Y35915D01*
X554321Y35790D01*
X554381Y35680D01*
X554461Y35580D01*
X554561Y35500D01*
X554671Y35440D01*
X554796Y35400D01*
X554921Y35390D01*
G37*
G36*
G01X550197D02*
X550322Y35400D01*
X550447Y35440D01*
X550557Y35500D01*
X550657Y35580D01*
X550737Y35680D01*
X550797Y35790D01*
X550837Y35915D01*
X550847Y36040D01*
Y38165D01*
X550877Y38195D01*
X550902Y38230D01*
X550932Y38265D01*
X550952Y38300D01*
X550977Y38335D01*
X551017Y38415D01*
X551062Y38535D01*
X551072Y38575D01*
X551082Y38620D01*
X551087Y38660D01*
X551097Y38705D01*
Y38875D01*
X551087Y38920D01*
X551082Y38960D01*
X551072Y39005D01*
X551062Y39045D01*
X551017Y39165D01*
X550977Y39245D01*
X550952Y39280D01*
X550932Y39315D01*
X550902Y39350D01*
X550877Y39385D01*
X550847Y39415D01*
Y41840D01*
X550837Y41965D01*
X550797Y42090D01*
X550737Y42200D01*
X550657Y42300D01*
X550557Y42380D01*
X550447Y42440D01*
X550322Y42480D01*
X550197Y42490D01*
X550072Y42480D01*
X549947Y42440D01*
X549837Y42380D01*
X549737Y42300D01*
X549657Y42200D01*
X549597Y42090D01*
X549557Y41965D01*
X549547Y41840D01*
Y39410D01*
X549517Y39380D01*
X549417Y39240D01*
X549397Y39200D01*
X549382Y39165D01*
X549362Y39125D01*
X549347Y39085D01*
X549337Y39045D01*
X549322Y39000D01*
X549317Y38960D01*
X549307Y38920D01*
X549302Y38875D01*
Y38835D01*
X549297Y38790D01*
X549302Y38745D01*
Y38705D01*
X549307Y38660D01*
X549317Y38620D01*
X549322Y38580D01*
X549337Y38535D01*
X549347Y38495D01*
X549362Y38455D01*
X549382Y38415D01*
X549397Y38380D01*
X549417Y38340D01*
X549517Y38200D01*
X549547Y38170D01*
Y36040D01*
X549557Y35915D01*
X549597Y35790D01*
X549657Y35680D01*
X549737Y35580D01*
X549837Y35500D01*
X549947Y35440D01*
X550072Y35400D01*
X550197Y35390D01*
G37*
G36*
G01X545472D02*
X545597Y35400D01*
X545722Y35440D01*
X545832Y35500D01*
X545932Y35580D01*
X546012Y35680D01*
X546072Y35790D01*
X546112Y35915D01*
X546122Y36040D01*
Y38165D01*
X546152Y38195D01*
X546177Y38230D01*
X546207Y38265D01*
X546227Y38300D01*
X546252Y38335D01*
X546292Y38415D01*
X546337Y38535D01*
X546347Y38575D01*
X546357Y38620D01*
X546362Y38660D01*
X546372Y38705D01*
Y38875D01*
X546362Y38920D01*
X546357Y38960D01*
X546347Y39005D01*
X546337Y39045D01*
X546292Y39165D01*
X546252Y39245D01*
X546227Y39280D01*
X546207Y39315D01*
X546177Y39350D01*
X546152Y39385D01*
X546122Y39415D01*
Y41840D01*
X546112Y41965D01*
X546072Y42090D01*
X546012Y42200D01*
X545932Y42300D01*
X545832Y42380D01*
X545722Y42440D01*
X545597Y42480D01*
X545472Y42490D01*
X545347Y42480D01*
X545222Y42440D01*
X545112Y42380D01*
X545012Y42300D01*
X544932Y42200D01*
X544872Y42090D01*
X544832Y41965D01*
X544822Y41840D01*
Y39410D01*
X544792Y39380D01*
X544692Y39240D01*
X544672Y39200D01*
X544657Y39165D01*
X544637Y39125D01*
X544622Y39085D01*
X544612Y39045D01*
X544597Y39000D01*
X544592Y38960D01*
X544582Y38920D01*
X544577Y38875D01*
Y38835D01*
X544572Y38790D01*
X544577Y38745D01*
Y38705D01*
X544582Y38660D01*
X544592Y38620D01*
X544597Y38580D01*
X544612Y38535D01*
X544622Y38495D01*
X544637Y38455D01*
X544657Y38415D01*
X544672Y38380D01*
X544692Y38340D01*
X544792Y38200D01*
X544822Y38170D01*
Y36040D01*
X544832Y35915D01*
X544872Y35790D01*
X544932Y35680D01*
X545012Y35580D01*
X545112Y35500D01*
X545222Y35440D01*
X545347Y35400D01*
X545472Y35390D01*
G37*
G36*
G01X569094D02*
X569219Y35400D01*
X569344Y35440D01*
X569454Y35500D01*
X569554Y35580D01*
X569634Y35680D01*
X569694Y35790D01*
X569734Y35915D01*
X569744Y36040D01*
Y38165D01*
X569774Y38195D01*
X569799Y38230D01*
X569829Y38265D01*
X569849Y38300D01*
X569874Y38335D01*
X569914Y38415D01*
X569959Y38535D01*
X569969Y38575D01*
X569979Y38620D01*
X569984Y38660D01*
X569994Y38705D01*
Y38875D01*
X569984Y38920D01*
X569979Y38960D01*
X569969Y39005D01*
X569959Y39045D01*
X569914Y39165D01*
X569874Y39245D01*
X569849Y39280D01*
X569829Y39315D01*
X569799Y39350D01*
X569774Y39385D01*
X569744Y39415D01*
Y41840D01*
X569734Y41965D01*
X569694Y42090D01*
X569634Y42200D01*
X569554Y42300D01*
X569454Y42380D01*
X569344Y42440D01*
X569219Y42480D01*
X569094Y42490D01*
X568969Y42480D01*
X568844Y42440D01*
X568734Y42380D01*
X568634Y42300D01*
X568554Y42200D01*
X568494Y42090D01*
X568454Y41965D01*
X568444Y41840D01*
Y39410D01*
X568414Y39380D01*
X568314Y39240D01*
X568294Y39200D01*
X568279Y39165D01*
X568259Y39125D01*
X568244Y39085D01*
X568234Y39045D01*
X568219Y39000D01*
X568214Y38960D01*
X568204Y38920D01*
X568199Y38875D01*
Y38835D01*
X568194Y38790D01*
X568199Y38745D01*
Y38705D01*
X568204Y38660D01*
X568214Y38620D01*
X568219Y38580D01*
X568234Y38535D01*
X568244Y38495D01*
X568259Y38455D01*
X568279Y38415D01*
X568294Y38380D01*
X568314Y38340D01*
X568414Y38200D01*
X568444Y38170D01*
Y36040D01*
X568454Y35915D01*
X568494Y35790D01*
X568554Y35680D01*
X568634Y35580D01*
X568734Y35500D01*
X568844Y35440D01*
X568969Y35400D01*
X569094Y35390D01*
G37*
G36*
G01X564370D02*
X564495Y35400D01*
X564620Y35440D01*
X564730Y35500D01*
X564830Y35580D01*
X564910Y35680D01*
X564970Y35790D01*
X565010Y35915D01*
X565020Y36040D01*
Y38165D01*
X565050Y38195D01*
X565075Y38230D01*
X565105Y38265D01*
X565125Y38300D01*
X565150Y38335D01*
X565190Y38415D01*
X565235Y38535D01*
X565245Y38575D01*
X565255Y38620D01*
X565260Y38660D01*
X565270Y38705D01*
Y38875D01*
X565260Y38920D01*
X565255Y38960D01*
X565245Y39005D01*
X565235Y39045D01*
X565190Y39165D01*
X565150Y39245D01*
X565125Y39280D01*
X565105Y39315D01*
X565075Y39350D01*
X565050Y39385D01*
X565020Y39415D01*
Y41840D01*
X565010Y41965D01*
X564970Y42090D01*
X564910Y42200D01*
X564830Y42300D01*
X564730Y42380D01*
X564620Y42440D01*
X564495Y42480D01*
X564370Y42490D01*
X564245Y42480D01*
X564120Y42440D01*
X564010Y42380D01*
X563910Y42300D01*
X563830Y42200D01*
X563770Y42090D01*
X563730Y41965D01*
X563720Y41840D01*
Y39410D01*
X563690Y39380D01*
X563590Y39240D01*
X563570Y39200D01*
X563555Y39165D01*
X563535Y39125D01*
X563520Y39085D01*
X563510Y39045D01*
X563495Y39000D01*
X563490Y38960D01*
X563480Y38920D01*
X563475Y38875D01*
Y38835D01*
X563470Y38790D01*
X563475Y38745D01*
Y38705D01*
X563480Y38660D01*
X563490Y38620D01*
X563495Y38580D01*
X563510Y38535D01*
X563520Y38495D01*
X563535Y38455D01*
X563555Y38415D01*
X563570Y38380D01*
X563590Y38340D01*
X563690Y38200D01*
X563720Y38170D01*
Y36040D01*
X563730Y35915D01*
X563770Y35790D01*
X563830Y35680D01*
X563910Y35580D01*
X564010Y35500D01*
X564120Y35440D01*
X564245Y35400D01*
X564370Y35390D01*
G37*
G36*
G01X559645D02*
X559770Y35400D01*
X559895Y35440D01*
X560005Y35500D01*
X560105Y35580D01*
X560185Y35680D01*
X560245Y35790D01*
X560285Y35915D01*
X560295Y36040D01*
Y38165D01*
X560325Y38195D01*
X560350Y38230D01*
X560380Y38265D01*
X560400Y38300D01*
X560425Y38335D01*
X560465Y38415D01*
X560510Y38535D01*
X560520Y38575D01*
X560530Y38620D01*
X560535Y38660D01*
X560545Y38705D01*
Y38875D01*
X560535Y38920D01*
X560530Y38960D01*
X560520Y39005D01*
X560510Y39045D01*
X560465Y39165D01*
X560425Y39245D01*
X560400Y39280D01*
X560380Y39315D01*
X560350Y39350D01*
X560325Y39385D01*
X560295Y39415D01*
Y41840D01*
X560285Y41965D01*
X560245Y42090D01*
X560185Y42200D01*
X560105Y42300D01*
X560005Y42380D01*
X559895Y42440D01*
X559770Y42480D01*
X559645Y42490D01*
X559520Y42480D01*
X559395Y42440D01*
X559285Y42380D01*
X559185Y42300D01*
X559105Y42200D01*
X559045Y42090D01*
X559005Y41965D01*
X558995Y41840D01*
Y39410D01*
X558965Y39380D01*
X558865Y39240D01*
X558845Y39200D01*
X558830Y39165D01*
X558810Y39125D01*
X558795Y39085D01*
X558785Y39045D01*
X558770Y39000D01*
X558765Y38960D01*
X558755Y38920D01*
X558750Y38875D01*
Y38835D01*
X558745Y38790D01*
X558750Y38745D01*
Y38705D01*
X558755Y38660D01*
X558765Y38620D01*
X558770Y38580D01*
X558785Y38535D01*
X558795Y38495D01*
X558810Y38455D01*
X558830Y38415D01*
X558845Y38380D01*
X558865Y38340D01*
X558965Y38200D01*
X558995Y38170D01*
Y36040D01*
X559005Y35915D01*
X559045Y35790D01*
X559105Y35680D01*
X559185Y35580D01*
X559285Y35500D01*
X559395Y35440D01*
X559520Y35400D01*
X559645Y35390D01*
G37*
G36*
G01X587992D02*
X588117Y35400D01*
X588242Y35440D01*
X588352Y35500D01*
X588452Y35580D01*
X588532Y35680D01*
X588592Y35790D01*
X588632Y35915D01*
X588642Y36040D01*
Y38165D01*
X588672Y38195D01*
X588697Y38230D01*
X588727Y38265D01*
X588747Y38300D01*
X588772Y38335D01*
X588812Y38415D01*
X588857Y38535D01*
X588867Y38575D01*
X588877Y38620D01*
X588882Y38660D01*
X588892Y38705D01*
Y38875D01*
X588882Y38920D01*
X588877Y38960D01*
X588867Y39005D01*
X588857Y39045D01*
X588812Y39165D01*
X588772Y39245D01*
X588747Y39280D01*
X588727Y39315D01*
X588697Y39350D01*
X588672Y39385D01*
X588642Y39415D01*
Y41840D01*
X588632Y41965D01*
X588592Y42090D01*
X588532Y42200D01*
X588452Y42300D01*
X588352Y42380D01*
X588242Y42440D01*
X588117Y42480D01*
X587992Y42490D01*
X587867Y42480D01*
X587742Y42440D01*
X587632Y42380D01*
X587532Y42300D01*
X587452Y42200D01*
X587392Y42090D01*
X587352Y41965D01*
X587342Y41840D01*
Y39410D01*
X587312Y39380D01*
X587212Y39240D01*
X587192Y39200D01*
X587177Y39165D01*
X587157Y39125D01*
X587142Y39085D01*
X587132Y39045D01*
X587117Y39000D01*
X587112Y38960D01*
X587102Y38920D01*
X587097Y38875D01*
Y38835D01*
X587092Y38790D01*
X587097Y38745D01*
Y38705D01*
X587102Y38660D01*
X587112Y38620D01*
X587117Y38580D01*
X587132Y38535D01*
X587142Y38495D01*
X587157Y38455D01*
X587177Y38415D01*
X587192Y38380D01*
X587212Y38340D01*
X587312Y38200D01*
X587342Y38170D01*
Y36040D01*
X587352Y35915D01*
X587392Y35790D01*
X587452Y35680D01*
X587532Y35580D01*
X587632Y35500D01*
X587742Y35440D01*
X587867Y35400D01*
X587992Y35390D01*
G37*
G36*
G01X583267D02*
X583392Y35400D01*
X583517Y35440D01*
X583627Y35500D01*
X583727Y35580D01*
X583807Y35680D01*
X583867Y35790D01*
X583907Y35915D01*
X583917Y36040D01*
Y38165D01*
X583947Y38195D01*
X583972Y38230D01*
X584002Y38265D01*
X584022Y38300D01*
X584047Y38335D01*
X584087Y38415D01*
X584132Y38535D01*
X584142Y38575D01*
X584152Y38620D01*
X584157Y38660D01*
X584167Y38705D01*
Y38875D01*
X584157Y38920D01*
X584152Y38960D01*
X584142Y39005D01*
X584132Y39045D01*
X584087Y39165D01*
X584047Y39245D01*
X584022Y39280D01*
X584002Y39315D01*
X583972Y39350D01*
X583947Y39385D01*
X583917Y39415D01*
Y41840D01*
X583907Y41965D01*
X583867Y42090D01*
X583807Y42200D01*
X583727Y42300D01*
X583627Y42380D01*
X583517Y42440D01*
X583392Y42480D01*
X583267Y42490D01*
X583142Y42480D01*
X583017Y42440D01*
X582907Y42380D01*
X582807Y42300D01*
X582727Y42200D01*
X582667Y42090D01*
X582627Y41965D01*
X582617Y41840D01*
Y39410D01*
X582587Y39380D01*
X582487Y39240D01*
X582467Y39200D01*
X582452Y39165D01*
X582432Y39125D01*
X582417Y39085D01*
X582407Y39045D01*
X582392Y39000D01*
X582387Y38960D01*
X582377Y38920D01*
X582372Y38875D01*
Y38835D01*
X582367Y38790D01*
X582372Y38745D01*
Y38705D01*
X582377Y38660D01*
X582387Y38620D01*
X582392Y38580D01*
X582407Y38535D01*
X582417Y38495D01*
X582432Y38455D01*
X582452Y38415D01*
X582467Y38380D01*
X582487Y38340D01*
X582587Y38200D01*
X582617Y38170D01*
Y36040D01*
X582627Y35915D01*
X582667Y35790D01*
X582727Y35680D01*
X582807Y35580D01*
X582907Y35500D01*
X583017Y35440D01*
X583142Y35400D01*
X583267Y35390D01*
G37*
G36*
G01X578543D02*
X578668Y35400D01*
X578793Y35440D01*
X578903Y35500D01*
X579003Y35580D01*
X579083Y35680D01*
X579143Y35790D01*
X579183Y35915D01*
X579193Y36040D01*
Y38165D01*
X579223Y38195D01*
X579248Y38230D01*
X579278Y38265D01*
X579298Y38300D01*
X579323Y38335D01*
X579363Y38415D01*
X579408Y38535D01*
X579418Y38575D01*
X579428Y38620D01*
X579433Y38660D01*
X579443Y38705D01*
Y38875D01*
X579433Y38920D01*
X579428Y38960D01*
X579418Y39005D01*
X579408Y39045D01*
X579363Y39165D01*
X579323Y39245D01*
X579298Y39280D01*
X579278Y39315D01*
X579248Y39350D01*
X579223Y39385D01*
X579193Y39415D01*
Y41840D01*
X579183Y41965D01*
X579143Y42090D01*
X579083Y42200D01*
X579003Y42300D01*
X578903Y42380D01*
X578793Y42440D01*
X578668Y42480D01*
X578543Y42490D01*
X578418Y42480D01*
X578293Y42440D01*
X578183Y42380D01*
X578083Y42300D01*
X578003Y42200D01*
X577943Y42090D01*
X577903Y41965D01*
X577893Y41840D01*
Y39410D01*
X577863Y39380D01*
X577763Y39240D01*
X577743Y39200D01*
X577728Y39165D01*
X577708Y39125D01*
X577693Y39085D01*
X577683Y39045D01*
X577668Y39000D01*
X577663Y38960D01*
X577653Y38920D01*
X577648Y38875D01*
Y38835D01*
X577643Y38790D01*
X577648Y38745D01*
Y38705D01*
X577653Y38660D01*
X577663Y38620D01*
X577668Y38580D01*
X577683Y38535D01*
X577693Y38495D01*
X577708Y38455D01*
X577728Y38415D01*
X577743Y38380D01*
X577763Y38340D01*
X577863Y38200D01*
X577893Y38170D01*
Y36040D01*
X577903Y35915D01*
X577943Y35790D01*
X578003Y35680D01*
X578083Y35580D01*
X578183Y35500D01*
X578293Y35440D01*
X578418Y35400D01*
X578543Y35390D01*
G37*
G36*
G01X573819D02*
X573944Y35400D01*
X574069Y35440D01*
X574179Y35500D01*
X574279Y35580D01*
X574359Y35680D01*
X574419Y35790D01*
X574459Y35915D01*
X574469Y36040D01*
Y38165D01*
X574499Y38195D01*
X574524Y38230D01*
X574554Y38265D01*
X574574Y38300D01*
X574599Y38335D01*
X574639Y38415D01*
X574684Y38535D01*
X574694Y38575D01*
X574704Y38620D01*
X574709Y38660D01*
X574719Y38705D01*
Y38875D01*
X574709Y38920D01*
X574704Y38960D01*
X574694Y39005D01*
X574684Y39045D01*
X574639Y39165D01*
X574599Y39245D01*
X574574Y39280D01*
X574554Y39315D01*
X574524Y39350D01*
X574499Y39385D01*
X574469Y39415D01*
Y41840D01*
X574459Y41965D01*
X574419Y42090D01*
X574359Y42200D01*
X574279Y42300D01*
X574179Y42380D01*
X574069Y42440D01*
X573944Y42480D01*
X573819Y42490D01*
X573694Y42480D01*
X573569Y42440D01*
X573459Y42380D01*
X573359Y42300D01*
X573279Y42200D01*
X573219Y42090D01*
X573179Y41965D01*
X573169Y41840D01*
Y39410D01*
X573139Y39380D01*
X573039Y39240D01*
X573019Y39200D01*
X573004Y39165D01*
X572984Y39125D01*
X572969Y39085D01*
X572959Y39045D01*
X572944Y39000D01*
X572939Y38960D01*
X572929Y38920D01*
X572924Y38875D01*
Y38835D01*
X572919Y38790D01*
X572924Y38745D01*
Y38705D01*
X572929Y38660D01*
X572939Y38620D01*
X572944Y38580D01*
X572959Y38535D01*
X572969Y38495D01*
X572984Y38455D01*
X573004Y38415D01*
X573019Y38380D01*
X573039Y38340D01*
X573139Y38200D01*
X573169Y38170D01*
Y36040D01*
X573179Y35915D01*
X573219Y35790D01*
X573279Y35680D01*
X573359Y35580D01*
X573459Y35500D01*
X573569Y35440D01*
X573694Y35400D01*
X573819Y35390D01*
G37*
G36*
G01X602165D02*
X602290Y35400D01*
X602415Y35440D01*
X602525Y35500D01*
X602625Y35580D01*
X602705Y35680D01*
X602765Y35790D01*
X602805Y35915D01*
X602815Y36040D01*
Y38165D01*
X602845Y38195D01*
X602870Y38230D01*
X602900Y38265D01*
X602920Y38300D01*
X602945Y38335D01*
X602985Y38415D01*
X603030Y38535D01*
X603040Y38575D01*
X603050Y38620D01*
X603055Y38660D01*
X603065Y38705D01*
Y38875D01*
X603055Y38920D01*
X603050Y38960D01*
X603040Y39005D01*
X603030Y39045D01*
X602985Y39165D01*
X602945Y39245D01*
X602920Y39280D01*
X602900Y39315D01*
X602870Y39350D01*
X602845Y39385D01*
X602815Y39415D01*
Y41840D01*
X602805Y41965D01*
X602765Y42090D01*
X602705Y42200D01*
X602625Y42300D01*
X602525Y42380D01*
X602415Y42440D01*
X602290Y42480D01*
X602165Y42490D01*
X602040Y42480D01*
X601915Y42440D01*
X601805Y42380D01*
X601705Y42300D01*
X601625Y42200D01*
X601565Y42090D01*
X601525Y41965D01*
X601515Y41840D01*
Y39410D01*
X601485Y39380D01*
X601385Y39240D01*
X601365Y39200D01*
X601350Y39165D01*
X601330Y39125D01*
X601315Y39085D01*
X601305Y39045D01*
X601290Y39000D01*
X601285Y38960D01*
X601275Y38920D01*
X601270Y38875D01*
Y38835D01*
X601265Y38790D01*
X601270Y38745D01*
Y38705D01*
X601275Y38660D01*
X601285Y38620D01*
X601290Y38580D01*
X601305Y38535D01*
X601315Y38495D01*
X601330Y38455D01*
X601350Y38415D01*
X601365Y38380D01*
X601385Y38340D01*
X601485Y38200D01*
X601515Y38170D01*
Y36040D01*
X601525Y35915D01*
X601565Y35790D01*
X601625Y35680D01*
X601705Y35580D01*
X601805Y35500D01*
X601915Y35440D01*
X602040Y35400D01*
X602165Y35390D01*
G37*
G36*
G01X616338D02*
X616463Y35400D01*
X616588Y35440D01*
X616698Y35500D01*
X616798Y35580D01*
X616878Y35680D01*
X616938Y35790D01*
X616978Y35915D01*
X616988Y36040D01*
Y38165D01*
X617018Y38195D01*
X617043Y38230D01*
X617073Y38265D01*
X617093Y38300D01*
X617118Y38335D01*
X617158Y38415D01*
X617203Y38535D01*
X617213Y38575D01*
X617223Y38620D01*
X617228Y38660D01*
X617238Y38705D01*
Y38875D01*
X617228Y38920D01*
X617223Y38960D01*
X617213Y39005D01*
X617203Y39045D01*
X617158Y39165D01*
X617118Y39245D01*
X617093Y39280D01*
X617073Y39315D01*
X617043Y39350D01*
X617018Y39385D01*
X616988Y39415D01*
Y41840D01*
X616978Y41965D01*
X616938Y42090D01*
X616878Y42200D01*
X616798Y42300D01*
X616698Y42380D01*
X616588Y42440D01*
X616463Y42480D01*
X616338Y42490D01*
X616213Y42480D01*
X616088Y42440D01*
X615978Y42380D01*
X615878Y42300D01*
X615798Y42200D01*
X615738Y42090D01*
X615698Y41965D01*
X615688Y41840D01*
Y39410D01*
X615658Y39380D01*
X615558Y39240D01*
X615538Y39200D01*
X615523Y39165D01*
X615503Y39125D01*
X615488Y39085D01*
X615478Y39045D01*
X615463Y39000D01*
X615458Y38960D01*
X615448Y38920D01*
X615443Y38875D01*
Y38835D01*
X615438Y38790D01*
X615443Y38745D01*
Y38705D01*
X615448Y38660D01*
X615458Y38620D01*
X615463Y38580D01*
X615478Y38535D01*
X615488Y38495D01*
X615503Y38455D01*
X615523Y38415D01*
X615538Y38380D01*
X615558Y38340D01*
X615658Y38200D01*
X615688Y38170D01*
Y36040D01*
X615698Y35915D01*
X615738Y35790D01*
X615798Y35680D01*
X615878Y35580D01*
X615978Y35500D01*
X616088Y35440D01*
X616213Y35400D01*
X616338Y35390D01*
G37*
G36*
G01X611614D02*
X611739Y35400D01*
X611864Y35440D01*
X611974Y35500D01*
X612074Y35580D01*
X612154Y35680D01*
X612214Y35790D01*
X612254Y35915D01*
X612264Y36040D01*
Y38165D01*
X612294Y38195D01*
X612319Y38230D01*
X612349Y38265D01*
X612369Y38300D01*
X612394Y38335D01*
X612434Y38415D01*
X612479Y38535D01*
X612489Y38575D01*
X612499Y38620D01*
X612504Y38660D01*
X612514Y38705D01*
Y38875D01*
X612504Y38920D01*
X612499Y38960D01*
X612489Y39005D01*
X612479Y39045D01*
X612434Y39165D01*
X612394Y39245D01*
X612369Y39280D01*
X612349Y39315D01*
X612319Y39350D01*
X612294Y39385D01*
X612264Y39415D01*
Y41840D01*
X612254Y41965D01*
X612214Y42090D01*
X612154Y42200D01*
X612074Y42300D01*
X611974Y42380D01*
X611864Y42440D01*
X611739Y42480D01*
X611614Y42490D01*
X611489Y42480D01*
X611364Y42440D01*
X611254Y42380D01*
X611154Y42300D01*
X611074Y42200D01*
X611014Y42090D01*
X610974Y41965D01*
X610964Y41840D01*
Y39410D01*
X610934Y39380D01*
X610834Y39240D01*
X610814Y39200D01*
X610799Y39165D01*
X610779Y39125D01*
X610764Y39085D01*
X610754Y39045D01*
X610739Y39000D01*
X610734Y38960D01*
X610724Y38920D01*
X610719Y38875D01*
Y38835D01*
X610714Y38790D01*
X610719Y38745D01*
Y38705D01*
X610724Y38660D01*
X610734Y38620D01*
X610739Y38580D01*
X610754Y38535D01*
X610764Y38495D01*
X610779Y38455D01*
X610799Y38415D01*
X610814Y38380D01*
X610834Y38340D01*
X610934Y38200D01*
X610964Y38170D01*
Y36040D01*
X610974Y35915D01*
X611014Y35790D01*
X611074Y35680D01*
X611154Y35580D01*
X611254Y35500D01*
X611364Y35440D01*
X611489Y35400D01*
X611614Y35390D01*
G37*
G36*
G01X606890D02*
X607015Y35400D01*
X607140Y35440D01*
X607250Y35500D01*
X607350Y35580D01*
X607430Y35680D01*
X607490Y35790D01*
X607530Y35915D01*
X607540Y36040D01*
Y38165D01*
X607570Y38195D01*
X607595Y38230D01*
X607625Y38265D01*
X607645Y38300D01*
X607670Y38335D01*
X607710Y38415D01*
X607755Y38535D01*
X607765Y38575D01*
X607775Y38620D01*
X607780Y38660D01*
X607790Y38705D01*
Y38875D01*
X607780Y38920D01*
X607775Y38960D01*
X607765Y39005D01*
X607755Y39045D01*
X607710Y39165D01*
X607670Y39245D01*
X607645Y39280D01*
X607625Y39315D01*
X607595Y39350D01*
X607570Y39385D01*
X607540Y39415D01*
Y41840D01*
X607530Y41965D01*
X607490Y42090D01*
X607430Y42200D01*
X607350Y42300D01*
X607250Y42380D01*
X607140Y42440D01*
X607015Y42480D01*
X606890Y42490D01*
X606765Y42480D01*
X606640Y42440D01*
X606530Y42380D01*
X606430Y42300D01*
X606350Y42200D01*
X606290Y42090D01*
X606250Y41965D01*
X606240Y41840D01*
Y39410D01*
X606210Y39380D01*
X606110Y39240D01*
X606090Y39200D01*
X606075Y39165D01*
X606055Y39125D01*
X606040Y39085D01*
X606030Y39045D01*
X606015Y39000D01*
X606010Y38960D01*
X606000Y38920D01*
X605995Y38875D01*
Y38835D01*
X605990Y38790D01*
X605995Y38745D01*
Y38705D01*
X606000Y38660D01*
X606010Y38620D01*
X606015Y38580D01*
X606030Y38535D01*
X606040Y38495D01*
X606055Y38455D01*
X606075Y38415D01*
X606090Y38380D01*
X606110Y38340D01*
X606210Y38200D01*
X606240Y38170D01*
Y36040D01*
X606250Y35915D01*
X606290Y35790D01*
X606350Y35680D01*
X606430Y35580D01*
X606530Y35500D01*
X606640Y35440D01*
X606765Y35400D01*
X606890Y35390D01*
G37*
G36*
G01X630512D02*
X630637Y35400D01*
X630762Y35440D01*
X630872Y35500D01*
X630972Y35580D01*
X631052Y35680D01*
X631112Y35790D01*
X631152Y35915D01*
X631162Y36040D01*
Y38165D01*
X631192Y38195D01*
X631217Y38230D01*
X631247Y38265D01*
X631267Y38300D01*
X631292Y38335D01*
X631332Y38415D01*
X631377Y38535D01*
X631387Y38575D01*
X631397Y38620D01*
X631402Y38660D01*
X631412Y38705D01*
Y38875D01*
X631402Y38920D01*
X631397Y38960D01*
X631387Y39005D01*
X631377Y39045D01*
X631332Y39165D01*
X631292Y39245D01*
X631267Y39280D01*
X631247Y39315D01*
X631217Y39350D01*
X631192Y39385D01*
X631162Y39415D01*
Y41840D01*
X631152Y41965D01*
X631112Y42090D01*
X631052Y42200D01*
X630972Y42300D01*
X630872Y42380D01*
X630762Y42440D01*
X630637Y42480D01*
X630512Y42490D01*
X630387Y42480D01*
X630262Y42440D01*
X630152Y42380D01*
X630052Y42300D01*
X629972Y42200D01*
X629912Y42090D01*
X629872Y41965D01*
X629862Y41840D01*
Y39410D01*
X629832Y39380D01*
X629732Y39240D01*
X629712Y39200D01*
X629697Y39165D01*
X629677Y39125D01*
X629662Y39085D01*
X629652Y39045D01*
X629637Y39000D01*
X629632Y38960D01*
X629622Y38920D01*
X629617Y38875D01*
Y38835D01*
X629612Y38790D01*
X629617Y38745D01*
Y38705D01*
X629622Y38660D01*
X629632Y38620D01*
X629637Y38580D01*
X629652Y38535D01*
X629662Y38495D01*
X629677Y38455D01*
X629697Y38415D01*
X629712Y38380D01*
X629732Y38340D01*
X629832Y38200D01*
X629862Y38170D01*
Y36040D01*
X629872Y35915D01*
X629912Y35790D01*
X629972Y35680D01*
X630052Y35580D01*
X630152Y35500D01*
X630262Y35440D01*
X630387Y35400D01*
X630512Y35390D01*
G37*
G36*
G01X625787D02*
X625912Y35400D01*
X626037Y35440D01*
X626147Y35500D01*
X626247Y35580D01*
X626327Y35680D01*
X626387Y35790D01*
X626427Y35915D01*
X626437Y36040D01*
Y38165D01*
X626467Y38195D01*
X626492Y38230D01*
X626522Y38265D01*
X626542Y38300D01*
X626567Y38335D01*
X626607Y38415D01*
X626652Y38535D01*
X626662Y38575D01*
X626672Y38620D01*
X626677Y38660D01*
X626687Y38705D01*
Y38875D01*
X626677Y38920D01*
X626672Y38960D01*
X626662Y39005D01*
X626652Y39045D01*
X626607Y39165D01*
X626567Y39245D01*
X626542Y39280D01*
X626522Y39315D01*
X626492Y39350D01*
X626467Y39385D01*
X626437Y39415D01*
Y41840D01*
X626427Y41965D01*
X626387Y42090D01*
X626327Y42200D01*
X626247Y42300D01*
X626147Y42380D01*
X626037Y42440D01*
X625912Y42480D01*
X625787Y42490D01*
X625662Y42480D01*
X625537Y42440D01*
X625427Y42380D01*
X625327Y42300D01*
X625247Y42200D01*
X625187Y42090D01*
X625147Y41965D01*
X625137Y41840D01*
Y39410D01*
X625107Y39380D01*
X625007Y39240D01*
X624987Y39200D01*
X624972Y39165D01*
X624952Y39125D01*
X624937Y39085D01*
X624927Y39045D01*
X624912Y39000D01*
X624907Y38960D01*
X624897Y38920D01*
X624892Y38875D01*
Y38835D01*
X624887Y38790D01*
X624892Y38745D01*
Y38705D01*
X624897Y38660D01*
X624907Y38620D01*
X624912Y38580D01*
X624927Y38535D01*
X624937Y38495D01*
X624952Y38455D01*
X624972Y38415D01*
X624987Y38380D01*
X625007Y38340D01*
X625107Y38200D01*
X625137Y38170D01*
Y36040D01*
X625147Y35915D01*
X625187Y35790D01*
X625247Y35680D01*
X625327Y35580D01*
X625427Y35500D01*
X625537Y35440D01*
X625662Y35400D01*
X625787Y35390D01*
G37*
G36*
G01X621063D02*
X621188Y35400D01*
X621313Y35440D01*
X621423Y35500D01*
X621523Y35580D01*
X621603Y35680D01*
X621663Y35790D01*
X621703Y35915D01*
X621713Y36040D01*
Y38165D01*
X621743Y38195D01*
X621768Y38230D01*
X621798Y38265D01*
X621818Y38300D01*
X621843Y38335D01*
X621883Y38415D01*
X621928Y38535D01*
X621938Y38575D01*
X621948Y38620D01*
X621953Y38660D01*
X621963Y38705D01*
Y38875D01*
X621953Y38920D01*
X621948Y38960D01*
X621938Y39005D01*
X621928Y39045D01*
X621883Y39165D01*
X621843Y39245D01*
X621818Y39280D01*
X621798Y39315D01*
X621768Y39350D01*
X621743Y39385D01*
X621713Y39415D01*
Y41840D01*
X621703Y41965D01*
X621663Y42090D01*
X621603Y42200D01*
X621523Y42300D01*
X621423Y42380D01*
X621313Y42440D01*
X621188Y42480D01*
X621063Y42490D01*
X620938Y42480D01*
X620813Y42440D01*
X620703Y42380D01*
X620603Y42300D01*
X620523Y42200D01*
X620463Y42090D01*
X620423Y41965D01*
X620413Y41840D01*
Y39410D01*
X620383Y39380D01*
X620283Y39240D01*
X620263Y39200D01*
X620248Y39165D01*
X620228Y39125D01*
X620213Y39085D01*
X620203Y39045D01*
X620188Y39000D01*
X620183Y38960D01*
X620173Y38920D01*
X620168Y38875D01*
Y38835D01*
X620163Y38790D01*
X620168Y38745D01*
Y38705D01*
X620173Y38660D01*
X620183Y38620D01*
X620188Y38580D01*
X620203Y38535D01*
X620213Y38495D01*
X620228Y38455D01*
X620248Y38415D01*
X620263Y38380D01*
X620283Y38340D01*
X620383Y38200D01*
X620413Y38170D01*
Y36040D01*
X620423Y35915D01*
X620463Y35790D01*
X620523Y35680D01*
X620603Y35580D01*
X620703Y35500D01*
X620813Y35440D01*
X620938Y35400D01*
X621063Y35390D01*
G37*
G36*
G01X649409D02*
X649534Y35400D01*
X649659Y35440D01*
X649769Y35500D01*
X649869Y35580D01*
X649949Y35680D01*
X650009Y35790D01*
X650049Y35915D01*
X650059Y36040D01*
Y38165D01*
X650089Y38195D01*
X650114Y38230D01*
X650144Y38265D01*
X650164Y38300D01*
X650189Y38335D01*
X650229Y38415D01*
X650274Y38535D01*
X650284Y38575D01*
X650294Y38620D01*
X650299Y38660D01*
X650309Y38705D01*
Y38875D01*
X650299Y38920D01*
X650294Y38960D01*
X650284Y39005D01*
X650274Y39045D01*
X650229Y39165D01*
X650189Y39245D01*
X650164Y39280D01*
X650144Y39315D01*
X650114Y39350D01*
X650089Y39385D01*
X650059Y39415D01*
Y41840D01*
X650049Y41965D01*
X650009Y42090D01*
X649949Y42200D01*
X649869Y42300D01*
X649769Y42380D01*
X649659Y42440D01*
X649534Y42480D01*
X649409Y42490D01*
X649284Y42480D01*
X649159Y42440D01*
X649049Y42380D01*
X648949Y42300D01*
X648869Y42200D01*
X648809Y42090D01*
X648769Y41965D01*
X648759Y41840D01*
Y39410D01*
X648729Y39380D01*
X648629Y39240D01*
X648609Y39200D01*
X648594Y39165D01*
X648574Y39125D01*
X648559Y39085D01*
X648549Y39045D01*
X648534Y39000D01*
X648529Y38960D01*
X648519Y38920D01*
X648514Y38875D01*
Y38835D01*
X648509Y38790D01*
X648514Y38745D01*
Y38705D01*
X648519Y38660D01*
X648529Y38620D01*
X648534Y38580D01*
X648549Y38535D01*
X648559Y38495D01*
X648574Y38455D01*
X648594Y38415D01*
X648609Y38380D01*
X648629Y38340D01*
X648729Y38200D01*
X648759Y38170D01*
Y36040D01*
X648769Y35915D01*
X648809Y35790D01*
X648869Y35680D01*
X648949Y35580D01*
X649049Y35500D01*
X649159Y35440D01*
X649284Y35400D01*
X649409Y35390D01*
G37*
G36*
G01X644685D02*
X644810Y35400D01*
X644935Y35440D01*
X645045Y35500D01*
X645145Y35580D01*
X645225Y35680D01*
X645285Y35790D01*
X645325Y35915D01*
X645335Y36040D01*
Y38165D01*
X645365Y38195D01*
X645390Y38230D01*
X645420Y38265D01*
X645440Y38300D01*
X645465Y38335D01*
X645505Y38415D01*
X645550Y38535D01*
X645560Y38575D01*
X645570Y38620D01*
X645575Y38660D01*
X645585Y38705D01*
Y38875D01*
X645575Y38920D01*
X645570Y38960D01*
X645560Y39005D01*
X645550Y39045D01*
X645505Y39165D01*
X645465Y39245D01*
X645440Y39280D01*
X645420Y39315D01*
X645390Y39350D01*
X645365Y39385D01*
X645335Y39415D01*
Y41840D01*
X645325Y41965D01*
X645285Y42090D01*
X645225Y42200D01*
X645145Y42300D01*
X645045Y42380D01*
X644935Y42440D01*
X644810Y42480D01*
X644685Y42490D01*
X644560Y42480D01*
X644435Y42440D01*
X644325Y42380D01*
X644225Y42300D01*
X644145Y42200D01*
X644085Y42090D01*
X644045Y41965D01*
X644035Y41840D01*
Y39410D01*
X644005Y39380D01*
X643905Y39240D01*
X643885Y39200D01*
X643870Y39165D01*
X643850Y39125D01*
X643835Y39085D01*
X643825Y39045D01*
X643810Y39000D01*
X643805Y38960D01*
X643795Y38920D01*
X643790Y38875D01*
Y38835D01*
X643785Y38790D01*
X643790Y38745D01*
Y38705D01*
X643795Y38660D01*
X643805Y38620D01*
X643810Y38580D01*
X643825Y38535D01*
X643835Y38495D01*
X643850Y38455D01*
X643870Y38415D01*
X643885Y38380D01*
X643905Y38340D01*
X644005Y38200D01*
X644035Y38170D01*
Y36040D01*
X644045Y35915D01*
X644085Y35790D01*
X644145Y35680D01*
X644225Y35580D01*
X644325Y35500D01*
X644435Y35440D01*
X644560Y35400D01*
X644685Y35390D01*
G37*
G36*
G01X639960D02*
X640085Y35400D01*
X640210Y35440D01*
X640320Y35500D01*
X640420Y35580D01*
X640500Y35680D01*
X640560Y35790D01*
X640600Y35915D01*
X640610Y36040D01*
Y38165D01*
X640640Y38195D01*
X640665Y38230D01*
X640695Y38265D01*
X640715Y38300D01*
X640740Y38335D01*
X640780Y38415D01*
X640825Y38535D01*
X640835Y38575D01*
X640845Y38620D01*
X640850Y38660D01*
X640860Y38705D01*
Y38875D01*
X640850Y38920D01*
X640845Y38960D01*
X640835Y39005D01*
X640825Y39045D01*
X640780Y39165D01*
X640740Y39245D01*
X640715Y39280D01*
X640695Y39315D01*
X640665Y39350D01*
X640640Y39385D01*
X640610Y39415D01*
Y41840D01*
X640600Y41965D01*
X640560Y42090D01*
X640500Y42200D01*
X640420Y42300D01*
X640320Y42380D01*
X640210Y42440D01*
X640085Y42480D01*
X639960Y42490D01*
X639835Y42480D01*
X639710Y42440D01*
X639600Y42380D01*
X639500Y42300D01*
X639420Y42200D01*
X639360Y42090D01*
X639320Y41965D01*
X639310Y41840D01*
Y39410D01*
X639280Y39380D01*
X639180Y39240D01*
X639160Y39200D01*
X639145Y39165D01*
X639125Y39125D01*
X639110Y39085D01*
X639100Y39045D01*
X639085Y39000D01*
X639080Y38960D01*
X639070Y38920D01*
X639065Y38875D01*
Y38835D01*
X639060Y38790D01*
X639065Y38745D01*
Y38705D01*
X639070Y38660D01*
X639080Y38620D01*
X639085Y38580D01*
X639100Y38535D01*
X639110Y38495D01*
X639125Y38455D01*
X639145Y38415D01*
X639160Y38380D01*
X639180Y38340D01*
X639280Y38200D01*
X639310Y38170D01*
Y36040D01*
X639320Y35915D01*
X639360Y35790D01*
X639420Y35680D01*
X639500Y35580D01*
X639600Y35500D01*
X639710Y35440D01*
X639835Y35400D01*
X639960Y35390D01*
G37*
G36*
G01X635236D02*
X635361Y35400D01*
X635486Y35440D01*
X635596Y35500D01*
X635696Y35580D01*
X635776Y35680D01*
X635836Y35790D01*
X635876Y35915D01*
X635886Y36040D01*
Y38165D01*
X635916Y38195D01*
X635941Y38230D01*
X635971Y38265D01*
X635991Y38300D01*
X636016Y38335D01*
X636056Y38415D01*
X636101Y38535D01*
X636111Y38575D01*
X636121Y38620D01*
X636126Y38660D01*
X636136Y38705D01*
Y38875D01*
X636126Y38920D01*
X636121Y38960D01*
X636111Y39005D01*
X636101Y39045D01*
X636056Y39165D01*
X636016Y39245D01*
X635991Y39280D01*
X635971Y39315D01*
X635941Y39350D01*
X635916Y39385D01*
X635886Y39415D01*
Y41840D01*
X635876Y41965D01*
X635836Y42090D01*
X635776Y42200D01*
X635696Y42300D01*
X635596Y42380D01*
X635486Y42440D01*
X635361Y42480D01*
X635236Y42490D01*
X635111Y42480D01*
X634986Y42440D01*
X634876Y42380D01*
X634776Y42300D01*
X634696Y42200D01*
X634636Y42090D01*
X634596Y41965D01*
X634586Y41840D01*
Y39410D01*
X634556Y39380D01*
X634456Y39240D01*
X634436Y39200D01*
X634421Y39165D01*
X634401Y39125D01*
X634386Y39085D01*
X634376Y39045D01*
X634361Y39000D01*
X634356Y38960D01*
X634346Y38920D01*
X634341Y38875D01*
Y38835D01*
X634336Y38790D01*
X634341Y38745D01*
Y38705D01*
X634346Y38660D01*
X634356Y38620D01*
X634361Y38580D01*
X634376Y38535D01*
X634386Y38495D01*
X634401Y38455D01*
X634421Y38415D01*
X634436Y38380D01*
X634456Y38340D01*
X634556Y38200D01*
X634586Y38170D01*
Y36040D01*
X634596Y35915D01*
X634636Y35790D01*
X634696Y35680D01*
X634776Y35580D01*
X634876Y35500D01*
X634986Y35440D01*
X635111Y35400D01*
X635236Y35390D01*
G37*
G36*
G01X663582D02*
X663707Y35400D01*
X663832Y35440D01*
X663942Y35500D01*
X664042Y35580D01*
X664122Y35680D01*
X664182Y35790D01*
X664222Y35915D01*
X664232Y36040D01*
Y38165D01*
X664262Y38195D01*
X664287Y38230D01*
X664317Y38265D01*
X664337Y38300D01*
X664362Y38335D01*
X664402Y38415D01*
X664447Y38535D01*
X664457Y38575D01*
X664467Y38620D01*
X664472Y38660D01*
X664482Y38705D01*
Y38875D01*
X664472Y38920D01*
X664467Y38960D01*
X664457Y39005D01*
X664447Y39045D01*
X664402Y39165D01*
X664362Y39245D01*
X664337Y39280D01*
X664317Y39315D01*
X664287Y39350D01*
X664262Y39385D01*
X664232Y39415D01*
Y41840D01*
X664222Y41965D01*
X664182Y42090D01*
X664122Y42200D01*
X664042Y42300D01*
X663942Y42380D01*
X663832Y42440D01*
X663707Y42480D01*
X663582Y42490D01*
X663457Y42480D01*
X663332Y42440D01*
X663222Y42380D01*
X663122Y42300D01*
X663042Y42200D01*
X662982Y42090D01*
X662942Y41965D01*
X662932Y41840D01*
Y39410D01*
X662902Y39380D01*
X662802Y39240D01*
X662782Y39200D01*
X662767Y39165D01*
X662747Y39125D01*
X662732Y39085D01*
X662722Y39045D01*
X662707Y39000D01*
X662702Y38960D01*
X662692Y38920D01*
X662687Y38875D01*
Y38835D01*
X662682Y38790D01*
X662687Y38745D01*
Y38705D01*
X662692Y38660D01*
X662702Y38620D01*
X662707Y38580D01*
X662722Y38535D01*
X662732Y38495D01*
X662747Y38455D01*
X662767Y38415D01*
X662782Y38380D01*
X662802Y38340D01*
X662902Y38200D01*
X662932Y38170D01*
Y36040D01*
X662942Y35915D01*
X662982Y35790D01*
X663042Y35680D01*
X663122Y35580D01*
X663222Y35500D01*
X663332Y35440D01*
X663457Y35400D01*
X663582Y35390D01*
G37*
G36*
G01X658858D02*
X658983Y35400D01*
X659108Y35440D01*
X659218Y35500D01*
X659318Y35580D01*
X659398Y35680D01*
X659458Y35790D01*
X659498Y35915D01*
X659508Y36040D01*
Y38165D01*
X659538Y38195D01*
X659563Y38230D01*
X659593Y38265D01*
X659613Y38300D01*
X659638Y38335D01*
X659678Y38415D01*
X659723Y38535D01*
X659733Y38575D01*
X659743Y38620D01*
X659748Y38660D01*
X659758Y38705D01*
Y38875D01*
X659748Y38920D01*
X659743Y38960D01*
X659733Y39005D01*
X659723Y39045D01*
X659678Y39165D01*
X659638Y39245D01*
X659613Y39280D01*
X659593Y39315D01*
X659563Y39350D01*
X659538Y39385D01*
X659508Y39415D01*
Y41840D01*
X659498Y41965D01*
X659458Y42090D01*
X659398Y42200D01*
X659318Y42300D01*
X659218Y42380D01*
X659108Y42440D01*
X658983Y42480D01*
X658858Y42490D01*
X658733Y42480D01*
X658608Y42440D01*
X658498Y42380D01*
X658398Y42300D01*
X658318Y42200D01*
X658258Y42090D01*
X658218Y41965D01*
X658208Y41840D01*
Y39410D01*
X658178Y39380D01*
X658078Y39240D01*
X658058Y39200D01*
X658043Y39165D01*
X658023Y39125D01*
X658008Y39085D01*
X657998Y39045D01*
X657983Y39000D01*
X657978Y38960D01*
X657968Y38920D01*
X657963Y38875D01*
Y38835D01*
X657958Y38790D01*
X657963Y38745D01*
Y38705D01*
X657968Y38660D01*
X657978Y38620D01*
X657983Y38580D01*
X657998Y38535D01*
X658008Y38495D01*
X658023Y38455D01*
X658043Y38415D01*
X658058Y38380D01*
X658078Y38340D01*
X658178Y38200D01*
X658208Y38170D01*
Y36040D01*
X658218Y35915D01*
X658258Y35790D01*
X658318Y35680D01*
X658398Y35580D01*
X658498Y35500D01*
X658608Y35440D01*
X658733Y35400D01*
X658858Y35390D01*
G37*
G36*
G01X654134D02*
X654259Y35400D01*
X654384Y35440D01*
X654494Y35500D01*
X654594Y35580D01*
X654674Y35680D01*
X654734Y35790D01*
X654774Y35915D01*
X654784Y36040D01*
Y38165D01*
X654814Y38195D01*
X654839Y38230D01*
X654869Y38265D01*
X654889Y38300D01*
X654914Y38335D01*
X654954Y38415D01*
X654999Y38535D01*
X655009Y38575D01*
X655019Y38620D01*
X655024Y38660D01*
X655034Y38705D01*
Y38875D01*
X655024Y38920D01*
X655019Y38960D01*
X655009Y39005D01*
X654999Y39045D01*
X654954Y39165D01*
X654914Y39245D01*
X654889Y39280D01*
X654869Y39315D01*
X654839Y39350D01*
X654814Y39385D01*
X654784Y39415D01*
Y41840D01*
X654774Y41965D01*
X654734Y42090D01*
X654674Y42200D01*
X654594Y42300D01*
X654494Y42380D01*
X654384Y42440D01*
X654259Y42480D01*
X654134Y42490D01*
X654009Y42480D01*
X653884Y42440D01*
X653774Y42380D01*
X653674Y42300D01*
X653594Y42200D01*
X653534Y42090D01*
X653494Y41965D01*
X653484Y41840D01*
Y39410D01*
X653454Y39380D01*
X653354Y39240D01*
X653334Y39200D01*
X653319Y39165D01*
X653299Y39125D01*
X653284Y39085D01*
X653274Y39045D01*
X653259Y39000D01*
X653254Y38960D01*
X653244Y38920D01*
X653239Y38875D01*
Y38835D01*
X653234Y38790D01*
X653239Y38745D01*
Y38705D01*
X653244Y38660D01*
X653254Y38620D01*
X653259Y38580D01*
X653274Y38535D01*
X653284Y38495D01*
X653299Y38455D01*
X653319Y38415D01*
X653334Y38380D01*
X653354Y38340D01*
X653454Y38200D01*
X653484Y38170D01*
Y36040D01*
X653494Y35915D01*
X653534Y35790D01*
X653594Y35680D01*
X653674Y35580D01*
X653774Y35500D01*
X653884Y35440D01*
X654009Y35400D01*
X654134Y35390D01*
G37*
G36*
G01X677756D02*
X677881Y35400D01*
X678006Y35440D01*
X678116Y35500D01*
X678216Y35580D01*
X678296Y35680D01*
X678356Y35790D01*
X678396Y35915D01*
X678406Y36040D01*
Y38165D01*
X678436Y38195D01*
X678461Y38230D01*
X678491Y38265D01*
X678511Y38300D01*
X678536Y38335D01*
X678576Y38415D01*
X678621Y38535D01*
X678631Y38575D01*
X678641Y38620D01*
X678646Y38660D01*
X678656Y38705D01*
Y38875D01*
X678646Y38920D01*
X678641Y38960D01*
X678631Y39005D01*
X678621Y39045D01*
X678576Y39165D01*
X678536Y39245D01*
X678511Y39280D01*
X678491Y39315D01*
X678461Y39350D01*
X678436Y39385D01*
X678406Y39415D01*
Y41840D01*
X678396Y41965D01*
X678356Y42090D01*
X678296Y42200D01*
X678216Y42300D01*
X678116Y42380D01*
X678006Y42440D01*
X677881Y42480D01*
X677756Y42490D01*
X677631Y42480D01*
X677506Y42440D01*
X677396Y42380D01*
X677296Y42300D01*
X677216Y42200D01*
X677156Y42090D01*
X677116Y41965D01*
X677106Y41840D01*
Y39410D01*
X677076Y39380D01*
X676976Y39240D01*
X676956Y39200D01*
X676941Y39165D01*
X676921Y39125D01*
X676906Y39085D01*
X676896Y39045D01*
X676881Y39000D01*
X676876Y38960D01*
X676866Y38920D01*
X676861Y38875D01*
Y38835D01*
X676856Y38790D01*
X676861Y38745D01*
Y38705D01*
X676866Y38660D01*
X676876Y38620D01*
X676881Y38580D01*
X676896Y38535D01*
X676906Y38495D01*
X676921Y38455D01*
X676941Y38415D01*
X676956Y38380D01*
X676976Y38340D01*
X677076Y38200D01*
X677106Y38170D01*
Y36040D01*
X677116Y35915D01*
X677156Y35790D01*
X677216Y35680D01*
X677296Y35580D01*
X677396Y35500D01*
X677506Y35440D01*
X677631Y35400D01*
X677756Y35390D01*
G37*
G36*
G01X673031D02*
X673156Y35400D01*
X673281Y35440D01*
X673391Y35500D01*
X673491Y35580D01*
X673571Y35680D01*
X673631Y35790D01*
X673671Y35915D01*
X673681Y36040D01*
Y38165D01*
X673711Y38195D01*
X673736Y38230D01*
X673766Y38265D01*
X673786Y38300D01*
X673811Y38335D01*
X673851Y38415D01*
X673896Y38535D01*
X673906Y38575D01*
X673916Y38620D01*
X673921Y38660D01*
X673931Y38705D01*
Y38875D01*
X673921Y38920D01*
X673916Y38960D01*
X673906Y39005D01*
X673896Y39045D01*
X673851Y39165D01*
X673811Y39245D01*
X673786Y39280D01*
X673766Y39315D01*
X673736Y39350D01*
X673711Y39385D01*
X673681Y39415D01*
Y41840D01*
X673671Y41965D01*
X673631Y42090D01*
X673571Y42200D01*
X673491Y42300D01*
X673391Y42380D01*
X673281Y42440D01*
X673156Y42480D01*
X673031Y42490D01*
X672906Y42480D01*
X672781Y42440D01*
X672671Y42380D01*
X672571Y42300D01*
X672491Y42200D01*
X672431Y42090D01*
X672391Y41965D01*
X672381Y41840D01*
Y39410D01*
X672351Y39380D01*
X672251Y39240D01*
X672231Y39200D01*
X672216Y39165D01*
X672196Y39125D01*
X672181Y39085D01*
X672171Y39045D01*
X672156Y39000D01*
X672151Y38960D01*
X672141Y38920D01*
X672136Y38875D01*
Y38835D01*
X672131Y38790D01*
X672136Y38745D01*
Y38705D01*
X672141Y38660D01*
X672151Y38620D01*
X672156Y38580D01*
X672171Y38535D01*
X672181Y38495D01*
X672196Y38455D01*
X672216Y38415D01*
X672231Y38380D01*
X672251Y38340D01*
X672351Y38200D01*
X672381Y38170D01*
Y36040D01*
X672391Y35915D01*
X672431Y35790D01*
X672491Y35680D01*
X672571Y35580D01*
X672671Y35500D01*
X672781Y35440D01*
X672906Y35400D01*
X673031Y35390D01*
G37*
G36*
G01X668307D02*
X668432Y35400D01*
X668557Y35440D01*
X668667Y35500D01*
X668767Y35580D01*
X668847Y35680D01*
X668907Y35790D01*
X668947Y35915D01*
X668957Y36040D01*
Y38165D01*
X668987Y38195D01*
X669012Y38230D01*
X669042Y38265D01*
X669062Y38300D01*
X669087Y38335D01*
X669127Y38415D01*
X669172Y38535D01*
X669182Y38575D01*
X669192Y38620D01*
X669197Y38660D01*
X669207Y38705D01*
Y38875D01*
X669197Y38920D01*
X669192Y38960D01*
X669182Y39005D01*
X669172Y39045D01*
X669127Y39165D01*
X669087Y39245D01*
X669062Y39280D01*
X669042Y39315D01*
X669012Y39350D01*
X668987Y39385D01*
X668957Y39415D01*
Y41840D01*
X668947Y41965D01*
X668907Y42090D01*
X668847Y42200D01*
X668767Y42300D01*
X668667Y42380D01*
X668557Y42440D01*
X668432Y42480D01*
X668307Y42490D01*
X668182Y42480D01*
X668057Y42440D01*
X667947Y42380D01*
X667847Y42300D01*
X667767Y42200D01*
X667707Y42090D01*
X667667Y41965D01*
X667657Y41840D01*
Y39410D01*
X667627Y39380D01*
X667527Y39240D01*
X667507Y39200D01*
X667492Y39165D01*
X667472Y39125D01*
X667457Y39085D01*
X667447Y39045D01*
X667432Y39000D01*
X667427Y38960D01*
X667417Y38920D01*
X667412Y38875D01*
Y38835D01*
X667407Y38790D01*
X667412Y38745D01*
Y38705D01*
X667417Y38660D01*
X667427Y38620D01*
X667432Y38580D01*
X667447Y38535D01*
X667457Y38495D01*
X667472Y38455D01*
X667492Y38415D01*
X667507Y38380D01*
X667527Y38340D01*
X667627Y38200D01*
X667657Y38170D01*
Y36040D01*
X667667Y35915D01*
X667707Y35790D01*
X667767Y35680D01*
X667847Y35580D01*
X667947Y35500D01*
X668057Y35440D01*
X668182Y35400D01*
X668307Y35390D01*
G37*
G36*
G01X691929D02*
X692054Y35400D01*
X692179Y35440D01*
X692289Y35500D01*
X692389Y35580D01*
X692469Y35680D01*
X692529Y35790D01*
X692569Y35915D01*
X692579Y36040D01*
Y38165D01*
X692609Y38195D01*
X692634Y38230D01*
X692664Y38265D01*
X692684Y38300D01*
X692709Y38335D01*
X692749Y38415D01*
X692794Y38535D01*
X692804Y38575D01*
X692814Y38620D01*
X692819Y38660D01*
X692829Y38705D01*
Y38875D01*
X692819Y38920D01*
X692814Y38960D01*
X692804Y39005D01*
X692794Y39045D01*
X692749Y39165D01*
X692709Y39245D01*
X692684Y39280D01*
X692664Y39315D01*
X692634Y39350D01*
X692609Y39385D01*
X692579Y39415D01*
Y41840D01*
X692569Y41965D01*
X692529Y42090D01*
X692469Y42200D01*
X692389Y42300D01*
X692289Y42380D01*
X692179Y42440D01*
X692054Y42480D01*
X691929Y42490D01*
X691804Y42480D01*
X691679Y42440D01*
X691569Y42380D01*
X691469Y42300D01*
X691389Y42200D01*
X691329Y42090D01*
X691289Y41965D01*
X691279Y41840D01*
Y39410D01*
X691249Y39380D01*
X691149Y39240D01*
X691129Y39200D01*
X691114Y39165D01*
X691094Y39125D01*
X691079Y39085D01*
X691069Y39045D01*
X691054Y39000D01*
X691049Y38960D01*
X691039Y38920D01*
X691034Y38875D01*
Y38835D01*
X691029Y38790D01*
X691034Y38745D01*
Y38705D01*
X691039Y38660D01*
X691049Y38620D01*
X691054Y38580D01*
X691069Y38535D01*
X691079Y38495D01*
X691094Y38455D01*
X691114Y38415D01*
X691129Y38380D01*
X691149Y38340D01*
X691249Y38200D01*
X691279Y38170D01*
Y36040D01*
X691289Y35915D01*
X691329Y35790D01*
X691389Y35680D01*
X691469Y35580D01*
X691569Y35500D01*
X691679Y35440D01*
X691804Y35400D01*
X691929Y35390D01*
G37*
G36*
G01X687204D02*
X687329Y35400D01*
X687454Y35440D01*
X687564Y35500D01*
X687664Y35580D01*
X687744Y35680D01*
X687804Y35790D01*
X687844Y35915D01*
X687854Y36040D01*
Y38165D01*
X687884Y38195D01*
X687909Y38230D01*
X687939Y38265D01*
X687959Y38300D01*
X687984Y38335D01*
X688024Y38415D01*
X688069Y38535D01*
X688079Y38575D01*
X688089Y38620D01*
X688094Y38660D01*
X688104Y38705D01*
Y38875D01*
X688094Y38920D01*
X688089Y38960D01*
X688079Y39005D01*
X688069Y39045D01*
X688024Y39165D01*
X687984Y39245D01*
X687959Y39280D01*
X687939Y39315D01*
X687909Y39350D01*
X687884Y39385D01*
X687854Y39415D01*
Y41840D01*
X687844Y41965D01*
X687804Y42090D01*
X687744Y42200D01*
X687664Y42300D01*
X687564Y42380D01*
X687454Y42440D01*
X687329Y42480D01*
X687204Y42490D01*
X687079Y42480D01*
X686954Y42440D01*
X686844Y42380D01*
X686744Y42300D01*
X686664Y42200D01*
X686604Y42090D01*
X686564Y41965D01*
X686554Y41840D01*
Y39410D01*
X686524Y39380D01*
X686424Y39240D01*
X686404Y39200D01*
X686389Y39165D01*
X686369Y39125D01*
X686354Y39085D01*
X686344Y39045D01*
X686329Y39000D01*
X686324Y38960D01*
X686314Y38920D01*
X686309Y38875D01*
Y38835D01*
X686304Y38790D01*
X686309Y38745D01*
Y38705D01*
X686314Y38660D01*
X686324Y38620D01*
X686329Y38580D01*
X686344Y38535D01*
X686354Y38495D01*
X686369Y38455D01*
X686389Y38415D01*
X686404Y38380D01*
X686424Y38340D01*
X686524Y38200D01*
X686554Y38170D01*
Y36040D01*
X686564Y35915D01*
X686604Y35790D01*
X686664Y35680D01*
X686744Y35580D01*
X686844Y35500D01*
X686954Y35440D01*
X687079Y35400D01*
X687204Y35390D01*
G37*
G36*
G01X682480D02*
X682605Y35400D01*
X682730Y35440D01*
X682840Y35500D01*
X682940Y35580D01*
X683020Y35680D01*
X683080Y35790D01*
X683120Y35915D01*
X683130Y36040D01*
Y38165D01*
X683160Y38195D01*
X683185Y38230D01*
X683215Y38265D01*
X683235Y38300D01*
X683260Y38335D01*
X683300Y38415D01*
X683345Y38535D01*
X683355Y38575D01*
X683365Y38620D01*
X683370Y38660D01*
X683380Y38705D01*
Y38875D01*
X683370Y38920D01*
X683365Y38960D01*
X683355Y39005D01*
X683345Y39045D01*
X683300Y39165D01*
X683260Y39245D01*
X683235Y39280D01*
X683215Y39315D01*
X683185Y39350D01*
X683160Y39385D01*
X683130Y39415D01*
Y41840D01*
X683120Y41965D01*
X683080Y42090D01*
X683020Y42200D01*
X682940Y42300D01*
X682840Y42380D01*
X682730Y42440D01*
X682605Y42480D01*
X682480Y42490D01*
X682355Y42480D01*
X682230Y42440D01*
X682120Y42380D01*
X682020Y42300D01*
X681940Y42200D01*
X681880Y42090D01*
X681840Y41965D01*
X681830Y41840D01*
Y39410D01*
X681800Y39380D01*
X681700Y39240D01*
X681680Y39200D01*
X681665Y39165D01*
X681645Y39125D01*
X681630Y39085D01*
X681620Y39045D01*
X681605Y39000D01*
X681600Y38960D01*
X681590Y38920D01*
X681585Y38875D01*
Y38835D01*
X681580Y38790D01*
X681585Y38745D01*
Y38705D01*
X681590Y38660D01*
X681600Y38620D01*
X681605Y38580D01*
X681620Y38535D01*
X681630Y38495D01*
X681645Y38455D01*
X681665Y38415D01*
X681680Y38380D01*
X681700Y38340D01*
X681800Y38200D01*
X681830Y38170D01*
Y36040D01*
X681840Y35915D01*
X681880Y35790D01*
X681940Y35680D01*
X682020Y35580D01*
X682120Y35500D01*
X682230Y35440D01*
X682355Y35400D01*
X682480Y35390D01*
G37*
G36*
G01X710827D02*
X710952Y35400D01*
X711077Y35440D01*
X711187Y35500D01*
X711287Y35580D01*
X711367Y35680D01*
X711427Y35790D01*
X711467Y35915D01*
X711477Y36040D01*
Y38165D01*
X711507Y38195D01*
X711532Y38230D01*
X711562Y38265D01*
X711582Y38300D01*
X711607Y38335D01*
X711647Y38415D01*
X711692Y38535D01*
X711702Y38575D01*
X711712Y38620D01*
X711717Y38660D01*
X711727Y38705D01*
Y38875D01*
X711717Y38920D01*
X711712Y38960D01*
X711702Y39005D01*
X711692Y39045D01*
X711647Y39165D01*
X711607Y39245D01*
X711582Y39280D01*
X711562Y39315D01*
X711532Y39350D01*
X711507Y39385D01*
X711477Y39415D01*
Y41840D01*
X711467Y41965D01*
X711427Y42090D01*
X711367Y42200D01*
X711287Y42300D01*
X711187Y42380D01*
X711077Y42440D01*
X710952Y42480D01*
X710827Y42490D01*
X710702Y42480D01*
X710577Y42440D01*
X710467Y42380D01*
X710367Y42300D01*
X710287Y42200D01*
X710227Y42090D01*
X710187Y41965D01*
X710177Y41840D01*
Y39410D01*
X710147Y39380D01*
X710047Y39240D01*
X710027Y39200D01*
X710012Y39165D01*
X709992Y39125D01*
X709977Y39085D01*
X709967Y39045D01*
X709952Y39000D01*
X709947Y38960D01*
X709937Y38920D01*
X709932Y38875D01*
Y38835D01*
X709927Y38790D01*
X709932Y38745D01*
Y38705D01*
X709937Y38660D01*
X709947Y38620D01*
X709952Y38580D01*
X709967Y38535D01*
X709977Y38495D01*
X709992Y38455D01*
X710012Y38415D01*
X710027Y38380D01*
X710047Y38340D01*
X710147Y38200D01*
X710177Y38170D01*
Y36040D01*
X710187Y35915D01*
X710227Y35790D01*
X710287Y35680D01*
X710367Y35580D01*
X710467Y35500D01*
X710577Y35440D01*
X710702Y35400D01*
X710827Y35390D01*
G37*
G36*
G01X706102D02*
X706227Y35400D01*
X706352Y35440D01*
X706462Y35500D01*
X706562Y35580D01*
X706642Y35680D01*
X706702Y35790D01*
X706742Y35915D01*
X706752Y36040D01*
Y38165D01*
X706782Y38195D01*
X706807Y38230D01*
X706837Y38265D01*
X706857Y38300D01*
X706882Y38335D01*
X706922Y38415D01*
X706967Y38535D01*
X706977Y38575D01*
X706987Y38620D01*
X706992Y38660D01*
X707002Y38705D01*
Y38875D01*
X706992Y38920D01*
X706987Y38960D01*
X706977Y39005D01*
X706967Y39045D01*
X706922Y39165D01*
X706882Y39245D01*
X706857Y39280D01*
X706837Y39315D01*
X706807Y39350D01*
X706782Y39385D01*
X706752Y39415D01*
Y41840D01*
X706742Y41965D01*
X706702Y42090D01*
X706642Y42200D01*
X706562Y42300D01*
X706462Y42380D01*
X706352Y42440D01*
X706227Y42480D01*
X706102Y42490D01*
X705977Y42480D01*
X705852Y42440D01*
X705742Y42380D01*
X705642Y42300D01*
X705562Y42200D01*
X705502Y42090D01*
X705462Y41965D01*
X705452Y41840D01*
Y39410D01*
X705422Y39380D01*
X705322Y39240D01*
X705302Y39200D01*
X705287Y39165D01*
X705267Y39125D01*
X705252Y39085D01*
X705242Y39045D01*
X705227Y39000D01*
X705222Y38960D01*
X705212Y38920D01*
X705207Y38875D01*
Y38835D01*
X705202Y38790D01*
X705207Y38745D01*
Y38705D01*
X705212Y38660D01*
X705222Y38620D01*
X705227Y38580D01*
X705242Y38535D01*
X705252Y38495D01*
X705267Y38455D01*
X705287Y38415D01*
X705302Y38380D01*
X705322Y38340D01*
X705422Y38200D01*
X705452Y38170D01*
Y36040D01*
X705462Y35915D01*
X705502Y35790D01*
X705562Y35680D01*
X705642Y35580D01*
X705742Y35500D01*
X705852Y35440D01*
X705977Y35400D01*
X706102Y35390D01*
G37*
G36*
G01X701378D02*
X701503Y35400D01*
X701628Y35440D01*
X701738Y35500D01*
X701838Y35580D01*
X701918Y35680D01*
X701978Y35790D01*
X702018Y35915D01*
X702028Y36040D01*
Y38165D01*
X702058Y38195D01*
X702083Y38230D01*
X702113Y38265D01*
X702133Y38300D01*
X702158Y38335D01*
X702198Y38415D01*
X702243Y38535D01*
X702253Y38575D01*
X702263Y38620D01*
X702268Y38660D01*
X702278Y38705D01*
Y38875D01*
X702268Y38920D01*
X702263Y38960D01*
X702253Y39005D01*
X702243Y39045D01*
X702198Y39165D01*
X702158Y39245D01*
X702133Y39280D01*
X702113Y39315D01*
X702083Y39350D01*
X702058Y39385D01*
X702028Y39415D01*
Y41840D01*
X702018Y41965D01*
X701978Y42090D01*
X701918Y42200D01*
X701838Y42300D01*
X701738Y42380D01*
X701628Y42440D01*
X701503Y42480D01*
X701378Y42490D01*
X701253Y42480D01*
X701128Y42440D01*
X701018Y42380D01*
X700918Y42300D01*
X700838Y42200D01*
X700778Y42090D01*
X700738Y41965D01*
X700728Y41840D01*
Y39410D01*
X700698Y39380D01*
X700598Y39240D01*
X700578Y39200D01*
X700563Y39165D01*
X700543Y39125D01*
X700528Y39085D01*
X700518Y39045D01*
X700503Y39000D01*
X700498Y38960D01*
X700488Y38920D01*
X700483Y38875D01*
Y38835D01*
X700478Y38790D01*
X700483Y38745D01*
Y38705D01*
X700488Y38660D01*
X700498Y38620D01*
X700503Y38580D01*
X700518Y38535D01*
X700528Y38495D01*
X700543Y38455D01*
X700563Y38415D01*
X700578Y38380D01*
X700598Y38340D01*
X700698Y38200D01*
X700728Y38170D01*
Y36040D01*
X700738Y35915D01*
X700778Y35790D01*
X700838Y35680D01*
X700918Y35580D01*
X701018Y35500D01*
X701128Y35440D01*
X701253Y35400D01*
X701378Y35390D01*
G37*
G36*
G01X696653D02*
X696778Y35400D01*
X696903Y35440D01*
X697013Y35500D01*
X697113Y35580D01*
X697193Y35680D01*
X697253Y35790D01*
X697293Y35915D01*
X697303Y36040D01*
Y38165D01*
X697333Y38195D01*
X697358Y38230D01*
X697388Y38265D01*
X697408Y38300D01*
X697433Y38335D01*
X697473Y38415D01*
X697518Y38535D01*
X697528Y38575D01*
X697538Y38620D01*
X697543Y38660D01*
X697553Y38705D01*
Y38875D01*
X697543Y38920D01*
X697538Y38960D01*
X697528Y39005D01*
X697518Y39045D01*
X697473Y39165D01*
X697433Y39245D01*
X697408Y39280D01*
X697388Y39315D01*
X697358Y39350D01*
X697333Y39385D01*
X697303Y39415D01*
Y41840D01*
X697293Y41965D01*
X697253Y42090D01*
X697193Y42200D01*
X697113Y42300D01*
X697013Y42380D01*
X696903Y42440D01*
X696778Y42480D01*
X696653Y42490D01*
X696528Y42480D01*
X696403Y42440D01*
X696293Y42380D01*
X696193Y42300D01*
X696113Y42200D01*
X696053Y42090D01*
X696013Y41965D01*
X696003Y41840D01*
Y39410D01*
X695973Y39380D01*
X695873Y39240D01*
X695853Y39200D01*
X695838Y39165D01*
X695818Y39125D01*
X695803Y39085D01*
X695793Y39045D01*
X695778Y39000D01*
X695773Y38960D01*
X695763Y38920D01*
X695758Y38875D01*
Y38835D01*
X695753Y38790D01*
X695758Y38745D01*
Y38705D01*
X695763Y38660D01*
X695773Y38620D01*
X695778Y38580D01*
X695793Y38535D01*
X695803Y38495D01*
X695818Y38455D01*
X695838Y38415D01*
X695853Y38380D01*
X695873Y38340D01*
X695973Y38200D01*
X696003Y38170D01*
Y36040D01*
X696013Y35915D01*
X696053Y35790D01*
X696113Y35680D01*
X696193Y35580D01*
X696293Y35500D01*
X696403Y35440D01*
X696528Y35400D01*
X696653Y35390D01*
G37*
G36*
G01X725000D02*
X725125Y35400D01*
X725250Y35440D01*
X725360Y35500D01*
X725460Y35580D01*
X725540Y35680D01*
X725600Y35790D01*
X725640Y35915D01*
X725650Y36040D01*
Y38165D01*
X725680Y38195D01*
X725705Y38230D01*
X725735Y38265D01*
X725755Y38300D01*
X725780Y38335D01*
X725820Y38415D01*
X725865Y38535D01*
X725875Y38575D01*
X725885Y38620D01*
X725890Y38660D01*
X725900Y38705D01*
Y38875D01*
X725890Y38920D01*
X725885Y38960D01*
X725875Y39005D01*
X725865Y39045D01*
X725820Y39165D01*
X725780Y39245D01*
X725755Y39280D01*
X725735Y39315D01*
X725705Y39350D01*
X725680Y39385D01*
X725650Y39415D01*
Y41840D01*
X725640Y41965D01*
X725600Y42090D01*
X725540Y42200D01*
X725460Y42300D01*
X725360Y42380D01*
X725250Y42440D01*
X725125Y42480D01*
X725000Y42490D01*
X724875Y42480D01*
X724750Y42440D01*
X724640Y42380D01*
X724540Y42300D01*
X724460Y42200D01*
X724400Y42090D01*
X724360Y41965D01*
X724350Y41840D01*
Y39410D01*
X724320Y39380D01*
X724220Y39240D01*
X724200Y39200D01*
X724185Y39165D01*
X724165Y39125D01*
X724150Y39085D01*
X724140Y39045D01*
X724125Y39000D01*
X724120Y38960D01*
X724110Y38920D01*
X724105Y38875D01*
Y38835D01*
X724100Y38790D01*
X724105Y38745D01*
Y38705D01*
X724110Y38660D01*
X724120Y38620D01*
X724125Y38580D01*
X724140Y38535D01*
X724150Y38495D01*
X724165Y38455D01*
X724185Y38415D01*
X724200Y38380D01*
X724220Y38340D01*
X724320Y38200D01*
X724350Y38170D01*
Y36040D01*
X724360Y35915D01*
X724400Y35790D01*
X724460Y35680D01*
X724540Y35580D01*
X724640Y35500D01*
X724750Y35440D01*
X724875Y35400D01*
X725000Y35390D01*
G37*
G36*
G01X720275D02*
X720400Y35400D01*
X720525Y35440D01*
X720635Y35500D01*
X720735Y35580D01*
X720815Y35680D01*
X720875Y35790D01*
X720915Y35915D01*
X720925Y36040D01*
Y38165D01*
X720955Y38195D01*
X720980Y38230D01*
X721010Y38265D01*
X721030Y38300D01*
X721055Y38335D01*
X721095Y38415D01*
X721140Y38535D01*
X721150Y38575D01*
X721160Y38620D01*
X721165Y38660D01*
X721175Y38705D01*
Y38875D01*
X721165Y38920D01*
X721160Y38960D01*
X721150Y39005D01*
X721140Y39045D01*
X721095Y39165D01*
X721055Y39245D01*
X721030Y39280D01*
X721010Y39315D01*
X720980Y39350D01*
X720955Y39385D01*
X720925Y39415D01*
Y41840D01*
X720915Y41965D01*
X720875Y42090D01*
X720815Y42200D01*
X720735Y42300D01*
X720635Y42380D01*
X720525Y42440D01*
X720400Y42480D01*
X720275Y42490D01*
X720150Y42480D01*
X720025Y42440D01*
X719915Y42380D01*
X719815Y42300D01*
X719735Y42200D01*
X719675Y42090D01*
X719635Y41965D01*
X719625Y41840D01*
Y39410D01*
X719595Y39380D01*
X719495Y39240D01*
X719475Y39200D01*
X719460Y39165D01*
X719440Y39125D01*
X719425Y39085D01*
X719415Y39045D01*
X719400Y39000D01*
X719395Y38960D01*
X719385Y38920D01*
X719380Y38875D01*
Y38835D01*
X719375Y38790D01*
X719380Y38745D01*
Y38705D01*
X719385Y38660D01*
X719395Y38620D01*
X719400Y38580D01*
X719415Y38535D01*
X719425Y38495D01*
X719440Y38455D01*
X719460Y38415D01*
X719475Y38380D01*
X719495Y38340D01*
X719595Y38200D01*
X719625Y38170D01*
Y36040D01*
X719635Y35915D01*
X719675Y35790D01*
X719735Y35680D01*
X719815Y35580D01*
X719915Y35500D01*
X720025Y35440D01*
X720150Y35400D01*
X720275Y35390D01*
G37*
G36*
G01X715551D02*
X715676Y35400D01*
X715801Y35440D01*
X715911Y35500D01*
X716011Y35580D01*
X716091Y35680D01*
X716151Y35790D01*
X716191Y35915D01*
X716201Y36040D01*
Y38165D01*
X716231Y38195D01*
X716256Y38230D01*
X716286Y38265D01*
X716306Y38300D01*
X716331Y38335D01*
X716371Y38415D01*
X716416Y38535D01*
X716426Y38575D01*
X716436Y38620D01*
X716441Y38660D01*
X716451Y38705D01*
Y38875D01*
X716441Y38920D01*
X716436Y38960D01*
X716426Y39005D01*
X716416Y39045D01*
X716371Y39165D01*
X716331Y39245D01*
X716306Y39280D01*
X716286Y39315D01*
X716256Y39350D01*
X716231Y39385D01*
X716201Y39415D01*
Y41840D01*
X716191Y41965D01*
X716151Y42090D01*
X716091Y42200D01*
X716011Y42300D01*
X715911Y42380D01*
X715801Y42440D01*
X715676Y42480D01*
X715551Y42490D01*
X715426Y42480D01*
X715301Y42440D01*
X715191Y42380D01*
X715091Y42300D01*
X715011Y42200D01*
X714951Y42090D01*
X714911Y41965D01*
X714901Y41840D01*
Y39410D01*
X714871Y39380D01*
X714771Y39240D01*
X714751Y39200D01*
X714736Y39165D01*
X714716Y39125D01*
X714701Y39085D01*
X714691Y39045D01*
X714676Y39000D01*
X714671Y38960D01*
X714661Y38920D01*
X714656Y38875D01*
Y38835D01*
X714651Y38790D01*
X714656Y38745D01*
Y38705D01*
X714661Y38660D01*
X714671Y38620D01*
X714676Y38580D01*
X714691Y38535D01*
X714701Y38495D01*
X714716Y38455D01*
X714736Y38415D01*
X714751Y38380D01*
X714771Y38340D01*
X714871Y38200D01*
X714901Y38170D01*
Y36040D01*
X714911Y35915D01*
X714951Y35790D01*
X715011Y35680D01*
X715091Y35580D01*
X715191Y35500D01*
X715301Y35440D01*
X715426Y35400D01*
X715551Y35390D01*
G37*
G36*
G01X739173D02*
X739298Y35400D01*
X739423Y35440D01*
X739533Y35500D01*
X739633Y35580D01*
X739713Y35680D01*
X739773Y35790D01*
X739813Y35915D01*
X739823Y36040D01*
Y38165D01*
X739853Y38195D01*
X739878Y38230D01*
X739908Y38265D01*
X739928Y38300D01*
X739953Y38335D01*
X739993Y38415D01*
X740038Y38535D01*
X740048Y38575D01*
X740058Y38620D01*
X740063Y38660D01*
X740073Y38705D01*
Y38875D01*
X740063Y38920D01*
X740058Y38960D01*
X740048Y39005D01*
X740038Y39045D01*
X739993Y39165D01*
X739953Y39245D01*
X739928Y39280D01*
X739908Y39315D01*
X739878Y39350D01*
X739853Y39385D01*
X739823Y39415D01*
Y41840D01*
X739813Y41965D01*
X739773Y42090D01*
X739713Y42200D01*
X739633Y42300D01*
X739533Y42380D01*
X739423Y42440D01*
X739298Y42480D01*
X739173Y42490D01*
X739048Y42480D01*
X738923Y42440D01*
X738813Y42380D01*
X738713Y42300D01*
X738633Y42200D01*
X738573Y42090D01*
X738533Y41965D01*
X738523Y41840D01*
Y39410D01*
X738493Y39380D01*
X738393Y39240D01*
X738373Y39200D01*
X738358Y39165D01*
X738338Y39125D01*
X738323Y39085D01*
X738313Y39045D01*
X738298Y39000D01*
X738293Y38960D01*
X738283Y38920D01*
X738278Y38875D01*
Y38835D01*
X738273Y38790D01*
X738278Y38745D01*
Y38705D01*
X738283Y38660D01*
X738293Y38620D01*
X738298Y38580D01*
X738313Y38535D01*
X738323Y38495D01*
X738338Y38455D01*
X738358Y38415D01*
X738373Y38380D01*
X738393Y38340D01*
X738493Y38200D01*
X738523Y38170D01*
Y36040D01*
X738533Y35915D01*
X738573Y35790D01*
X738633Y35680D01*
X738713Y35580D01*
X738813Y35500D01*
X738923Y35440D01*
X739048Y35400D01*
X739173Y35390D01*
G37*
G36*
G01X734449D02*
X734574Y35400D01*
X734699Y35440D01*
X734809Y35500D01*
X734909Y35580D01*
X734989Y35680D01*
X735049Y35790D01*
X735089Y35915D01*
X735099Y36040D01*
Y38165D01*
X735129Y38195D01*
X735154Y38230D01*
X735184Y38265D01*
X735204Y38300D01*
X735229Y38335D01*
X735269Y38415D01*
X735314Y38535D01*
X735324Y38575D01*
X735334Y38620D01*
X735339Y38660D01*
X735349Y38705D01*
Y38875D01*
X735339Y38920D01*
X735334Y38960D01*
X735324Y39005D01*
X735314Y39045D01*
X735269Y39165D01*
X735229Y39245D01*
X735204Y39280D01*
X735184Y39315D01*
X735154Y39350D01*
X735129Y39385D01*
X735099Y39415D01*
Y41840D01*
X735089Y41965D01*
X735049Y42090D01*
X734989Y42200D01*
X734909Y42300D01*
X734809Y42380D01*
X734699Y42440D01*
X734574Y42480D01*
X734449Y42490D01*
X734324Y42480D01*
X734199Y42440D01*
X734089Y42380D01*
X733989Y42300D01*
X733909Y42200D01*
X733849Y42090D01*
X733809Y41965D01*
X733799Y41840D01*
Y39410D01*
X733769Y39380D01*
X733669Y39240D01*
X733649Y39200D01*
X733634Y39165D01*
X733614Y39125D01*
X733599Y39085D01*
X733589Y39045D01*
X733574Y39000D01*
X733569Y38960D01*
X733559Y38920D01*
X733554Y38875D01*
Y38835D01*
X733549Y38790D01*
X733554Y38745D01*
Y38705D01*
X733559Y38660D01*
X733569Y38620D01*
X733574Y38580D01*
X733589Y38535D01*
X733599Y38495D01*
X733614Y38455D01*
X733634Y38415D01*
X733649Y38380D01*
X733669Y38340D01*
X733769Y38200D01*
X733799Y38170D01*
Y36040D01*
X733809Y35915D01*
X733849Y35790D01*
X733909Y35680D01*
X733989Y35580D01*
X734089Y35500D01*
X734199Y35440D01*
X734324Y35400D01*
X734449Y35390D01*
G37*
G36*
G01X729724D02*
X729849Y35400D01*
X729974Y35440D01*
X730084Y35500D01*
X730184Y35580D01*
X730264Y35680D01*
X730324Y35790D01*
X730364Y35915D01*
X730374Y36040D01*
Y38165D01*
X730404Y38195D01*
X730429Y38230D01*
X730459Y38265D01*
X730479Y38300D01*
X730504Y38335D01*
X730544Y38415D01*
X730589Y38535D01*
X730599Y38575D01*
X730609Y38620D01*
X730614Y38660D01*
X730624Y38705D01*
Y38875D01*
X730614Y38920D01*
X730609Y38960D01*
X730599Y39005D01*
X730589Y39045D01*
X730544Y39165D01*
X730504Y39245D01*
X730479Y39280D01*
X730459Y39315D01*
X730429Y39350D01*
X730404Y39385D01*
X730374Y39415D01*
Y41840D01*
X730364Y41965D01*
X730324Y42090D01*
X730264Y42200D01*
X730184Y42300D01*
X730084Y42380D01*
X729974Y42440D01*
X729849Y42480D01*
X729724Y42490D01*
X729599Y42480D01*
X729474Y42440D01*
X729364Y42380D01*
X729264Y42300D01*
X729184Y42200D01*
X729124Y42090D01*
X729084Y41965D01*
X729074Y41840D01*
Y39410D01*
X729044Y39380D01*
X728944Y39240D01*
X728924Y39200D01*
X728909Y39165D01*
X728889Y39125D01*
X728874Y39085D01*
X728864Y39045D01*
X728849Y39000D01*
X728844Y38960D01*
X728834Y38920D01*
X728829Y38875D01*
Y38835D01*
X728824Y38790D01*
X728829Y38745D01*
Y38705D01*
X728834Y38660D01*
X728844Y38620D01*
X728849Y38580D01*
X728864Y38535D01*
X728874Y38495D01*
X728889Y38455D01*
X728909Y38415D01*
X728924Y38380D01*
X728944Y38340D01*
X729044Y38200D01*
X729074Y38170D01*
Y36040D01*
X729084Y35915D01*
X729124Y35790D01*
X729184Y35680D01*
X729264Y35580D01*
X729364Y35500D01*
X729474Y35440D01*
X729599Y35400D01*
X729724Y35390D01*
G37*
G36*
G01X753346D02*
X753471Y35400D01*
X753596Y35440D01*
X753706Y35500D01*
X753806Y35580D01*
X753886Y35680D01*
X753946Y35790D01*
X753986Y35915D01*
X753996Y36040D01*
Y38165D01*
X754026Y38195D01*
X754051Y38230D01*
X754081Y38265D01*
X754101Y38300D01*
X754126Y38335D01*
X754166Y38415D01*
X754211Y38535D01*
X754221Y38575D01*
X754231Y38620D01*
X754236Y38660D01*
X754246Y38705D01*
Y38875D01*
X754236Y38920D01*
X754231Y38960D01*
X754221Y39005D01*
X754211Y39045D01*
X754166Y39165D01*
X754126Y39245D01*
X754101Y39280D01*
X754081Y39315D01*
X754051Y39350D01*
X754026Y39385D01*
X753996Y39415D01*
Y41840D01*
X753986Y41965D01*
X753946Y42090D01*
X753886Y42200D01*
X753806Y42300D01*
X753706Y42380D01*
X753596Y42440D01*
X753471Y42480D01*
X753346Y42490D01*
X753221Y42480D01*
X753096Y42440D01*
X752986Y42380D01*
X752886Y42300D01*
X752806Y42200D01*
X752746Y42090D01*
X752706Y41965D01*
X752696Y41840D01*
Y39410D01*
X752666Y39380D01*
X752566Y39240D01*
X752546Y39200D01*
X752531Y39165D01*
X752511Y39125D01*
X752496Y39085D01*
X752486Y39045D01*
X752471Y39000D01*
X752466Y38960D01*
X752456Y38920D01*
X752451Y38875D01*
Y38835D01*
X752446Y38790D01*
X752451Y38745D01*
Y38705D01*
X752456Y38660D01*
X752466Y38620D01*
X752471Y38580D01*
X752486Y38535D01*
X752496Y38495D01*
X752511Y38455D01*
X752531Y38415D01*
X752546Y38380D01*
X752566Y38340D01*
X752666Y38200D01*
X752696Y38170D01*
Y36040D01*
X752706Y35915D01*
X752746Y35790D01*
X752806Y35680D01*
X752886Y35580D01*
X752986Y35500D01*
X753096Y35440D01*
X753221Y35400D01*
X753346Y35390D01*
G37*
G36*
G01X748622D02*
X748747Y35400D01*
X748872Y35440D01*
X748982Y35500D01*
X749082Y35580D01*
X749162Y35680D01*
X749222Y35790D01*
X749262Y35915D01*
X749272Y36040D01*
Y38165D01*
X749302Y38195D01*
X749327Y38230D01*
X749357Y38265D01*
X749377Y38300D01*
X749402Y38335D01*
X749442Y38415D01*
X749487Y38535D01*
X749497Y38575D01*
X749507Y38620D01*
X749512Y38660D01*
X749522Y38705D01*
Y38875D01*
X749512Y38920D01*
X749507Y38960D01*
X749497Y39005D01*
X749487Y39045D01*
X749442Y39165D01*
X749402Y39245D01*
X749377Y39280D01*
X749357Y39315D01*
X749327Y39350D01*
X749302Y39385D01*
X749272Y39415D01*
Y41840D01*
X749262Y41965D01*
X749222Y42090D01*
X749162Y42200D01*
X749082Y42300D01*
X748982Y42380D01*
X748872Y42440D01*
X748747Y42480D01*
X748622Y42490D01*
X748497Y42480D01*
X748372Y42440D01*
X748262Y42380D01*
X748162Y42300D01*
X748082Y42200D01*
X748022Y42090D01*
X747982Y41965D01*
X747972Y41840D01*
Y39410D01*
X747942Y39380D01*
X747842Y39240D01*
X747822Y39200D01*
X747807Y39165D01*
X747787Y39125D01*
X747772Y39085D01*
X747762Y39045D01*
X747747Y39000D01*
X747742Y38960D01*
X747732Y38920D01*
X747727Y38875D01*
Y38835D01*
X747722Y38790D01*
X747727Y38745D01*
Y38705D01*
X747732Y38660D01*
X747742Y38620D01*
X747747Y38580D01*
X747762Y38535D01*
X747772Y38495D01*
X747787Y38455D01*
X747807Y38415D01*
X747822Y38380D01*
X747842Y38340D01*
X747942Y38200D01*
X747972Y38170D01*
Y36040D01*
X747982Y35915D01*
X748022Y35790D01*
X748082Y35680D01*
X748162Y35580D01*
X748262Y35500D01*
X748372Y35440D01*
X748497Y35400D01*
X748622Y35390D01*
G37*
G36*
G01X743897D02*
X744022Y35400D01*
X744147Y35440D01*
X744257Y35500D01*
X744357Y35580D01*
X744437Y35680D01*
X744497Y35790D01*
X744537Y35915D01*
X744547Y36040D01*
Y38165D01*
X744577Y38195D01*
X744602Y38230D01*
X744632Y38265D01*
X744652Y38300D01*
X744677Y38335D01*
X744717Y38415D01*
X744762Y38535D01*
X744772Y38575D01*
X744782Y38620D01*
X744787Y38660D01*
X744797Y38705D01*
Y38875D01*
X744787Y38920D01*
X744782Y38960D01*
X744772Y39005D01*
X744762Y39045D01*
X744717Y39165D01*
X744677Y39245D01*
X744652Y39280D01*
X744632Y39315D01*
X744602Y39350D01*
X744577Y39385D01*
X744547Y39415D01*
Y41840D01*
X744537Y41965D01*
X744497Y42090D01*
X744437Y42200D01*
X744357Y42300D01*
X744257Y42380D01*
X744147Y42440D01*
X744022Y42480D01*
X743897Y42490D01*
X743772Y42480D01*
X743647Y42440D01*
X743537Y42380D01*
X743437Y42300D01*
X743357Y42200D01*
X743297Y42090D01*
X743257Y41965D01*
X743247Y41840D01*
Y39410D01*
X743217Y39380D01*
X743117Y39240D01*
X743097Y39200D01*
X743082Y39165D01*
X743062Y39125D01*
X743047Y39085D01*
X743037Y39045D01*
X743022Y39000D01*
X743017Y38960D01*
X743007Y38920D01*
X743002Y38875D01*
Y38835D01*
X742997Y38790D01*
X743002Y38745D01*
Y38705D01*
X743007Y38660D01*
X743017Y38620D01*
X743022Y38580D01*
X743037Y38535D01*
X743047Y38495D01*
X743062Y38455D01*
X743082Y38415D01*
X743097Y38380D01*
X743117Y38340D01*
X743217Y38200D01*
X743247Y38170D01*
Y36040D01*
X743257Y35915D01*
X743297Y35790D01*
X743357Y35680D01*
X743437Y35580D01*
X743537Y35500D01*
X743647Y35440D01*
X743772Y35400D01*
X743897Y35390D01*
G37*
G54D69*
X350197Y231103D03*
G54D96*
X782046Y280709D03*
G54D78*
X404750Y254500D03*
G36*
G01X510039Y35390D02*
X510164Y35400D01*
X510289Y35440D01*
X510399Y35500D01*
X510499Y35580D01*
X510579Y35680D01*
X510639Y35790D01*
X510679Y35915D01*
X510689Y36040D01*
Y37170D01*
X510719Y37200D01*
X510819Y37340D01*
X510839Y37380D01*
X510854Y37415D01*
X510874Y37455D01*
X510889Y37495D01*
X510899Y37535D01*
X510914Y37580D01*
X510919Y37620D01*
X510929Y37660D01*
X510934Y37705D01*
Y37745D01*
X510939Y37790D01*
X510934Y37835D01*
Y37875D01*
X510929Y37920D01*
X510919Y37960D01*
X510914Y38000D01*
X510899Y38045D01*
X510889Y38085D01*
X510874Y38125D01*
X510854Y38165D01*
X510839Y38200D01*
X510819Y38240D01*
X510719Y38380D01*
X510689Y38410D01*
Y41840D01*
X510679Y41965D01*
X510639Y42090D01*
X510579Y42200D01*
X510499Y42300D01*
X510399Y42380D01*
X510289Y42440D01*
X510164Y42480D01*
X510039Y42490D01*
X509914Y42480D01*
X509789Y42440D01*
X509679Y42380D01*
X509579Y42300D01*
X509499Y42200D01*
X509439Y42090D01*
X509399Y41965D01*
X509389Y41840D01*
Y38410D01*
X509359Y38380D01*
X509259Y38240D01*
X509239Y38200D01*
X509224Y38165D01*
X509204Y38125D01*
X509189Y38085D01*
X509179Y38045D01*
X509164Y38000D01*
X509159Y37960D01*
X509149Y37920D01*
X509144Y37875D01*
Y37835D01*
X509139Y37790D01*
X509144Y37745D01*
Y37705D01*
X509149Y37660D01*
X509159Y37620D01*
X509164Y37580D01*
X509179Y37535D01*
X509189Y37495D01*
X509204Y37455D01*
X509224Y37415D01*
X509239Y37380D01*
X509259Y37340D01*
X509359Y37200D01*
X509389Y37170D01*
Y36040D01*
X509399Y35915D01*
X509439Y35790D01*
X509499Y35680D01*
X509579Y35580D01*
X509679Y35500D01*
X509789Y35440D01*
X509914Y35400D01*
X510039Y35390D01*
G37*
G36*
G01X505315D02*
X505440Y35400D01*
X505565Y35440D01*
X505675Y35500D01*
X505775Y35580D01*
X505855Y35680D01*
X505915Y35790D01*
X505955Y35915D01*
X505965Y36040D01*
Y37170D01*
X505995Y37200D01*
X506095Y37340D01*
X506115Y37380D01*
X506130Y37415D01*
X506150Y37455D01*
X506165Y37495D01*
X506175Y37535D01*
X506190Y37580D01*
X506195Y37620D01*
X506205Y37660D01*
X506210Y37705D01*
Y37745D01*
X506215Y37790D01*
X506210Y37835D01*
Y37875D01*
X506205Y37920D01*
X506195Y37960D01*
X506190Y38000D01*
X506175Y38045D01*
X506165Y38085D01*
X506150Y38125D01*
X506130Y38165D01*
X506115Y38200D01*
X506095Y38240D01*
X505995Y38380D01*
X505965Y38410D01*
Y41840D01*
X505955Y41965D01*
X505915Y42090D01*
X505855Y42200D01*
X505775Y42300D01*
X505675Y42380D01*
X505565Y42440D01*
X505440Y42480D01*
X505315Y42490D01*
X505190Y42480D01*
X505065Y42440D01*
X504955Y42380D01*
X504855Y42300D01*
X504775Y42200D01*
X504715Y42090D01*
X504675Y41965D01*
X504665Y41840D01*
Y38410D01*
X504635Y38380D01*
X504535Y38240D01*
X504515Y38200D01*
X504500Y38165D01*
X504480Y38125D01*
X504465Y38085D01*
X504455Y38045D01*
X504440Y38000D01*
X504435Y37960D01*
X504425Y37920D01*
X504420Y37875D01*
Y37835D01*
X504415Y37790D01*
X504420Y37745D01*
Y37705D01*
X504425Y37660D01*
X504435Y37620D01*
X504440Y37580D01*
X504455Y37535D01*
X504465Y37495D01*
X504480Y37455D01*
X504500Y37415D01*
X504515Y37380D01*
X504535Y37340D01*
X504635Y37200D01*
X504665Y37170D01*
Y36040D01*
X504675Y35915D01*
X504715Y35790D01*
X504775Y35680D01*
X504855Y35580D01*
X504955Y35500D01*
X505065Y35440D01*
X505190Y35400D01*
X505315Y35390D01*
G37*
G36*
G01X524212D02*
X524337Y35400D01*
X524462Y35440D01*
X524572Y35500D01*
X524672Y35580D01*
X524752Y35680D01*
X524812Y35790D01*
X524852Y35915D01*
X524862Y36040D01*
Y37170D01*
X524892Y37200D01*
X524992Y37340D01*
X525012Y37380D01*
X525027Y37415D01*
X525047Y37455D01*
X525062Y37495D01*
X525072Y37535D01*
X525087Y37580D01*
X525092Y37620D01*
X525102Y37660D01*
X525107Y37705D01*
Y37745D01*
X525112Y37790D01*
X525107Y37835D01*
Y37875D01*
X525102Y37920D01*
X525092Y37960D01*
X525087Y38000D01*
X525072Y38045D01*
X525062Y38085D01*
X525047Y38125D01*
X525027Y38165D01*
X525012Y38200D01*
X524992Y38240D01*
X524892Y38380D01*
X524862Y38410D01*
Y41840D01*
X524852Y41965D01*
X524812Y42090D01*
X524752Y42200D01*
X524672Y42300D01*
X524572Y42380D01*
X524462Y42440D01*
X524337Y42480D01*
X524212Y42490D01*
X524087Y42480D01*
X523962Y42440D01*
X523852Y42380D01*
X523752Y42300D01*
X523672Y42200D01*
X523612Y42090D01*
X523572Y41965D01*
X523562Y41840D01*
Y38410D01*
X523532Y38380D01*
X523432Y38240D01*
X523412Y38200D01*
X523397Y38165D01*
X523377Y38125D01*
X523362Y38085D01*
X523352Y38045D01*
X523337Y38000D01*
X523332Y37960D01*
X523322Y37920D01*
X523317Y37875D01*
Y37835D01*
X523312Y37790D01*
X523317Y37745D01*
Y37705D01*
X523322Y37660D01*
X523332Y37620D01*
X523337Y37580D01*
X523352Y37535D01*
X523362Y37495D01*
X523377Y37455D01*
X523397Y37415D01*
X523412Y37380D01*
X523432Y37340D01*
X523532Y37200D01*
X523562Y37170D01*
Y36040D01*
X523572Y35915D01*
X523612Y35790D01*
X523672Y35680D01*
X523752Y35580D01*
X523852Y35500D01*
X523962Y35440D01*
X524087Y35400D01*
X524212Y35390D01*
G37*
G36*
G01X519488D02*
X519613Y35400D01*
X519738Y35440D01*
X519848Y35500D01*
X519948Y35580D01*
X520028Y35680D01*
X520088Y35790D01*
X520128Y35915D01*
X520138Y36040D01*
Y37170D01*
X520168Y37200D01*
X520268Y37340D01*
X520288Y37380D01*
X520303Y37415D01*
X520323Y37455D01*
X520338Y37495D01*
X520348Y37535D01*
X520363Y37580D01*
X520368Y37620D01*
X520378Y37660D01*
X520383Y37705D01*
Y37745D01*
X520388Y37790D01*
X520383Y37835D01*
Y37875D01*
X520378Y37920D01*
X520368Y37960D01*
X520363Y38000D01*
X520348Y38045D01*
X520338Y38085D01*
X520323Y38125D01*
X520303Y38165D01*
X520288Y38200D01*
X520268Y38240D01*
X520168Y38380D01*
X520138Y38410D01*
Y41840D01*
X520128Y41965D01*
X520088Y42090D01*
X520028Y42200D01*
X519948Y42300D01*
X519848Y42380D01*
X519738Y42440D01*
X519613Y42480D01*
X519488Y42490D01*
X519363Y42480D01*
X519238Y42440D01*
X519128Y42380D01*
X519028Y42300D01*
X518948Y42200D01*
X518888Y42090D01*
X518848Y41965D01*
X518838Y41840D01*
Y38410D01*
X518808Y38380D01*
X518708Y38240D01*
X518688Y38200D01*
X518673Y38165D01*
X518653Y38125D01*
X518638Y38085D01*
X518628Y38045D01*
X518613Y38000D01*
X518608Y37960D01*
X518598Y37920D01*
X518593Y37875D01*
Y37835D01*
X518588Y37790D01*
X518593Y37745D01*
Y37705D01*
X518598Y37660D01*
X518608Y37620D01*
X518613Y37580D01*
X518628Y37535D01*
X518638Y37495D01*
X518653Y37455D01*
X518673Y37415D01*
X518688Y37380D01*
X518708Y37340D01*
X518808Y37200D01*
X518838Y37170D01*
Y36040D01*
X518848Y35915D01*
X518888Y35790D01*
X518948Y35680D01*
X519028Y35580D01*
X519128Y35500D01*
X519238Y35440D01*
X519363Y35400D01*
X519488Y35390D01*
G37*
G36*
G01X514764D02*
X514889Y35400D01*
X515014Y35440D01*
X515124Y35500D01*
X515224Y35580D01*
X515304Y35680D01*
X515364Y35790D01*
X515404Y35915D01*
X515414Y36040D01*
Y37170D01*
X515444Y37200D01*
X515544Y37340D01*
X515564Y37380D01*
X515579Y37415D01*
X515599Y37455D01*
X515614Y37495D01*
X515624Y37535D01*
X515639Y37580D01*
X515644Y37620D01*
X515654Y37660D01*
X515659Y37705D01*
Y37745D01*
X515664Y37790D01*
X515659Y37835D01*
Y37875D01*
X515654Y37920D01*
X515644Y37960D01*
X515639Y38000D01*
X515624Y38045D01*
X515614Y38085D01*
X515599Y38125D01*
X515579Y38165D01*
X515564Y38200D01*
X515544Y38240D01*
X515444Y38380D01*
X515414Y38410D01*
Y41840D01*
X515404Y41965D01*
X515364Y42090D01*
X515304Y42200D01*
X515224Y42300D01*
X515124Y42380D01*
X515014Y42440D01*
X514889Y42480D01*
X514764Y42490D01*
X514639Y42480D01*
X514514Y42440D01*
X514404Y42380D01*
X514304Y42300D01*
X514224Y42200D01*
X514164Y42090D01*
X514124Y41965D01*
X514114Y41840D01*
Y38410D01*
X514084Y38380D01*
X513984Y38240D01*
X513964Y38200D01*
X513949Y38165D01*
X513929Y38125D01*
X513914Y38085D01*
X513904Y38045D01*
X513889Y38000D01*
X513884Y37960D01*
X513874Y37920D01*
X513869Y37875D01*
Y37835D01*
X513864Y37790D01*
X513869Y37745D01*
Y37705D01*
X513874Y37660D01*
X513884Y37620D01*
X513889Y37580D01*
X513904Y37535D01*
X513914Y37495D01*
X513929Y37455D01*
X513949Y37415D01*
X513964Y37380D01*
X513984Y37340D01*
X514084Y37200D01*
X514114Y37170D01*
Y36040D01*
X514124Y35915D01*
X514164Y35790D01*
X514224Y35680D01*
X514304Y35580D01*
X514404Y35500D01*
X514514Y35440D01*
X514639Y35400D01*
X514764Y35390D01*
G37*
G36*
G01X538386D02*
X538511Y35400D01*
X538636Y35440D01*
X538746Y35500D01*
X538846Y35580D01*
X538926Y35680D01*
X538986Y35790D01*
X539026Y35915D01*
X539036Y36040D01*
Y37170D01*
X539066Y37200D01*
X539166Y37340D01*
X539186Y37380D01*
X539201Y37415D01*
X539221Y37455D01*
X539236Y37495D01*
X539246Y37535D01*
X539261Y37580D01*
X539266Y37620D01*
X539276Y37660D01*
X539281Y37705D01*
Y37745D01*
X539286Y37790D01*
X539281Y37835D01*
Y37875D01*
X539276Y37920D01*
X539266Y37960D01*
X539261Y38000D01*
X539246Y38045D01*
X539236Y38085D01*
X539221Y38125D01*
X539201Y38165D01*
X539186Y38200D01*
X539166Y38240D01*
X539066Y38380D01*
X539036Y38410D01*
Y41840D01*
X539026Y41965D01*
X538986Y42090D01*
X538926Y42200D01*
X538846Y42300D01*
X538746Y42380D01*
X538636Y42440D01*
X538511Y42480D01*
X538386Y42490D01*
X538261Y42480D01*
X538136Y42440D01*
X538026Y42380D01*
X537926Y42300D01*
X537846Y42200D01*
X537786Y42090D01*
X537746Y41965D01*
X537736Y41840D01*
Y38410D01*
X537706Y38380D01*
X537606Y38240D01*
X537586Y38200D01*
X537571Y38165D01*
X537551Y38125D01*
X537536Y38085D01*
X537526Y38045D01*
X537511Y38000D01*
X537506Y37960D01*
X537496Y37920D01*
X537491Y37875D01*
Y37835D01*
X537486Y37790D01*
X537491Y37745D01*
Y37705D01*
X537496Y37660D01*
X537506Y37620D01*
X537511Y37580D01*
X537526Y37535D01*
X537536Y37495D01*
X537551Y37455D01*
X537571Y37415D01*
X537586Y37380D01*
X537606Y37340D01*
X537706Y37200D01*
X537736Y37170D01*
Y36040D01*
X537746Y35915D01*
X537786Y35790D01*
X537846Y35680D01*
X537926Y35580D01*
X538026Y35500D01*
X538136Y35440D01*
X538261Y35400D01*
X538386Y35390D01*
G37*
G36*
G01X533661D02*
X533786Y35400D01*
X533911Y35440D01*
X534021Y35500D01*
X534121Y35580D01*
X534201Y35680D01*
X534261Y35790D01*
X534301Y35915D01*
X534311Y36040D01*
Y37170D01*
X534341Y37200D01*
X534441Y37340D01*
X534461Y37380D01*
X534476Y37415D01*
X534496Y37455D01*
X534511Y37495D01*
X534521Y37535D01*
X534536Y37580D01*
X534541Y37620D01*
X534551Y37660D01*
X534556Y37705D01*
Y37745D01*
X534561Y37790D01*
X534556Y37835D01*
Y37875D01*
X534551Y37920D01*
X534541Y37960D01*
X534536Y38000D01*
X534521Y38045D01*
X534511Y38085D01*
X534496Y38125D01*
X534476Y38165D01*
X534461Y38200D01*
X534441Y38240D01*
X534341Y38380D01*
X534311Y38410D01*
Y41840D01*
X534301Y41965D01*
X534261Y42090D01*
X534201Y42200D01*
X534121Y42300D01*
X534021Y42380D01*
X533911Y42440D01*
X533786Y42480D01*
X533661Y42490D01*
X533536Y42480D01*
X533411Y42440D01*
X533301Y42380D01*
X533201Y42300D01*
X533121Y42200D01*
X533061Y42090D01*
X533021Y41965D01*
X533011Y41840D01*
Y38410D01*
X532981Y38380D01*
X532881Y38240D01*
X532861Y38200D01*
X532846Y38165D01*
X532826Y38125D01*
X532811Y38085D01*
X532801Y38045D01*
X532786Y38000D01*
X532781Y37960D01*
X532771Y37920D01*
X532766Y37875D01*
Y37835D01*
X532761Y37790D01*
X532766Y37745D01*
Y37705D01*
X532771Y37660D01*
X532781Y37620D01*
X532786Y37580D01*
X532801Y37535D01*
X532811Y37495D01*
X532826Y37455D01*
X532846Y37415D01*
X532861Y37380D01*
X532881Y37340D01*
X532981Y37200D01*
X533011Y37170D01*
Y36040D01*
X533021Y35915D01*
X533061Y35790D01*
X533121Y35680D01*
X533201Y35580D01*
X533301Y35500D01*
X533411Y35440D01*
X533536Y35400D01*
X533661Y35390D01*
G37*
G36*
G01X528937D02*
X529062Y35400D01*
X529187Y35440D01*
X529297Y35500D01*
X529397Y35580D01*
X529477Y35680D01*
X529537Y35790D01*
X529577Y35915D01*
X529587Y36040D01*
Y37170D01*
X529617Y37200D01*
X529717Y37340D01*
X529737Y37380D01*
X529752Y37415D01*
X529772Y37455D01*
X529787Y37495D01*
X529797Y37535D01*
X529812Y37580D01*
X529817Y37620D01*
X529827Y37660D01*
X529832Y37705D01*
Y37745D01*
X529837Y37790D01*
X529832Y37835D01*
Y37875D01*
X529827Y37920D01*
X529817Y37960D01*
X529812Y38000D01*
X529797Y38045D01*
X529787Y38085D01*
X529772Y38125D01*
X529752Y38165D01*
X529737Y38200D01*
X529717Y38240D01*
X529617Y38380D01*
X529587Y38410D01*
Y41840D01*
X529577Y41965D01*
X529537Y42090D01*
X529477Y42200D01*
X529397Y42300D01*
X529297Y42380D01*
X529187Y42440D01*
X529062Y42480D01*
X528937Y42490D01*
X528812Y42480D01*
X528687Y42440D01*
X528577Y42380D01*
X528477Y42300D01*
X528397Y42200D01*
X528337Y42090D01*
X528297Y41965D01*
X528287Y41840D01*
Y38410D01*
X528257Y38380D01*
X528157Y38240D01*
X528137Y38200D01*
X528122Y38165D01*
X528102Y38125D01*
X528087Y38085D01*
X528077Y38045D01*
X528062Y38000D01*
X528057Y37960D01*
X528047Y37920D01*
X528042Y37875D01*
Y37835D01*
X528037Y37790D01*
X528042Y37745D01*
Y37705D01*
X528047Y37660D01*
X528057Y37620D01*
X528062Y37580D01*
X528077Y37535D01*
X528087Y37495D01*
X528102Y37455D01*
X528122Y37415D01*
X528137Y37380D01*
X528157Y37340D01*
X528257Y37200D01*
X528287Y37170D01*
Y36040D01*
X528297Y35915D01*
X528337Y35790D01*
X528397Y35680D01*
X528477Y35580D01*
X528577Y35500D01*
X528687Y35440D01*
X528812Y35400D01*
X528937Y35390D01*
G37*
G36*
G01X557283D02*
X557408Y35400D01*
X557533Y35440D01*
X557643Y35500D01*
X557743Y35580D01*
X557823Y35680D01*
X557883Y35790D01*
X557923Y35915D01*
X557933Y36040D01*
Y37170D01*
X557963Y37200D01*
X558063Y37340D01*
X558083Y37380D01*
X558098Y37415D01*
X558118Y37455D01*
X558133Y37495D01*
X558143Y37535D01*
X558158Y37580D01*
X558163Y37620D01*
X558173Y37660D01*
X558178Y37705D01*
Y37745D01*
X558183Y37790D01*
X558178Y37835D01*
Y37875D01*
X558173Y37920D01*
X558163Y37960D01*
X558158Y38000D01*
X558143Y38045D01*
X558133Y38085D01*
X558118Y38125D01*
X558098Y38165D01*
X558083Y38200D01*
X558063Y38240D01*
X557963Y38380D01*
X557933Y38410D01*
Y41840D01*
X557923Y41965D01*
X557883Y42090D01*
X557823Y42200D01*
X557743Y42300D01*
X557643Y42380D01*
X557533Y42440D01*
X557408Y42480D01*
X557283Y42490D01*
X557158Y42480D01*
X557033Y42440D01*
X556923Y42380D01*
X556823Y42300D01*
X556743Y42200D01*
X556683Y42090D01*
X556643Y41965D01*
X556633Y41840D01*
Y38410D01*
X556603Y38380D01*
X556503Y38240D01*
X556483Y38200D01*
X556468Y38165D01*
X556448Y38125D01*
X556433Y38085D01*
X556423Y38045D01*
X556408Y38000D01*
X556403Y37960D01*
X556393Y37920D01*
X556388Y37875D01*
Y37835D01*
X556383Y37790D01*
X556388Y37745D01*
Y37705D01*
X556393Y37660D01*
X556403Y37620D01*
X556408Y37580D01*
X556423Y37535D01*
X556433Y37495D01*
X556448Y37455D01*
X556468Y37415D01*
X556483Y37380D01*
X556503Y37340D01*
X556603Y37200D01*
X556633Y37170D01*
Y36040D01*
X556643Y35915D01*
X556683Y35790D01*
X556743Y35680D01*
X556823Y35580D01*
X556923Y35500D01*
X557033Y35440D01*
X557158Y35400D01*
X557283Y35390D01*
G37*
G36*
G01X552559D02*
X552684Y35400D01*
X552809Y35440D01*
X552919Y35500D01*
X553019Y35580D01*
X553099Y35680D01*
X553159Y35790D01*
X553199Y35915D01*
X553209Y36040D01*
Y37170D01*
X553239Y37200D01*
X553339Y37340D01*
X553359Y37380D01*
X553374Y37415D01*
X553394Y37455D01*
X553409Y37495D01*
X553419Y37535D01*
X553434Y37580D01*
X553439Y37620D01*
X553449Y37660D01*
X553454Y37705D01*
Y37745D01*
X553459Y37790D01*
X553454Y37835D01*
Y37875D01*
X553449Y37920D01*
X553439Y37960D01*
X553434Y38000D01*
X553419Y38045D01*
X553409Y38085D01*
X553394Y38125D01*
X553374Y38165D01*
X553359Y38200D01*
X553339Y38240D01*
X553239Y38380D01*
X553209Y38410D01*
Y41840D01*
X553199Y41965D01*
X553159Y42090D01*
X553099Y42200D01*
X553019Y42300D01*
X552919Y42380D01*
X552809Y42440D01*
X552684Y42480D01*
X552559Y42490D01*
X552434Y42480D01*
X552309Y42440D01*
X552199Y42380D01*
X552099Y42300D01*
X552019Y42200D01*
X551959Y42090D01*
X551919Y41965D01*
X551909Y41840D01*
Y38410D01*
X551879Y38380D01*
X551779Y38240D01*
X551759Y38200D01*
X551744Y38165D01*
X551724Y38125D01*
X551709Y38085D01*
X551699Y38045D01*
X551684Y38000D01*
X551679Y37960D01*
X551669Y37920D01*
X551664Y37875D01*
Y37835D01*
X551659Y37790D01*
X551664Y37745D01*
Y37705D01*
X551669Y37660D01*
X551679Y37620D01*
X551684Y37580D01*
X551699Y37535D01*
X551709Y37495D01*
X551724Y37455D01*
X551744Y37415D01*
X551759Y37380D01*
X551779Y37340D01*
X551879Y37200D01*
X551909Y37170D01*
Y36040D01*
X551919Y35915D01*
X551959Y35790D01*
X552019Y35680D01*
X552099Y35580D01*
X552199Y35500D01*
X552309Y35440D01*
X552434Y35400D01*
X552559Y35390D01*
G37*
G36*
G01X547834D02*
X547959Y35400D01*
X548084Y35440D01*
X548194Y35500D01*
X548294Y35580D01*
X548374Y35680D01*
X548434Y35790D01*
X548474Y35915D01*
X548484Y36040D01*
Y37170D01*
X548514Y37200D01*
X548614Y37340D01*
X548634Y37380D01*
X548649Y37415D01*
X548669Y37455D01*
X548684Y37495D01*
X548694Y37535D01*
X548709Y37580D01*
X548714Y37620D01*
X548724Y37660D01*
X548729Y37705D01*
Y37745D01*
X548734Y37790D01*
X548729Y37835D01*
Y37875D01*
X548724Y37920D01*
X548714Y37960D01*
X548709Y38000D01*
X548694Y38045D01*
X548684Y38085D01*
X548669Y38125D01*
X548649Y38165D01*
X548634Y38200D01*
X548614Y38240D01*
X548514Y38380D01*
X548484Y38410D01*
Y41840D01*
X548474Y41965D01*
X548434Y42090D01*
X548374Y42200D01*
X548294Y42300D01*
X548194Y42380D01*
X548084Y42440D01*
X547959Y42480D01*
X547834Y42490D01*
X547709Y42480D01*
X547584Y42440D01*
X547474Y42380D01*
X547374Y42300D01*
X547294Y42200D01*
X547234Y42090D01*
X547194Y41965D01*
X547184Y41840D01*
Y38410D01*
X547154Y38380D01*
X547054Y38240D01*
X547034Y38200D01*
X547019Y38165D01*
X546999Y38125D01*
X546984Y38085D01*
X546974Y38045D01*
X546959Y38000D01*
X546954Y37960D01*
X546944Y37920D01*
X546939Y37875D01*
Y37835D01*
X546934Y37790D01*
X546939Y37745D01*
Y37705D01*
X546944Y37660D01*
X546954Y37620D01*
X546959Y37580D01*
X546974Y37535D01*
X546984Y37495D01*
X546999Y37455D01*
X547019Y37415D01*
X547034Y37380D01*
X547054Y37340D01*
X547154Y37200D01*
X547184Y37170D01*
Y36040D01*
X547194Y35915D01*
X547234Y35790D01*
X547294Y35680D01*
X547374Y35580D01*
X547474Y35500D01*
X547584Y35440D01*
X547709Y35400D01*
X547834Y35390D01*
G37*
G36*
G01X543110D02*
X543235Y35400D01*
X543360Y35440D01*
X543470Y35500D01*
X543570Y35580D01*
X543650Y35680D01*
X543710Y35790D01*
X543750Y35915D01*
X543760Y36040D01*
Y37170D01*
X543790Y37200D01*
X543890Y37340D01*
X543910Y37380D01*
X543925Y37415D01*
X543945Y37455D01*
X543960Y37495D01*
X543970Y37535D01*
X543985Y37580D01*
X543990Y37620D01*
X544000Y37660D01*
X544005Y37705D01*
Y37745D01*
X544010Y37790D01*
X544005Y37835D01*
Y37875D01*
X544000Y37920D01*
X543990Y37960D01*
X543985Y38000D01*
X543970Y38045D01*
X543960Y38085D01*
X543945Y38125D01*
X543925Y38165D01*
X543910Y38200D01*
X543890Y38240D01*
X543790Y38380D01*
X543760Y38410D01*
Y41840D01*
X543750Y41965D01*
X543710Y42090D01*
X543650Y42200D01*
X543570Y42300D01*
X543470Y42380D01*
X543360Y42440D01*
X543235Y42480D01*
X543110Y42490D01*
X542985Y42480D01*
X542860Y42440D01*
X542750Y42380D01*
X542650Y42300D01*
X542570Y42200D01*
X542510Y42090D01*
X542470Y41965D01*
X542460Y41840D01*
Y38410D01*
X542430Y38380D01*
X542330Y38240D01*
X542310Y38200D01*
X542295Y38165D01*
X542275Y38125D01*
X542260Y38085D01*
X542250Y38045D01*
X542235Y38000D01*
X542230Y37960D01*
X542220Y37920D01*
X542215Y37875D01*
Y37835D01*
X542210Y37790D01*
X542215Y37745D01*
Y37705D01*
X542220Y37660D01*
X542230Y37620D01*
X542235Y37580D01*
X542250Y37535D01*
X542260Y37495D01*
X542275Y37455D01*
X542295Y37415D01*
X542310Y37380D01*
X542330Y37340D01*
X542430Y37200D01*
X542460Y37170D01*
Y36040D01*
X542470Y35915D01*
X542510Y35790D01*
X542570Y35680D01*
X542650Y35580D01*
X542750Y35500D01*
X542860Y35440D01*
X542985Y35400D01*
X543110Y35390D01*
G37*
G36*
G01X571456D02*
X571581Y35400D01*
X571706Y35440D01*
X571816Y35500D01*
X571916Y35580D01*
X571996Y35680D01*
X572056Y35790D01*
X572096Y35915D01*
X572106Y36040D01*
Y37170D01*
X572136Y37200D01*
X572236Y37340D01*
X572256Y37380D01*
X572271Y37415D01*
X572291Y37455D01*
X572306Y37495D01*
X572316Y37535D01*
X572331Y37580D01*
X572336Y37620D01*
X572346Y37660D01*
X572351Y37705D01*
Y37745D01*
X572356Y37790D01*
X572351Y37835D01*
Y37875D01*
X572346Y37920D01*
X572336Y37960D01*
X572331Y38000D01*
X572316Y38045D01*
X572306Y38085D01*
X572291Y38125D01*
X572271Y38165D01*
X572256Y38200D01*
X572236Y38240D01*
X572136Y38380D01*
X572106Y38410D01*
Y41840D01*
X572096Y41965D01*
X572056Y42090D01*
X571996Y42200D01*
X571916Y42300D01*
X571816Y42380D01*
X571706Y42440D01*
X571581Y42480D01*
X571456Y42490D01*
X571331Y42480D01*
X571206Y42440D01*
X571096Y42380D01*
X570996Y42300D01*
X570916Y42200D01*
X570856Y42090D01*
X570816Y41965D01*
X570806Y41840D01*
Y38410D01*
X570776Y38380D01*
X570676Y38240D01*
X570656Y38200D01*
X570641Y38165D01*
X570621Y38125D01*
X570606Y38085D01*
X570596Y38045D01*
X570581Y38000D01*
X570576Y37960D01*
X570566Y37920D01*
X570561Y37875D01*
Y37835D01*
X570556Y37790D01*
X570561Y37745D01*
Y37705D01*
X570566Y37660D01*
X570576Y37620D01*
X570581Y37580D01*
X570596Y37535D01*
X570606Y37495D01*
X570621Y37455D01*
X570641Y37415D01*
X570656Y37380D01*
X570676Y37340D01*
X570776Y37200D01*
X570806Y37170D01*
Y36040D01*
X570816Y35915D01*
X570856Y35790D01*
X570916Y35680D01*
X570996Y35580D01*
X571096Y35500D01*
X571206Y35440D01*
X571331Y35400D01*
X571456Y35390D01*
G37*
G36*
G01X566732D02*
X566857Y35400D01*
X566982Y35440D01*
X567092Y35500D01*
X567192Y35580D01*
X567272Y35680D01*
X567332Y35790D01*
X567372Y35915D01*
X567382Y36040D01*
Y37170D01*
X567412Y37200D01*
X567512Y37340D01*
X567532Y37380D01*
X567547Y37415D01*
X567567Y37455D01*
X567582Y37495D01*
X567592Y37535D01*
X567607Y37580D01*
X567612Y37620D01*
X567622Y37660D01*
X567627Y37705D01*
Y37745D01*
X567632Y37790D01*
X567627Y37835D01*
Y37875D01*
X567622Y37920D01*
X567612Y37960D01*
X567607Y38000D01*
X567592Y38045D01*
X567582Y38085D01*
X567567Y38125D01*
X567547Y38165D01*
X567532Y38200D01*
X567512Y38240D01*
X567412Y38380D01*
X567382Y38410D01*
Y41840D01*
X567372Y41965D01*
X567332Y42090D01*
X567272Y42200D01*
X567192Y42300D01*
X567092Y42380D01*
X566982Y42440D01*
X566857Y42480D01*
X566732Y42490D01*
X566607Y42480D01*
X566482Y42440D01*
X566372Y42380D01*
X566272Y42300D01*
X566192Y42200D01*
X566132Y42090D01*
X566092Y41965D01*
X566082Y41840D01*
Y38410D01*
X566052Y38380D01*
X565952Y38240D01*
X565932Y38200D01*
X565917Y38165D01*
X565897Y38125D01*
X565882Y38085D01*
X565872Y38045D01*
X565857Y38000D01*
X565852Y37960D01*
X565842Y37920D01*
X565837Y37875D01*
Y37835D01*
X565832Y37790D01*
X565837Y37745D01*
Y37705D01*
X565842Y37660D01*
X565852Y37620D01*
X565857Y37580D01*
X565872Y37535D01*
X565882Y37495D01*
X565897Y37455D01*
X565917Y37415D01*
X565932Y37380D01*
X565952Y37340D01*
X566052Y37200D01*
X566082Y37170D01*
Y36040D01*
X566092Y35915D01*
X566132Y35790D01*
X566192Y35680D01*
X566272Y35580D01*
X566372Y35500D01*
X566482Y35440D01*
X566607Y35400D01*
X566732Y35390D01*
G37*
G36*
G01X562008D02*
X562133Y35400D01*
X562258Y35440D01*
X562368Y35500D01*
X562468Y35580D01*
X562548Y35680D01*
X562608Y35790D01*
X562648Y35915D01*
X562658Y36040D01*
Y37170D01*
X562688Y37200D01*
X562788Y37340D01*
X562808Y37380D01*
X562823Y37415D01*
X562843Y37455D01*
X562858Y37495D01*
X562868Y37535D01*
X562883Y37580D01*
X562888Y37620D01*
X562898Y37660D01*
X562903Y37705D01*
Y37745D01*
X562908Y37790D01*
X562903Y37835D01*
Y37875D01*
X562898Y37920D01*
X562888Y37960D01*
X562883Y38000D01*
X562868Y38045D01*
X562858Y38085D01*
X562843Y38125D01*
X562823Y38165D01*
X562808Y38200D01*
X562788Y38240D01*
X562688Y38380D01*
X562658Y38410D01*
Y41840D01*
X562648Y41965D01*
X562608Y42090D01*
X562548Y42200D01*
X562468Y42300D01*
X562368Y42380D01*
X562258Y42440D01*
X562133Y42480D01*
X562008Y42490D01*
X561883Y42480D01*
X561758Y42440D01*
X561648Y42380D01*
X561548Y42300D01*
X561468Y42200D01*
X561408Y42090D01*
X561368Y41965D01*
X561358Y41840D01*
Y38410D01*
X561328Y38380D01*
X561228Y38240D01*
X561208Y38200D01*
X561193Y38165D01*
X561173Y38125D01*
X561158Y38085D01*
X561148Y38045D01*
X561133Y38000D01*
X561128Y37960D01*
X561118Y37920D01*
X561113Y37875D01*
Y37835D01*
X561108Y37790D01*
X561113Y37745D01*
Y37705D01*
X561118Y37660D01*
X561128Y37620D01*
X561133Y37580D01*
X561148Y37535D01*
X561158Y37495D01*
X561173Y37455D01*
X561193Y37415D01*
X561208Y37380D01*
X561228Y37340D01*
X561328Y37200D01*
X561358Y37170D01*
Y36040D01*
X561368Y35915D01*
X561408Y35790D01*
X561468Y35680D01*
X561548Y35580D01*
X561648Y35500D01*
X561758Y35440D01*
X561883Y35400D01*
X562008Y35390D01*
G37*
G36*
G01X585630D02*
X585755Y35400D01*
X585880Y35440D01*
X585990Y35500D01*
X586090Y35580D01*
X586170Y35680D01*
X586230Y35790D01*
X586270Y35915D01*
X586280Y36040D01*
Y37170D01*
X586310Y37200D01*
X586410Y37340D01*
X586430Y37380D01*
X586445Y37415D01*
X586465Y37455D01*
X586480Y37495D01*
X586490Y37535D01*
X586505Y37580D01*
X586510Y37620D01*
X586520Y37660D01*
X586525Y37705D01*
Y37745D01*
X586530Y37790D01*
X586525Y37835D01*
Y37875D01*
X586520Y37920D01*
X586510Y37960D01*
X586505Y38000D01*
X586490Y38045D01*
X586480Y38085D01*
X586465Y38125D01*
X586445Y38165D01*
X586430Y38200D01*
X586410Y38240D01*
X586310Y38380D01*
X586280Y38410D01*
Y41840D01*
X586270Y41965D01*
X586230Y42090D01*
X586170Y42200D01*
X586090Y42300D01*
X585990Y42380D01*
X585880Y42440D01*
X585755Y42480D01*
X585630Y42490D01*
X585505Y42480D01*
X585380Y42440D01*
X585270Y42380D01*
X585170Y42300D01*
X585090Y42200D01*
X585030Y42090D01*
X584990Y41965D01*
X584980Y41840D01*
Y38410D01*
X584950Y38380D01*
X584850Y38240D01*
X584830Y38200D01*
X584815Y38165D01*
X584795Y38125D01*
X584780Y38085D01*
X584770Y38045D01*
X584755Y38000D01*
X584750Y37960D01*
X584740Y37920D01*
X584735Y37875D01*
Y37835D01*
X584730Y37790D01*
X584735Y37745D01*
Y37705D01*
X584740Y37660D01*
X584750Y37620D01*
X584755Y37580D01*
X584770Y37535D01*
X584780Y37495D01*
X584795Y37455D01*
X584815Y37415D01*
X584830Y37380D01*
X584850Y37340D01*
X584950Y37200D01*
X584980Y37170D01*
Y36040D01*
X584990Y35915D01*
X585030Y35790D01*
X585090Y35680D01*
X585170Y35580D01*
X585270Y35500D01*
X585380Y35440D01*
X585505Y35400D01*
X585630Y35390D01*
G37*
G36*
G01X580905D02*
X581030Y35400D01*
X581155Y35440D01*
X581265Y35500D01*
X581365Y35580D01*
X581445Y35680D01*
X581505Y35790D01*
X581545Y35915D01*
X581555Y36040D01*
Y37170D01*
X581585Y37200D01*
X581685Y37340D01*
X581705Y37380D01*
X581720Y37415D01*
X581740Y37455D01*
X581755Y37495D01*
X581765Y37535D01*
X581780Y37580D01*
X581785Y37620D01*
X581795Y37660D01*
X581800Y37705D01*
Y37745D01*
X581805Y37790D01*
X581800Y37835D01*
Y37875D01*
X581795Y37920D01*
X581785Y37960D01*
X581780Y38000D01*
X581765Y38045D01*
X581755Y38085D01*
X581740Y38125D01*
X581720Y38165D01*
X581705Y38200D01*
X581685Y38240D01*
X581585Y38380D01*
X581555Y38410D01*
Y41840D01*
X581545Y41965D01*
X581505Y42090D01*
X581445Y42200D01*
X581365Y42300D01*
X581265Y42380D01*
X581155Y42440D01*
X581030Y42480D01*
X580905Y42490D01*
X580780Y42480D01*
X580655Y42440D01*
X580545Y42380D01*
X580445Y42300D01*
X580365Y42200D01*
X580305Y42090D01*
X580265Y41965D01*
X580255Y41840D01*
Y38410D01*
X580225Y38380D01*
X580125Y38240D01*
X580105Y38200D01*
X580090Y38165D01*
X580070Y38125D01*
X580055Y38085D01*
X580045Y38045D01*
X580030Y38000D01*
X580025Y37960D01*
X580015Y37920D01*
X580010Y37875D01*
Y37835D01*
X580005Y37790D01*
X580010Y37745D01*
Y37705D01*
X580015Y37660D01*
X580025Y37620D01*
X580030Y37580D01*
X580045Y37535D01*
X580055Y37495D01*
X580070Y37455D01*
X580090Y37415D01*
X580105Y37380D01*
X580125Y37340D01*
X580225Y37200D01*
X580255Y37170D01*
Y36040D01*
X580265Y35915D01*
X580305Y35790D01*
X580365Y35680D01*
X580445Y35580D01*
X580545Y35500D01*
X580655Y35440D01*
X580780Y35400D01*
X580905Y35390D01*
G37*
G36*
G01X576181D02*
X576306Y35400D01*
X576431Y35440D01*
X576541Y35500D01*
X576641Y35580D01*
X576721Y35680D01*
X576781Y35790D01*
X576821Y35915D01*
X576831Y36040D01*
Y37170D01*
X576861Y37200D01*
X576961Y37340D01*
X576981Y37380D01*
X576996Y37415D01*
X577016Y37455D01*
X577031Y37495D01*
X577041Y37535D01*
X577056Y37580D01*
X577061Y37620D01*
X577071Y37660D01*
X577076Y37705D01*
Y37745D01*
X577081Y37790D01*
X577076Y37835D01*
Y37875D01*
X577071Y37920D01*
X577061Y37960D01*
X577056Y38000D01*
X577041Y38045D01*
X577031Y38085D01*
X577016Y38125D01*
X576996Y38165D01*
X576981Y38200D01*
X576961Y38240D01*
X576861Y38380D01*
X576831Y38410D01*
Y41840D01*
X576821Y41965D01*
X576781Y42090D01*
X576721Y42200D01*
X576641Y42300D01*
X576541Y42380D01*
X576431Y42440D01*
X576306Y42480D01*
X576181Y42490D01*
X576056Y42480D01*
X575931Y42440D01*
X575821Y42380D01*
X575721Y42300D01*
X575641Y42200D01*
X575581Y42090D01*
X575541Y41965D01*
X575531Y41840D01*
Y38410D01*
X575501Y38380D01*
X575401Y38240D01*
X575381Y38200D01*
X575366Y38165D01*
X575346Y38125D01*
X575331Y38085D01*
X575321Y38045D01*
X575306Y38000D01*
X575301Y37960D01*
X575291Y37920D01*
X575286Y37875D01*
Y37835D01*
X575281Y37790D01*
X575286Y37745D01*
Y37705D01*
X575291Y37660D01*
X575301Y37620D01*
X575306Y37580D01*
X575321Y37535D01*
X575331Y37495D01*
X575346Y37455D01*
X575366Y37415D01*
X575381Y37380D01*
X575401Y37340D01*
X575501Y37200D01*
X575531Y37170D01*
Y36040D01*
X575541Y35915D01*
X575581Y35790D01*
X575641Y35680D01*
X575721Y35580D01*
X575821Y35500D01*
X575931Y35440D01*
X576056Y35400D01*
X576181Y35390D01*
G37*
G36*
G01X599803D02*
X599928Y35400D01*
X600053Y35440D01*
X600163Y35500D01*
X600263Y35580D01*
X600343Y35680D01*
X600403Y35790D01*
X600443Y35915D01*
X600453Y36040D01*
Y37170D01*
X600483Y37200D01*
X600583Y37340D01*
X600603Y37380D01*
X600618Y37415D01*
X600638Y37455D01*
X600653Y37495D01*
X600663Y37535D01*
X600678Y37580D01*
X600683Y37620D01*
X600693Y37660D01*
X600698Y37705D01*
Y37745D01*
X600703Y37790D01*
X600698Y37835D01*
Y37875D01*
X600693Y37920D01*
X600683Y37960D01*
X600678Y38000D01*
X600663Y38045D01*
X600653Y38085D01*
X600638Y38125D01*
X600618Y38165D01*
X600603Y38200D01*
X600583Y38240D01*
X600483Y38380D01*
X600453Y38410D01*
Y41840D01*
X600443Y41965D01*
X600403Y42090D01*
X600343Y42200D01*
X600263Y42300D01*
X600163Y42380D01*
X600053Y42440D01*
X599928Y42480D01*
X599803Y42490D01*
X599678Y42480D01*
X599553Y42440D01*
X599443Y42380D01*
X599343Y42300D01*
X599263Y42200D01*
X599203Y42090D01*
X599163Y41965D01*
X599153Y41840D01*
Y38410D01*
X599123Y38380D01*
X599023Y38240D01*
X599003Y38200D01*
X598988Y38165D01*
X598968Y38125D01*
X598953Y38085D01*
X598943Y38045D01*
X598928Y38000D01*
X598923Y37960D01*
X598913Y37920D01*
X598908Y37875D01*
Y37835D01*
X598903Y37790D01*
X598908Y37745D01*
Y37705D01*
X598913Y37660D01*
X598923Y37620D01*
X598928Y37580D01*
X598943Y37535D01*
X598953Y37495D01*
X598968Y37455D01*
X598988Y37415D01*
X599003Y37380D01*
X599023Y37340D01*
X599123Y37200D01*
X599153Y37170D01*
Y36040D01*
X599163Y35915D01*
X599203Y35790D01*
X599263Y35680D01*
X599343Y35580D01*
X599443Y35500D01*
X599553Y35440D01*
X599678Y35400D01*
X599803Y35390D01*
G37*
G36*
G01X618701D02*
X618826Y35400D01*
X618951Y35440D01*
X619061Y35500D01*
X619161Y35580D01*
X619241Y35680D01*
X619301Y35790D01*
X619341Y35915D01*
X619351Y36040D01*
Y37170D01*
X619381Y37200D01*
X619481Y37340D01*
X619501Y37380D01*
X619516Y37415D01*
X619536Y37455D01*
X619551Y37495D01*
X619561Y37535D01*
X619576Y37580D01*
X619581Y37620D01*
X619591Y37660D01*
X619596Y37705D01*
Y37745D01*
X619601Y37790D01*
X619596Y37835D01*
Y37875D01*
X619591Y37920D01*
X619581Y37960D01*
X619576Y38000D01*
X619561Y38045D01*
X619551Y38085D01*
X619536Y38125D01*
X619516Y38165D01*
X619501Y38200D01*
X619481Y38240D01*
X619381Y38380D01*
X619351Y38410D01*
Y41840D01*
X619341Y41965D01*
X619301Y42090D01*
X619241Y42200D01*
X619161Y42300D01*
X619061Y42380D01*
X618951Y42440D01*
X618826Y42480D01*
X618701Y42490D01*
X618576Y42480D01*
X618451Y42440D01*
X618341Y42380D01*
X618241Y42300D01*
X618161Y42200D01*
X618101Y42090D01*
X618061Y41965D01*
X618051Y41840D01*
Y38410D01*
X618021Y38380D01*
X617921Y38240D01*
X617901Y38200D01*
X617886Y38165D01*
X617866Y38125D01*
X617851Y38085D01*
X617841Y38045D01*
X617826Y38000D01*
X617821Y37960D01*
X617811Y37920D01*
X617806Y37875D01*
Y37835D01*
X617801Y37790D01*
X617806Y37745D01*
Y37705D01*
X617811Y37660D01*
X617821Y37620D01*
X617826Y37580D01*
X617841Y37535D01*
X617851Y37495D01*
X617866Y37455D01*
X617886Y37415D01*
X617901Y37380D01*
X617921Y37340D01*
X618021Y37200D01*
X618051Y37170D01*
Y36040D01*
X618061Y35915D01*
X618101Y35790D01*
X618161Y35680D01*
X618241Y35580D01*
X618341Y35500D01*
X618451Y35440D01*
X618576Y35400D01*
X618701Y35390D01*
G37*
G36*
G01X613976D02*
X614101Y35400D01*
X614226Y35440D01*
X614336Y35500D01*
X614436Y35580D01*
X614516Y35680D01*
X614576Y35790D01*
X614616Y35915D01*
X614626Y36040D01*
Y37170D01*
X614656Y37200D01*
X614756Y37340D01*
X614776Y37380D01*
X614791Y37415D01*
X614811Y37455D01*
X614826Y37495D01*
X614836Y37535D01*
X614851Y37580D01*
X614856Y37620D01*
X614866Y37660D01*
X614871Y37705D01*
Y37745D01*
X614876Y37790D01*
X614871Y37835D01*
Y37875D01*
X614866Y37920D01*
X614856Y37960D01*
X614851Y38000D01*
X614836Y38045D01*
X614826Y38085D01*
X614811Y38125D01*
X614791Y38165D01*
X614776Y38200D01*
X614756Y38240D01*
X614656Y38380D01*
X614626Y38410D01*
Y41840D01*
X614616Y41965D01*
X614576Y42090D01*
X614516Y42200D01*
X614436Y42300D01*
X614336Y42380D01*
X614226Y42440D01*
X614101Y42480D01*
X613976Y42490D01*
X613851Y42480D01*
X613726Y42440D01*
X613616Y42380D01*
X613516Y42300D01*
X613436Y42200D01*
X613376Y42090D01*
X613336Y41965D01*
X613326Y41840D01*
Y38410D01*
X613296Y38380D01*
X613196Y38240D01*
X613176Y38200D01*
X613161Y38165D01*
X613141Y38125D01*
X613126Y38085D01*
X613116Y38045D01*
X613101Y38000D01*
X613096Y37960D01*
X613086Y37920D01*
X613081Y37875D01*
Y37835D01*
X613076Y37790D01*
X613081Y37745D01*
Y37705D01*
X613086Y37660D01*
X613096Y37620D01*
X613101Y37580D01*
X613116Y37535D01*
X613126Y37495D01*
X613141Y37455D01*
X613161Y37415D01*
X613176Y37380D01*
X613196Y37340D01*
X613296Y37200D01*
X613326Y37170D01*
Y36040D01*
X613336Y35915D01*
X613376Y35790D01*
X613436Y35680D01*
X613516Y35580D01*
X613616Y35500D01*
X613726Y35440D01*
X613851Y35400D01*
X613976Y35390D01*
G37*
G36*
G01X609252D02*
X609377Y35400D01*
X609502Y35440D01*
X609612Y35500D01*
X609712Y35580D01*
X609792Y35680D01*
X609852Y35790D01*
X609892Y35915D01*
X609902Y36040D01*
Y37170D01*
X609932Y37200D01*
X610032Y37340D01*
X610052Y37380D01*
X610067Y37415D01*
X610087Y37455D01*
X610102Y37495D01*
X610112Y37535D01*
X610127Y37580D01*
X610132Y37620D01*
X610142Y37660D01*
X610147Y37705D01*
Y37745D01*
X610152Y37790D01*
X610147Y37835D01*
Y37875D01*
X610142Y37920D01*
X610132Y37960D01*
X610127Y38000D01*
X610112Y38045D01*
X610102Y38085D01*
X610087Y38125D01*
X610067Y38165D01*
X610052Y38200D01*
X610032Y38240D01*
X609932Y38380D01*
X609902Y38410D01*
Y41840D01*
X609892Y41965D01*
X609852Y42090D01*
X609792Y42200D01*
X609712Y42300D01*
X609612Y42380D01*
X609502Y42440D01*
X609377Y42480D01*
X609252Y42490D01*
X609127Y42480D01*
X609002Y42440D01*
X608892Y42380D01*
X608792Y42300D01*
X608712Y42200D01*
X608652Y42090D01*
X608612Y41965D01*
X608602Y41840D01*
Y38410D01*
X608572Y38380D01*
X608472Y38240D01*
X608452Y38200D01*
X608437Y38165D01*
X608417Y38125D01*
X608402Y38085D01*
X608392Y38045D01*
X608377Y38000D01*
X608372Y37960D01*
X608362Y37920D01*
X608357Y37875D01*
Y37835D01*
X608352Y37790D01*
X608357Y37745D01*
Y37705D01*
X608362Y37660D01*
X608372Y37620D01*
X608377Y37580D01*
X608392Y37535D01*
X608402Y37495D01*
X608417Y37455D01*
X608437Y37415D01*
X608452Y37380D01*
X608472Y37340D01*
X608572Y37200D01*
X608602Y37170D01*
Y36040D01*
X608612Y35915D01*
X608652Y35790D01*
X608712Y35680D01*
X608792Y35580D01*
X608892Y35500D01*
X609002Y35440D01*
X609127Y35400D01*
X609252Y35390D01*
G37*
G36*
G01X604527D02*
X604652Y35400D01*
X604777Y35440D01*
X604887Y35500D01*
X604987Y35580D01*
X605067Y35680D01*
X605127Y35790D01*
X605167Y35915D01*
X605177Y36040D01*
Y37170D01*
X605207Y37200D01*
X605307Y37340D01*
X605327Y37380D01*
X605342Y37415D01*
X605362Y37455D01*
X605377Y37495D01*
X605387Y37535D01*
X605402Y37580D01*
X605407Y37620D01*
X605417Y37660D01*
X605422Y37705D01*
Y37745D01*
X605427Y37790D01*
X605422Y37835D01*
Y37875D01*
X605417Y37920D01*
X605407Y37960D01*
X605402Y38000D01*
X605387Y38045D01*
X605377Y38085D01*
X605362Y38125D01*
X605342Y38165D01*
X605327Y38200D01*
X605307Y38240D01*
X605207Y38380D01*
X605177Y38410D01*
Y41840D01*
X605167Y41965D01*
X605127Y42090D01*
X605067Y42200D01*
X604987Y42300D01*
X604887Y42380D01*
X604777Y42440D01*
X604652Y42480D01*
X604527Y42490D01*
X604402Y42480D01*
X604277Y42440D01*
X604167Y42380D01*
X604067Y42300D01*
X603987Y42200D01*
X603927Y42090D01*
X603887Y41965D01*
X603877Y41840D01*
Y38410D01*
X603847Y38380D01*
X603747Y38240D01*
X603727Y38200D01*
X603712Y38165D01*
X603692Y38125D01*
X603677Y38085D01*
X603667Y38045D01*
X603652Y38000D01*
X603647Y37960D01*
X603637Y37920D01*
X603632Y37875D01*
Y37835D01*
X603627Y37790D01*
X603632Y37745D01*
Y37705D01*
X603637Y37660D01*
X603647Y37620D01*
X603652Y37580D01*
X603667Y37535D01*
X603677Y37495D01*
X603692Y37455D01*
X603712Y37415D01*
X603727Y37380D01*
X603747Y37340D01*
X603847Y37200D01*
X603877Y37170D01*
Y36040D01*
X603887Y35915D01*
X603927Y35790D01*
X603987Y35680D01*
X604067Y35580D01*
X604167Y35500D01*
X604277Y35440D01*
X604402Y35400D01*
X604527Y35390D01*
G37*
G36*
G01X632874D02*
X632999Y35400D01*
X633124Y35440D01*
X633234Y35500D01*
X633334Y35580D01*
X633414Y35680D01*
X633474Y35790D01*
X633514Y35915D01*
X633524Y36040D01*
Y37170D01*
X633554Y37200D01*
X633654Y37340D01*
X633674Y37380D01*
X633689Y37415D01*
X633709Y37455D01*
X633724Y37495D01*
X633734Y37535D01*
X633749Y37580D01*
X633754Y37620D01*
X633764Y37660D01*
X633769Y37705D01*
Y37745D01*
X633774Y37790D01*
X633769Y37835D01*
Y37875D01*
X633764Y37920D01*
X633754Y37960D01*
X633749Y38000D01*
X633734Y38045D01*
X633724Y38085D01*
X633709Y38125D01*
X633689Y38165D01*
X633674Y38200D01*
X633654Y38240D01*
X633554Y38380D01*
X633524Y38410D01*
Y41840D01*
X633514Y41965D01*
X633474Y42090D01*
X633414Y42200D01*
X633334Y42300D01*
X633234Y42380D01*
X633124Y42440D01*
X632999Y42480D01*
X632874Y42490D01*
X632749Y42480D01*
X632624Y42440D01*
X632514Y42380D01*
X632414Y42300D01*
X632334Y42200D01*
X632274Y42090D01*
X632234Y41965D01*
X632224Y41840D01*
Y38410D01*
X632194Y38380D01*
X632094Y38240D01*
X632074Y38200D01*
X632059Y38165D01*
X632039Y38125D01*
X632024Y38085D01*
X632014Y38045D01*
X631999Y38000D01*
X631994Y37960D01*
X631984Y37920D01*
X631979Y37875D01*
Y37835D01*
X631974Y37790D01*
X631979Y37745D01*
Y37705D01*
X631984Y37660D01*
X631994Y37620D01*
X631999Y37580D01*
X632014Y37535D01*
X632024Y37495D01*
X632039Y37455D01*
X632059Y37415D01*
X632074Y37380D01*
X632094Y37340D01*
X632194Y37200D01*
X632224Y37170D01*
Y36040D01*
X632234Y35915D01*
X632274Y35790D01*
X632334Y35680D01*
X632414Y35580D01*
X632514Y35500D01*
X632624Y35440D01*
X632749Y35400D01*
X632874Y35390D01*
G37*
G36*
G01X628149D02*
X628274Y35400D01*
X628399Y35440D01*
X628509Y35500D01*
X628609Y35580D01*
X628689Y35680D01*
X628749Y35790D01*
X628789Y35915D01*
X628799Y36040D01*
Y37170D01*
X628829Y37200D01*
X628929Y37340D01*
X628949Y37380D01*
X628964Y37415D01*
X628984Y37455D01*
X628999Y37495D01*
X629009Y37535D01*
X629024Y37580D01*
X629029Y37620D01*
X629039Y37660D01*
X629044Y37705D01*
Y37745D01*
X629049Y37790D01*
X629044Y37835D01*
Y37875D01*
X629039Y37920D01*
X629029Y37960D01*
X629024Y38000D01*
X629009Y38045D01*
X628999Y38085D01*
X628984Y38125D01*
X628964Y38165D01*
X628949Y38200D01*
X628929Y38240D01*
X628829Y38380D01*
X628799Y38410D01*
Y41840D01*
X628789Y41965D01*
X628749Y42090D01*
X628689Y42200D01*
X628609Y42300D01*
X628509Y42380D01*
X628399Y42440D01*
X628274Y42480D01*
X628149Y42490D01*
X628024Y42480D01*
X627899Y42440D01*
X627789Y42380D01*
X627689Y42300D01*
X627609Y42200D01*
X627549Y42090D01*
X627509Y41965D01*
X627499Y41840D01*
Y38410D01*
X627469Y38380D01*
X627369Y38240D01*
X627349Y38200D01*
X627334Y38165D01*
X627314Y38125D01*
X627299Y38085D01*
X627289Y38045D01*
X627274Y38000D01*
X627269Y37960D01*
X627259Y37920D01*
X627254Y37875D01*
Y37835D01*
X627249Y37790D01*
X627254Y37745D01*
Y37705D01*
X627259Y37660D01*
X627269Y37620D01*
X627274Y37580D01*
X627289Y37535D01*
X627299Y37495D01*
X627314Y37455D01*
X627334Y37415D01*
X627349Y37380D01*
X627369Y37340D01*
X627469Y37200D01*
X627499Y37170D01*
Y36040D01*
X627509Y35915D01*
X627549Y35790D01*
X627609Y35680D01*
X627689Y35580D01*
X627789Y35500D01*
X627899Y35440D01*
X628024Y35400D01*
X628149Y35390D01*
G37*
G36*
G01X623425D02*
X623550Y35400D01*
X623675Y35440D01*
X623785Y35500D01*
X623885Y35580D01*
X623965Y35680D01*
X624025Y35790D01*
X624065Y35915D01*
X624075Y36040D01*
Y37170D01*
X624105Y37200D01*
X624205Y37340D01*
X624225Y37380D01*
X624240Y37415D01*
X624260Y37455D01*
X624275Y37495D01*
X624285Y37535D01*
X624300Y37580D01*
X624305Y37620D01*
X624315Y37660D01*
X624320Y37705D01*
Y37745D01*
X624325Y37790D01*
X624320Y37835D01*
Y37875D01*
X624315Y37920D01*
X624305Y37960D01*
X624300Y38000D01*
X624285Y38045D01*
X624275Y38085D01*
X624260Y38125D01*
X624240Y38165D01*
X624225Y38200D01*
X624205Y38240D01*
X624105Y38380D01*
X624075Y38410D01*
Y41840D01*
X624065Y41965D01*
X624025Y42090D01*
X623965Y42200D01*
X623885Y42300D01*
X623785Y42380D01*
X623675Y42440D01*
X623550Y42480D01*
X623425Y42490D01*
X623300Y42480D01*
X623175Y42440D01*
X623065Y42380D01*
X622965Y42300D01*
X622885Y42200D01*
X622825Y42090D01*
X622785Y41965D01*
X622775Y41840D01*
Y38410D01*
X622745Y38380D01*
X622645Y38240D01*
X622625Y38200D01*
X622610Y38165D01*
X622590Y38125D01*
X622575Y38085D01*
X622565Y38045D01*
X622550Y38000D01*
X622545Y37960D01*
X622535Y37920D01*
X622530Y37875D01*
Y37835D01*
X622525Y37790D01*
X622530Y37745D01*
Y37705D01*
X622535Y37660D01*
X622545Y37620D01*
X622550Y37580D01*
X622565Y37535D01*
X622575Y37495D01*
X622590Y37455D01*
X622610Y37415D01*
X622625Y37380D01*
X622645Y37340D01*
X622745Y37200D01*
X622775Y37170D01*
Y36040D01*
X622785Y35915D01*
X622825Y35790D01*
X622885Y35680D01*
X622965Y35580D01*
X623065Y35500D01*
X623175Y35440D01*
X623300Y35400D01*
X623425Y35390D01*
G37*
G36*
G01X647047D02*
X647172Y35400D01*
X647297Y35440D01*
X647407Y35500D01*
X647507Y35580D01*
X647587Y35680D01*
X647647Y35790D01*
X647687Y35915D01*
X647697Y36040D01*
Y37170D01*
X647727Y37200D01*
X647827Y37340D01*
X647847Y37380D01*
X647862Y37415D01*
X647882Y37455D01*
X647897Y37495D01*
X647907Y37535D01*
X647922Y37580D01*
X647927Y37620D01*
X647937Y37660D01*
X647942Y37705D01*
Y37745D01*
X647947Y37790D01*
X647942Y37835D01*
Y37875D01*
X647937Y37920D01*
X647927Y37960D01*
X647922Y38000D01*
X647907Y38045D01*
X647897Y38085D01*
X647882Y38125D01*
X647862Y38165D01*
X647847Y38200D01*
X647827Y38240D01*
X647727Y38380D01*
X647697Y38410D01*
Y41840D01*
X647687Y41965D01*
X647647Y42090D01*
X647587Y42200D01*
X647507Y42300D01*
X647407Y42380D01*
X647297Y42440D01*
X647172Y42480D01*
X647047Y42490D01*
X646922Y42480D01*
X646797Y42440D01*
X646687Y42380D01*
X646587Y42300D01*
X646507Y42200D01*
X646447Y42090D01*
X646407Y41965D01*
X646397Y41840D01*
Y38410D01*
X646367Y38380D01*
X646267Y38240D01*
X646247Y38200D01*
X646232Y38165D01*
X646212Y38125D01*
X646197Y38085D01*
X646187Y38045D01*
X646172Y38000D01*
X646167Y37960D01*
X646157Y37920D01*
X646152Y37875D01*
Y37835D01*
X646147Y37790D01*
X646152Y37745D01*
Y37705D01*
X646157Y37660D01*
X646167Y37620D01*
X646172Y37580D01*
X646187Y37535D01*
X646197Y37495D01*
X646212Y37455D01*
X646232Y37415D01*
X646247Y37380D01*
X646267Y37340D01*
X646367Y37200D01*
X646397Y37170D01*
Y36040D01*
X646407Y35915D01*
X646447Y35790D01*
X646507Y35680D01*
X646587Y35580D01*
X646687Y35500D01*
X646797Y35440D01*
X646922Y35400D01*
X647047Y35390D01*
G37*
G36*
G01X642323D02*
X642448Y35400D01*
X642573Y35440D01*
X642683Y35500D01*
X642783Y35580D01*
X642863Y35680D01*
X642923Y35790D01*
X642963Y35915D01*
X642973Y36040D01*
Y37170D01*
X643003Y37200D01*
X643103Y37340D01*
X643123Y37380D01*
X643138Y37415D01*
X643158Y37455D01*
X643173Y37495D01*
X643183Y37535D01*
X643198Y37580D01*
X643203Y37620D01*
X643213Y37660D01*
X643218Y37705D01*
Y37745D01*
X643223Y37790D01*
X643218Y37835D01*
Y37875D01*
X643213Y37920D01*
X643203Y37960D01*
X643198Y38000D01*
X643183Y38045D01*
X643173Y38085D01*
X643158Y38125D01*
X643138Y38165D01*
X643123Y38200D01*
X643103Y38240D01*
X643003Y38380D01*
X642973Y38410D01*
Y41840D01*
X642963Y41965D01*
X642923Y42090D01*
X642863Y42200D01*
X642783Y42300D01*
X642683Y42380D01*
X642573Y42440D01*
X642448Y42480D01*
X642323Y42490D01*
X642198Y42480D01*
X642073Y42440D01*
X641963Y42380D01*
X641863Y42300D01*
X641783Y42200D01*
X641723Y42090D01*
X641683Y41965D01*
X641673Y41840D01*
Y38410D01*
X641643Y38380D01*
X641543Y38240D01*
X641523Y38200D01*
X641508Y38165D01*
X641488Y38125D01*
X641473Y38085D01*
X641463Y38045D01*
X641448Y38000D01*
X641443Y37960D01*
X641433Y37920D01*
X641428Y37875D01*
Y37835D01*
X641423Y37790D01*
X641428Y37745D01*
Y37705D01*
X641433Y37660D01*
X641443Y37620D01*
X641448Y37580D01*
X641463Y37535D01*
X641473Y37495D01*
X641488Y37455D01*
X641508Y37415D01*
X641523Y37380D01*
X641543Y37340D01*
X641643Y37200D01*
X641673Y37170D01*
Y36040D01*
X641683Y35915D01*
X641723Y35790D01*
X641783Y35680D01*
X641863Y35580D01*
X641963Y35500D01*
X642073Y35440D01*
X642198Y35400D01*
X642323Y35390D01*
G37*
G36*
G01X637598D02*
X637723Y35400D01*
X637848Y35440D01*
X637958Y35500D01*
X638058Y35580D01*
X638138Y35680D01*
X638198Y35790D01*
X638238Y35915D01*
X638248Y36040D01*
Y37170D01*
X638278Y37200D01*
X638378Y37340D01*
X638398Y37380D01*
X638413Y37415D01*
X638433Y37455D01*
X638448Y37495D01*
X638458Y37535D01*
X638473Y37580D01*
X638478Y37620D01*
X638488Y37660D01*
X638493Y37705D01*
Y37745D01*
X638498Y37790D01*
X638493Y37835D01*
Y37875D01*
X638488Y37920D01*
X638478Y37960D01*
X638473Y38000D01*
X638458Y38045D01*
X638448Y38085D01*
X638433Y38125D01*
X638413Y38165D01*
X638398Y38200D01*
X638378Y38240D01*
X638278Y38380D01*
X638248Y38410D01*
Y41840D01*
X638238Y41965D01*
X638198Y42090D01*
X638138Y42200D01*
X638058Y42300D01*
X637958Y42380D01*
X637848Y42440D01*
X637723Y42480D01*
X637598Y42490D01*
X637473Y42480D01*
X637348Y42440D01*
X637238Y42380D01*
X637138Y42300D01*
X637058Y42200D01*
X636998Y42090D01*
X636958Y41965D01*
X636948Y41840D01*
Y38410D01*
X636918Y38380D01*
X636818Y38240D01*
X636798Y38200D01*
X636783Y38165D01*
X636763Y38125D01*
X636748Y38085D01*
X636738Y38045D01*
X636723Y38000D01*
X636718Y37960D01*
X636708Y37920D01*
X636703Y37875D01*
Y37835D01*
X636698Y37790D01*
X636703Y37745D01*
Y37705D01*
X636708Y37660D01*
X636718Y37620D01*
X636723Y37580D01*
X636738Y37535D01*
X636748Y37495D01*
X636763Y37455D01*
X636783Y37415D01*
X636798Y37380D01*
X636818Y37340D01*
X636918Y37200D01*
X636948Y37170D01*
Y36040D01*
X636958Y35915D01*
X636998Y35790D01*
X637058Y35680D01*
X637138Y35580D01*
X637238Y35500D01*
X637348Y35440D01*
X637473Y35400D01*
X637598Y35390D01*
G37*
G36*
G01X661220D02*
X661345Y35400D01*
X661470Y35440D01*
X661580Y35500D01*
X661680Y35580D01*
X661760Y35680D01*
X661820Y35790D01*
X661860Y35915D01*
X661870Y36040D01*
Y37170D01*
X661900Y37200D01*
X662000Y37340D01*
X662020Y37380D01*
X662035Y37415D01*
X662055Y37455D01*
X662070Y37495D01*
X662080Y37535D01*
X662095Y37580D01*
X662100Y37620D01*
X662110Y37660D01*
X662115Y37705D01*
Y37745D01*
X662120Y37790D01*
X662115Y37835D01*
Y37875D01*
X662110Y37920D01*
X662100Y37960D01*
X662095Y38000D01*
X662080Y38045D01*
X662070Y38085D01*
X662055Y38125D01*
X662035Y38165D01*
X662020Y38200D01*
X662000Y38240D01*
X661900Y38380D01*
X661870Y38410D01*
Y41840D01*
X661860Y41965D01*
X661820Y42090D01*
X661760Y42200D01*
X661680Y42300D01*
X661580Y42380D01*
X661470Y42440D01*
X661345Y42480D01*
X661220Y42490D01*
X661095Y42480D01*
X660970Y42440D01*
X660860Y42380D01*
X660760Y42300D01*
X660680Y42200D01*
X660620Y42090D01*
X660580Y41965D01*
X660570Y41840D01*
Y38410D01*
X660540Y38380D01*
X660440Y38240D01*
X660420Y38200D01*
X660405Y38165D01*
X660385Y38125D01*
X660370Y38085D01*
X660360Y38045D01*
X660345Y38000D01*
X660340Y37960D01*
X660330Y37920D01*
X660325Y37875D01*
Y37835D01*
X660320Y37790D01*
X660325Y37745D01*
Y37705D01*
X660330Y37660D01*
X660340Y37620D01*
X660345Y37580D01*
X660360Y37535D01*
X660370Y37495D01*
X660385Y37455D01*
X660405Y37415D01*
X660420Y37380D01*
X660440Y37340D01*
X660540Y37200D01*
X660570Y37170D01*
Y36040D01*
X660580Y35915D01*
X660620Y35790D01*
X660680Y35680D01*
X660760Y35580D01*
X660860Y35500D01*
X660970Y35440D01*
X661095Y35400D01*
X661220Y35390D01*
G37*
G36*
G01X656496D02*
X656621Y35400D01*
X656746Y35440D01*
X656856Y35500D01*
X656956Y35580D01*
X657036Y35680D01*
X657096Y35790D01*
X657136Y35915D01*
X657146Y36040D01*
Y37170D01*
X657176Y37200D01*
X657276Y37340D01*
X657296Y37380D01*
X657311Y37415D01*
X657331Y37455D01*
X657346Y37495D01*
X657356Y37535D01*
X657371Y37580D01*
X657376Y37620D01*
X657386Y37660D01*
X657391Y37705D01*
Y37745D01*
X657396Y37790D01*
X657391Y37835D01*
Y37875D01*
X657386Y37920D01*
X657376Y37960D01*
X657371Y38000D01*
X657356Y38045D01*
X657346Y38085D01*
X657331Y38125D01*
X657311Y38165D01*
X657296Y38200D01*
X657276Y38240D01*
X657176Y38380D01*
X657146Y38410D01*
Y41840D01*
X657136Y41965D01*
X657096Y42090D01*
X657036Y42200D01*
X656956Y42300D01*
X656856Y42380D01*
X656746Y42440D01*
X656621Y42480D01*
X656496Y42490D01*
X656371Y42480D01*
X656246Y42440D01*
X656136Y42380D01*
X656036Y42300D01*
X655956Y42200D01*
X655896Y42090D01*
X655856Y41965D01*
X655846Y41840D01*
Y38410D01*
X655816Y38380D01*
X655716Y38240D01*
X655696Y38200D01*
X655681Y38165D01*
X655661Y38125D01*
X655646Y38085D01*
X655636Y38045D01*
X655621Y38000D01*
X655616Y37960D01*
X655606Y37920D01*
X655601Y37875D01*
Y37835D01*
X655596Y37790D01*
X655601Y37745D01*
Y37705D01*
X655606Y37660D01*
X655616Y37620D01*
X655621Y37580D01*
X655636Y37535D01*
X655646Y37495D01*
X655661Y37455D01*
X655681Y37415D01*
X655696Y37380D01*
X655716Y37340D01*
X655816Y37200D01*
X655846Y37170D01*
Y36040D01*
X655856Y35915D01*
X655896Y35790D01*
X655956Y35680D01*
X656036Y35580D01*
X656136Y35500D01*
X656246Y35440D01*
X656371Y35400D01*
X656496Y35390D01*
G37*
G36*
G01X651771D02*
X651896Y35400D01*
X652021Y35440D01*
X652131Y35500D01*
X652231Y35580D01*
X652311Y35680D01*
X652371Y35790D01*
X652411Y35915D01*
X652421Y36040D01*
Y37170D01*
X652451Y37200D01*
X652551Y37340D01*
X652571Y37380D01*
X652586Y37415D01*
X652606Y37455D01*
X652621Y37495D01*
X652631Y37535D01*
X652646Y37580D01*
X652651Y37620D01*
X652661Y37660D01*
X652666Y37705D01*
Y37745D01*
X652671Y37790D01*
X652666Y37835D01*
Y37875D01*
X652661Y37920D01*
X652651Y37960D01*
X652646Y38000D01*
X652631Y38045D01*
X652621Y38085D01*
X652606Y38125D01*
X652586Y38165D01*
X652571Y38200D01*
X652551Y38240D01*
X652451Y38380D01*
X652421Y38410D01*
Y41840D01*
X652411Y41965D01*
X652371Y42090D01*
X652311Y42200D01*
X652231Y42300D01*
X652131Y42380D01*
X652021Y42440D01*
X651896Y42480D01*
X651771Y42490D01*
X651646Y42480D01*
X651521Y42440D01*
X651411Y42380D01*
X651311Y42300D01*
X651231Y42200D01*
X651171Y42090D01*
X651131Y41965D01*
X651121Y41840D01*
Y38410D01*
X651091Y38380D01*
X650991Y38240D01*
X650971Y38200D01*
X650956Y38165D01*
X650936Y38125D01*
X650921Y38085D01*
X650911Y38045D01*
X650896Y38000D01*
X650891Y37960D01*
X650881Y37920D01*
X650876Y37875D01*
Y37835D01*
X650871Y37790D01*
X650876Y37745D01*
Y37705D01*
X650881Y37660D01*
X650891Y37620D01*
X650896Y37580D01*
X650911Y37535D01*
X650921Y37495D01*
X650936Y37455D01*
X650956Y37415D01*
X650971Y37380D01*
X650991Y37340D01*
X651091Y37200D01*
X651121Y37170D01*
Y36040D01*
X651131Y35915D01*
X651171Y35790D01*
X651231Y35680D01*
X651311Y35580D01*
X651411Y35500D01*
X651521Y35440D01*
X651646Y35400D01*
X651771Y35390D01*
G37*
G36*
G01X680118D02*
X680243Y35400D01*
X680368Y35440D01*
X680478Y35500D01*
X680578Y35580D01*
X680658Y35680D01*
X680718Y35790D01*
X680758Y35915D01*
X680768Y36040D01*
Y37170D01*
X680798Y37200D01*
X680898Y37340D01*
X680918Y37380D01*
X680933Y37415D01*
X680953Y37455D01*
X680968Y37495D01*
X680978Y37535D01*
X680993Y37580D01*
X680998Y37620D01*
X681008Y37660D01*
X681013Y37705D01*
Y37745D01*
X681018Y37790D01*
X681013Y37835D01*
Y37875D01*
X681008Y37920D01*
X680998Y37960D01*
X680993Y38000D01*
X680978Y38045D01*
X680968Y38085D01*
X680953Y38125D01*
X680933Y38165D01*
X680918Y38200D01*
X680898Y38240D01*
X680798Y38380D01*
X680768Y38410D01*
Y41840D01*
X680758Y41965D01*
X680718Y42090D01*
X680658Y42200D01*
X680578Y42300D01*
X680478Y42380D01*
X680368Y42440D01*
X680243Y42480D01*
X680118Y42490D01*
X679993Y42480D01*
X679868Y42440D01*
X679758Y42380D01*
X679658Y42300D01*
X679578Y42200D01*
X679518Y42090D01*
X679478Y41965D01*
X679468Y41840D01*
Y38410D01*
X679438Y38380D01*
X679338Y38240D01*
X679318Y38200D01*
X679303Y38165D01*
X679283Y38125D01*
X679268Y38085D01*
X679258Y38045D01*
X679243Y38000D01*
X679238Y37960D01*
X679228Y37920D01*
X679223Y37875D01*
Y37835D01*
X679218Y37790D01*
X679223Y37745D01*
Y37705D01*
X679228Y37660D01*
X679238Y37620D01*
X679243Y37580D01*
X679258Y37535D01*
X679268Y37495D01*
X679283Y37455D01*
X679303Y37415D01*
X679318Y37380D01*
X679338Y37340D01*
X679438Y37200D01*
X679468Y37170D01*
Y36040D01*
X679478Y35915D01*
X679518Y35790D01*
X679578Y35680D01*
X679658Y35580D01*
X679758Y35500D01*
X679868Y35440D01*
X679993Y35400D01*
X680118Y35390D01*
G37*
G36*
G01X675393D02*
X675518Y35400D01*
X675643Y35440D01*
X675753Y35500D01*
X675853Y35580D01*
X675933Y35680D01*
X675993Y35790D01*
X676033Y35915D01*
X676043Y36040D01*
Y37170D01*
X676073Y37200D01*
X676173Y37340D01*
X676193Y37380D01*
X676208Y37415D01*
X676228Y37455D01*
X676243Y37495D01*
X676253Y37535D01*
X676268Y37580D01*
X676273Y37620D01*
X676283Y37660D01*
X676288Y37705D01*
Y37745D01*
X676293Y37790D01*
X676288Y37835D01*
Y37875D01*
X676283Y37920D01*
X676273Y37960D01*
X676268Y38000D01*
X676253Y38045D01*
X676243Y38085D01*
X676228Y38125D01*
X676208Y38165D01*
X676193Y38200D01*
X676173Y38240D01*
X676073Y38380D01*
X676043Y38410D01*
Y41840D01*
X676033Y41965D01*
X675993Y42090D01*
X675933Y42200D01*
X675853Y42300D01*
X675753Y42380D01*
X675643Y42440D01*
X675518Y42480D01*
X675393Y42490D01*
X675268Y42480D01*
X675143Y42440D01*
X675033Y42380D01*
X674933Y42300D01*
X674853Y42200D01*
X674793Y42090D01*
X674753Y41965D01*
X674743Y41840D01*
Y38410D01*
X674713Y38380D01*
X674613Y38240D01*
X674593Y38200D01*
X674578Y38165D01*
X674558Y38125D01*
X674543Y38085D01*
X674533Y38045D01*
X674518Y38000D01*
X674513Y37960D01*
X674503Y37920D01*
X674498Y37875D01*
Y37835D01*
X674493Y37790D01*
X674498Y37745D01*
Y37705D01*
X674503Y37660D01*
X674513Y37620D01*
X674518Y37580D01*
X674533Y37535D01*
X674543Y37495D01*
X674558Y37455D01*
X674578Y37415D01*
X674593Y37380D01*
X674613Y37340D01*
X674713Y37200D01*
X674743Y37170D01*
Y36040D01*
X674753Y35915D01*
X674793Y35790D01*
X674853Y35680D01*
X674933Y35580D01*
X675033Y35500D01*
X675143Y35440D01*
X675268Y35400D01*
X675393Y35390D01*
G37*
G36*
G01X670669D02*
X670794Y35400D01*
X670919Y35440D01*
X671029Y35500D01*
X671129Y35580D01*
X671209Y35680D01*
X671269Y35790D01*
X671309Y35915D01*
X671319Y36040D01*
Y37170D01*
X671349Y37200D01*
X671449Y37340D01*
X671469Y37380D01*
X671484Y37415D01*
X671504Y37455D01*
X671519Y37495D01*
X671529Y37535D01*
X671544Y37580D01*
X671549Y37620D01*
X671559Y37660D01*
X671564Y37705D01*
Y37745D01*
X671569Y37790D01*
X671564Y37835D01*
Y37875D01*
X671559Y37920D01*
X671549Y37960D01*
X671544Y38000D01*
X671529Y38045D01*
X671519Y38085D01*
X671504Y38125D01*
X671484Y38165D01*
X671469Y38200D01*
X671449Y38240D01*
X671349Y38380D01*
X671319Y38410D01*
Y41840D01*
X671309Y41965D01*
X671269Y42090D01*
X671209Y42200D01*
X671129Y42300D01*
X671029Y42380D01*
X670919Y42440D01*
X670794Y42480D01*
X670669Y42490D01*
X670544Y42480D01*
X670419Y42440D01*
X670309Y42380D01*
X670209Y42300D01*
X670129Y42200D01*
X670069Y42090D01*
X670029Y41965D01*
X670019Y41840D01*
Y38410D01*
X669989Y38380D01*
X669889Y38240D01*
X669869Y38200D01*
X669854Y38165D01*
X669834Y38125D01*
X669819Y38085D01*
X669809Y38045D01*
X669794Y38000D01*
X669789Y37960D01*
X669779Y37920D01*
X669774Y37875D01*
Y37835D01*
X669769Y37790D01*
X669774Y37745D01*
Y37705D01*
X669779Y37660D01*
X669789Y37620D01*
X669794Y37580D01*
X669809Y37535D01*
X669819Y37495D01*
X669834Y37455D01*
X669854Y37415D01*
X669869Y37380D01*
X669889Y37340D01*
X669989Y37200D01*
X670019Y37170D01*
Y36040D01*
X670029Y35915D01*
X670069Y35790D01*
X670129Y35680D01*
X670209Y35580D01*
X670309Y35500D01*
X670419Y35440D01*
X670544Y35400D01*
X670669Y35390D01*
G37*
G36*
G01X665945D02*
X666070Y35400D01*
X666195Y35440D01*
X666305Y35500D01*
X666405Y35580D01*
X666485Y35680D01*
X666545Y35790D01*
X666585Y35915D01*
X666595Y36040D01*
Y37170D01*
X666625Y37200D01*
X666725Y37340D01*
X666745Y37380D01*
X666760Y37415D01*
X666780Y37455D01*
X666795Y37495D01*
X666805Y37535D01*
X666820Y37580D01*
X666825Y37620D01*
X666835Y37660D01*
X666840Y37705D01*
Y37745D01*
X666845Y37790D01*
X666840Y37835D01*
Y37875D01*
X666835Y37920D01*
X666825Y37960D01*
X666820Y38000D01*
X666805Y38045D01*
X666795Y38085D01*
X666780Y38125D01*
X666760Y38165D01*
X666745Y38200D01*
X666725Y38240D01*
X666625Y38380D01*
X666595Y38410D01*
Y41840D01*
X666585Y41965D01*
X666545Y42090D01*
X666485Y42200D01*
X666405Y42300D01*
X666305Y42380D01*
X666195Y42440D01*
X666070Y42480D01*
X665945Y42490D01*
X665820Y42480D01*
X665695Y42440D01*
X665585Y42380D01*
X665485Y42300D01*
X665405Y42200D01*
X665345Y42090D01*
X665305Y41965D01*
X665295Y41840D01*
Y38410D01*
X665265Y38380D01*
X665165Y38240D01*
X665145Y38200D01*
X665130Y38165D01*
X665110Y38125D01*
X665095Y38085D01*
X665085Y38045D01*
X665070Y38000D01*
X665065Y37960D01*
X665055Y37920D01*
X665050Y37875D01*
Y37835D01*
X665045Y37790D01*
X665050Y37745D01*
Y37705D01*
X665055Y37660D01*
X665065Y37620D01*
X665070Y37580D01*
X665085Y37535D01*
X665095Y37495D01*
X665110Y37455D01*
X665130Y37415D01*
X665145Y37380D01*
X665165Y37340D01*
X665265Y37200D01*
X665295Y37170D01*
Y36040D01*
X665305Y35915D01*
X665345Y35790D01*
X665405Y35680D01*
X665485Y35580D01*
X665585Y35500D01*
X665695Y35440D01*
X665820Y35400D01*
X665945Y35390D01*
G37*
G36*
G01X694291D02*
X694416Y35400D01*
X694541Y35440D01*
X694651Y35500D01*
X694751Y35580D01*
X694831Y35680D01*
X694891Y35790D01*
X694931Y35915D01*
X694941Y36040D01*
Y37170D01*
X694971Y37200D01*
X695071Y37340D01*
X695091Y37380D01*
X695106Y37415D01*
X695126Y37455D01*
X695141Y37495D01*
X695151Y37535D01*
X695166Y37580D01*
X695171Y37620D01*
X695181Y37660D01*
X695186Y37705D01*
Y37745D01*
X695191Y37790D01*
X695186Y37835D01*
Y37875D01*
X695181Y37920D01*
X695171Y37960D01*
X695166Y38000D01*
X695151Y38045D01*
X695141Y38085D01*
X695126Y38125D01*
X695106Y38165D01*
X695091Y38200D01*
X695071Y38240D01*
X694971Y38380D01*
X694941Y38410D01*
Y41840D01*
X694931Y41965D01*
X694891Y42090D01*
X694831Y42200D01*
X694751Y42300D01*
X694651Y42380D01*
X694541Y42440D01*
X694416Y42480D01*
X694291Y42490D01*
X694166Y42480D01*
X694041Y42440D01*
X693931Y42380D01*
X693831Y42300D01*
X693751Y42200D01*
X693691Y42090D01*
X693651Y41965D01*
X693641Y41840D01*
Y38410D01*
X693611Y38380D01*
X693511Y38240D01*
X693491Y38200D01*
X693476Y38165D01*
X693456Y38125D01*
X693441Y38085D01*
X693431Y38045D01*
X693416Y38000D01*
X693411Y37960D01*
X693401Y37920D01*
X693396Y37875D01*
Y37835D01*
X693391Y37790D01*
X693396Y37745D01*
Y37705D01*
X693401Y37660D01*
X693411Y37620D01*
X693416Y37580D01*
X693431Y37535D01*
X693441Y37495D01*
X693456Y37455D01*
X693476Y37415D01*
X693491Y37380D01*
X693511Y37340D01*
X693611Y37200D01*
X693641Y37170D01*
Y36040D01*
X693651Y35915D01*
X693691Y35790D01*
X693751Y35680D01*
X693831Y35580D01*
X693931Y35500D01*
X694041Y35440D01*
X694166Y35400D01*
X694291Y35390D01*
G37*
G36*
G01X689567D02*
X689692Y35400D01*
X689817Y35440D01*
X689927Y35500D01*
X690027Y35580D01*
X690107Y35680D01*
X690167Y35790D01*
X690207Y35915D01*
X690217Y36040D01*
Y37170D01*
X690247Y37200D01*
X690347Y37340D01*
X690367Y37380D01*
X690382Y37415D01*
X690402Y37455D01*
X690417Y37495D01*
X690427Y37535D01*
X690442Y37580D01*
X690447Y37620D01*
X690457Y37660D01*
X690462Y37705D01*
Y37745D01*
X690467Y37790D01*
X690462Y37835D01*
Y37875D01*
X690457Y37920D01*
X690447Y37960D01*
X690442Y38000D01*
X690427Y38045D01*
X690417Y38085D01*
X690402Y38125D01*
X690382Y38165D01*
X690367Y38200D01*
X690347Y38240D01*
X690247Y38380D01*
X690217Y38410D01*
Y41840D01*
X690207Y41965D01*
X690167Y42090D01*
X690107Y42200D01*
X690027Y42300D01*
X689927Y42380D01*
X689817Y42440D01*
X689692Y42480D01*
X689567Y42490D01*
X689442Y42480D01*
X689317Y42440D01*
X689207Y42380D01*
X689107Y42300D01*
X689027Y42200D01*
X688967Y42090D01*
X688927Y41965D01*
X688917Y41840D01*
Y38410D01*
X688887Y38380D01*
X688787Y38240D01*
X688767Y38200D01*
X688752Y38165D01*
X688732Y38125D01*
X688717Y38085D01*
X688707Y38045D01*
X688692Y38000D01*
X688687Y37960D01*
X688677Y37920D01*
X688672Y37875D01*
Y37835D01*
X688667Y37790D01*
X688672Y37745D01*
Y37705D01*
X688677Y37660D01*
X688687Y37620D01*
X688692Y37580D01*
X688707Y37535D01*
X688717Y37495D01*
X688732Y37455D01*
X688752Y37415D01*
X688767Y37380D01*
X688787Y37340D01*
X688887Y37200D01*
X688917Y37170D01*
Y36040D01*
X688927Y35915D01*
X688967Y35790D01*
X689027Y35680D01*
X689107Y35580D01*
X689207Y35500D01*
X689317Y35440D01*
X689442Y35400D01*
X689567Y35390D01*
G37*
G36*
G01X684842D02*
X684967Y35400D01*
X685092Y35440D01*
X685202Y35500D01*
X685302Y35580D01*
X685382Y35680D01*
X685442Y35790D01*
X685482Y35915D01*
X685492Y36040D01*
Y37170D01*
X685522Y37200D01*
X685622Y37340D01*
X685642Y37380D01*
X685657Y37415D01*
X685677Y37455D01*
X685692Y37495D01*
X685702Y37535D01*
X685717Y37580D01*
X685722Y37620D01*
X685732Y37660D01*
X685737Y37705D01*
Y37745D01*
X685742Y37790D01*
X685737Y37835D01*
Y37875D01*
X685732Y37920D01*
X685722Y37960D01*
X685717Y38000D01*
X685702Y38045D01*
X685692Y38085D01*
X685677Y38125D01*
X685657Y38165D01*
X685642Y38200D01*
X685622Y38240D01*
X685522Y38380D01*
X685492Y38410D01*
Y41840D01*
X685482Y41965D01*
X685442Y42090D01*
X685382Y42200D01*
X685302Y42300D01*
X685202Y42380D01*
X685092Y42440D01*
X684967Y42480D01*
X684842Y42490D01*
X684717Y42480D01*
X684592Y42440D01*
X684482Y42380D01*
X684382Y42300D01*
X684302Y42200D01*
X684242Y42090D01*
X684202Y41965D01*
X684192Y41840D01*
Y38410D01*
X684162Y38380D01*
X684062Y38240D01*
X684042Y38200D01*
X684027Y38165D01*
X684007Y38125D01*
X683992Y38085D01*
X683982Y38045D01*
X683967Y38000D01*
X683962Y37960D01*
X683952Y37920D01*
X683947Y37875D01*
Y37835D01*
X683942Y37790D01*
X683947Y37745D01*
Y37705D01*
X683952Y37660D01*
X683962Y37620D01*
X683967Y37580D01*
X683982Y37535D01*
X683992Y37495D01*
X684007Y37455D01*
X684027Y37415D01*
X684042Y37380D01*
X684062Y37340D01*
X684162Y37200D01*
X684192Y37170D01*
Y36040D01*
X684202Y35915D01*
X684242Y35790D01*
X684302Y35680D01*
X684382Y35580D01*
X684482Y35500D01*
X684592Y35440D01*
X684717Y35400D01*
X684842Y35390D01*
G37*
G36*
G01X708464D02*
X708589Y35400D01*
X708714Y35440D01*
X708824Y35500D01*
X708924Y35580D01*
X709004Y35680D01*
X709064Y35790D01*
X709104Y35915D01*
X709114Y36040D01*
Y37170D01*
X709144Y37200D01*
X709244Y37340D01*
X709264Y37380D01*
X709279Y37415D01*
X709299Y37455D01*
X709314Y37495D01*
X709324Y37535D01*
X709339Y37580D01*
X709344Y37620D01*
X709354Y37660D01*
X709359Y37705D01*
Y37745D01*
X709364Y37790D01*
X709359Y37835D01*
Y37875D01*
X709354Y37920D01*
X709344Y37960D01*
X709339Y38000D01*
X709324Y38045D01*
X709314Y38085D01*
X709299Y38125D01*
X709279Y38165D01*
X709264Y38200D01*
X709244Y38240D01*
X709144Y38380D01*
X709114Y38410D01*
Y41840D01*
X709104Y41965D01*
X709064Y42090D01*
X709004Y42200D01*
X708924Y42300D01*
X708824Y42380D01*
X708714Y42440D01*
X708589Y42480D01*
X708464Y42490D01*
X708339Y42480D01*
X708214Y42440D01*
X708104Y42380D01*
X708004Y42300D01*
X707924Y42200D01*
X707864Y42090D01*
X707824Y41965D01*
X707814Y41840D01*
Y38410D01*
X707784Y38380D01*
X707684Y38240D01*
X707664Y38200D01*
X707649Y38165D01*
X707629Y38125D01*
X707614Y38085D01*
X707604Y38045D01*
X707589Y38000D01*
X707584Y37960D01*
X707574Y37920D01*
X707569Y37875D01*
Y37835D01*
X707564Y37790D01*
X707569Y37745D01*
Y37705D01*
X707574Y37660D01*
X707584Y37620D01*
X707589Y37580D01*
X707604Y37535D01*
X707614Y37495D01*
X707629Y37455D01*
X707649Y37415D01*
X707664Y37380D01*
X707684Y37340D01*
X707784Y37200D01*
X707814Y37170D01*
Y36040D01*
X707824Y35915D01*
X707864Y35790D01*
X707924Y35680D01*
X708004Y35580D01*
X708104Y35500D01*
X708214Y35440D01*
X708339Y35400D01*
X708464Y35390D01*
G37*
G36*
G01X703740D02*
X703865Y35400D01*
X703990Y35440D01*
X704100Y35500D01*
X704200Y35580D01*
X704280Y35680D01*
X704340Y35790D01*
X704380Y35915D01*
X704390Y36040D01*
Y37170D01*
X704420Y37200D01*
X704520Y37340D01*
X704540Y37380D01*
X704555Y37415D01*
X704575Y37455D01*
X704590Y37495D01*
X704600Y37535D01*
X704615Y37580D01*
X704620Y37620D01*
X704630Y37660D01*
X704635Y37705D01*
Y37745D01*
X704640Y37790D01*
X704635Y37835D01*
Y37875D01*
X704630Y37920D01*
X704620Y37960D01*
X704615Y38000D01*
X704600Y38045D01*
X704590Y38085D01*
X704575Y38125D01*
X704555Y38165D01*
X704540Y38200D01*
X704520Y38240D01*
X704420Y38380D01*
X704390Y38410D01*
Y41840D01*
X704380Y41965D01*
X704340Y42090D01*
X704280Y42200D01*
X704200Y42300D01*
X704100Y42380D01*
X703990Y42440D01*
X703865Y42480D01*
X703740Y42490D01*
X703615Y42480D01*
X703490Y42440D01*
X703380Y42380D01*
X703280Y42300D01*
X703200Y42200D01*
X703140Y42090D01*
X703100Y41965D01*
X703090Y41840D01*
Y38410D01*
X703060Y38380D01*
X702960Y38240D01*
X702940Y38200D01*
X702925Y38165D01*
X702905Y38125D01*
X702890Y38085D01*
X702880Y38045D01*
X702865Y38000D01*
X702860Y37960D01*
X702850Y37920D01*
X702845Y37875D01*
Y37835D01*
X702840Y37790D01*
X702845Y37745D01*
Y37705D01*
X702850Y37660D01*
X702860Y37620D01*
X702865Y37580D01*
X702880Y37535D01*
X702890Y37495D01*
X702905Y37455D01*
X702925Y37415D01*
X702940Y37380D01*
X702960Y37340D01*
X703060Y37200D01*
X703090Y37170D01*
Y36040D01*
X703100Y35915D01*
X703140Y35790D01*
X703200Y35680D01*
X703280Y35580D01*
X703380Y35500D01*
X703490Y35440D01*
X703615Y35400D01*
X703740Y35390D01*
G37*
G36*
G01X699015D02*
X699140Y35400D01*
X699265Y35440D01*
X699375Y35500D01*
X699475Y35580D01*
X699555Y35680D01*
X699615Y35790D01*
X699655Y35915D01*
X699665Y36040D01*
Y37170D01*
X699695Y37200D01*
X699795Y37340D01*
X699815Y37380D01*
X699830Y37415D01*
X699850Y37455D01*
X699865Y37495D01*
X699875Y37535D01*
X699890Y37580D01*
X699895Y37620D01*
X699905Y37660D01*
X699910Y37705D01*
Y37745D01*
X699915Y37790D01*
X699910Y37835D01*
Y37875D01*
X699905Y37920D01*
X699895Y37960D01*
X699890Y38000D01*
X699875Y38045D01*
X699865Y38085D01*
X699850Y38125D01*
X699830Y38165D01*
X699815Y38200D01*
X699795Y38240D01*
X699695Y38380D01*
X699665Y38410D01*
Y41840D01*
X699655Y41965D01*
X699615Y42090D01*
X699555Y42200D01*
X699475Y42300D01*
X699375Y42380D01*
X699265Y42440D01*
X699140Y42480D01*
X699015Y42490D01*
X698890Y42480D01*
X698765Y42440D01*
X698655Y42380D01*
X698555Y42300D01*
X698475Y42200D01*
X698415Y42090D01*
X698375Y41965D01*
X698365Y41840D01*
Y38410D01*
X698335Y38380D01*
X698235Y38240D01*
X698215Y38200D01*
X698200Y38165D01*
X698180Y38125D01*
X698165Y38085D01*
X698155Y38045D01*
X698140Y38000D01*
X698135Y37960D01*
X698125Y37920D01*
X698120Y37875D01*
Y37835D01*
X698115Y37790D01*
X698120Y37745D01*
Y37705D01*
X698125Y37660D01*
X698135Y37620D01*
X698140Y37580D01*
X698155Y37535D01*
X698165Y37495D01*
X698180Y37455D01*
X698200Y37415D01*
X698215Y37380D01*
X698235Y37340D01*
X698335Y37200D01*
X698365Y37170D01*
Y36040D01*
X698375Y35915D01*
X698415Y35790D01*
X698475Y35680D01*
X698555Y35580D01*
X698655Y35500D01*
X698765Y35440D01*
X698890Y35400D01*
X699015Y35390D01*
G37*
G36*
G01X722638D02*
X722763Y35400D01*
X722888Y35440D01*
X722998Y35500D01*
X723098Y35580D01*
X723178Y35680D01*
X723238Y35790D01*
X723278Y35915D01*
X723288Y36040D01*
Y37170D01*
X723318Y37200D01*
X723418Y37340D01*
X723438Y37380D01*
X723453Y37415D01*
X723473Y37455D01*
X723488Y37495D01*
X723498Y37535D01*
X723513Y37580D01*
X723518Y37620D01*
X723528Y37660D01*
X723533Y37705D01*
Y37745D01*
X723538Y37790D01*
X723533Y37835D01*
Y37875D01*
X723528Y37920D01*
X723518Y37960D01*
X723513Y38000D01*
X723498Y38045D01*
X723488Y38085D01*
X723473Y38125D01*
X723453Y38165D01*
X723438Y38200D01*
X723418Y38240D01*
X723318Y38380D01*
X723288Y38410D01*
Y41840D01*
X723278Y41965D01*
X723238Y42090D01*
X723178Y42200D01*
X723098Y42300D01*
X722998Y42380D01*
X722888Y42440D01*
X722763Y42480D01*
X722638Y42490D01*
X722513Y42480D01*
X722388Y42440D01*
X722278Y42380D01*
X722178Y42300D01*
X722098Y42200D01*
X722038Y42090D01*
X721998Y41965D01*
X721988Y41840D01*
Y38410D01*
X721958Y38380D01*
X721858Y38240D01*
X721838Y38200D01*
X721823Y38165D01*
X721803Y38125D01*
X721788Y38085D01*
X721778Y38045D01*
X721763Y38000D01*
X721758Y37960D01*
X721748Y37920D01*
X721743Y37875D01*
Y37835D01*
X721738Y37790D01*
X721743Y37745D01*
Y37705D01*
X721748Y37660D01*
X721758Y37620D01*
X721763Y37580D01*
X721778Y37535D01*
X721788Y37495D01*
X721803Y37455D01*
X721823Y37415D01*
X721838Y37380D01*
X721858Y37340D01*
X721958Y37200D01*
X721988Y37170D01*
Y36040D01*
X721998Y35915D01*
X722038Y35790D01*
X722098Y35680D01*
X722178Y35580D01*
X722278Y35500D01*
X722388Y35440D01*
X722513Y35400D01*
X722638Y35390D01*
G37*
G36*
G01X717913D02*
X718038Y35400D01*
X718163Y35440D01*
X718273Y35500D01*
X718373Y35580D01*
X718453Y35680D01*
X718513Y35790D01*
X718553Y35915D01*
X718563Y36040D01*
Y37170D01*
X718593Y37200D01*
X718693Y37340D01*
X718713Y37380D01*
X718728Y37415D01*
X718748Y37455D01*
X718763Y37495D01*
X718773Y37535D01*
X718788Y37580D01*
X718793Y37620D01*
X718803Y37660D01*
X718808Y37705D01*
Y37745D01*
X718813Y37790D01*
X718808Y37835D01*
Y37875D01*
X718803Y37920D01*
X718793Y37960D01*
X718788Y38000D01*
X718773Y38045D01*
X718763Y38085D01*
X718748Y38125D01*
X718728Y38165D01*
X718713Y38200D01*
X718693Y38240D01*
X718593Y38380D01*
X718563Y38410D01*
Y41840D01*
X718553Y41965D01*
X718513Y42090D01*
X718453Y42200D01*
X718373Y42300D01*
X718273Y42380D01*
X718163Y42440D01*
X718038Y42480D01*
X717913Y42490D01*
X717788Y42480D01*
X717663Y42440D01*
X717553Y42380D01*
X717453Y42300D01*
X717373Y42200D01*
X717313Y42090D01*
X717273Y41965D01*
X717263Y41840D01*
Y38410D01*
X717233Y38380D01*
X717133Y38240D01*
X717113Y38200D01*
X717098Y38165D01*
X717078Y38125D01*
X717063Y38085D01*
X717053Y38045D01*
X717038Y38000D01*
X717033Y37960D01*
X717023Y37920D01*
X717018Y37875D01*
Y37835D01*
X717013Y37790D01*
X717018Y37745D01*
Y37705D01*
X717023Y37660D01*
X717033Y37620D01*
X717038Y37580D01*
X717053Y37535D01*
X717063Y37495D01*
X717078Y37455D01*
X717098Y37415D01*
X717113Y37380D01*
X717133Y37340D01*
X717233Y37200D01*
X717263Y37170D01*
Y36040D01*
X717273Y35915D01*
X717313Y35790D01*
X717373Y35680D01*
X717453Y35580D01*
X717553Y35500D01*
X717663Y35440D01*
X717788Y35400D01*
X717913Y35390D01*
G37*
G36*
G01X713189D02*
X713314Y35400D01*
X713439Y35440D01*
X713549Y35500D01*
X713649Y35580D01*
X713729Y35680D01*
X713789Y35790D01*
X713829Y35915D01*
X713839Y36040D01*
Y37170D01*
X713869Y37200D01*
X713969Y37340D01*
X713989Y37380D01*
X714004Y37415D01*
X714024Y37455D01*
X714039Y37495D01*
X714049Y37535D01*
X714064Y37580D01*
X714069Y37620D01*
X714079Y37660D01*
X714084Y37705D01*
Y37745D01*
X714089Y37790D01*
X714084Y37835D01*
Y37875D01*
X714079Y37920D01*
X714069Y37960D01*
X714064Y38000D01*
X714049Y38045D01*
X714039Y38085D01*
X714024Y38125D01*
X714004Y38165D01*
X713989Y38200D01*
X713969Y38240D01*
X713869Y38380D01*
X713839Y38410D01*
Y41840D01*
X713829Y41965D01*
X713789Y42090D01*
X713729Y42200D01*
X713649Y42300D01*
X713549Y42380D01*
X713439Y42440D01*
X713314Y42480D01*
X713189Y42490D01*
X713064Y42480D01*
X712939Y42440D01*
X712829Y42380D01*
X712729Y42300D01*
X712649Y42200D01*
X712589Y42090D01*
X712549Y41965D01*
X712539Y41840D01*
Y38410D01*
X712509Y38380D01*
X712409Y38240D01*
X712389Y38200D01*
X712374Y38165D01*
X712354Y38125D01*
X712339Y38085D01*
X712329Y38045D01*
X712314Y38000D01*
X712309Y37960D01*
X712299Y37920D01*
X712294Y37875D01*
Y37835D01*
X712289Y37790D01*
X712294Y37745D01*
Y37705D01*
X712299Y37660D01*
X712309Y37620D01*
X712314Y37580D01*
X712329Y37535D01*
X712339Y37495D01*
X712354Y37455D01*
X712374Y37415D01*
X712389Y37380D01*
X712409Y37340D01*
X712509Y37200D01*
X712539Y37170D01*
Y36040D01*
X712549Y35915D01*
X712589Y35790D01*
X712649Y35680D01*
X712729Y35580D01*
X712829Y35500D01*
X712939Y35440D01*
X713064Y35400D01*
X713189Y35390D01*
G37*
G36*
G01X741535D02*
X741660Y35400D01*
X741785Y35440D01*
X741895Y35500D01*
X741995Y35580D01*
X742075Y35680D01*
X742135Y35790D01*
X742175Y35915D01*
X742185Y36040D01*
Y37170D01*
X742215Y37200D01*
X742315Y37340D01*
X742335Y37380D01*
X742350Y37415D01*
X742370Y37455D01*
X742385Y37495D01*
X742395Y37535D01*
X742410Y37580D01*
X742415Y37620D01*
X742425Y37660D01*
X742430Y37705D01*
Y37745D01*
X742435Y37790D01*
X742430Y37835D01*
Y37875D01*
X742425Y37920D01*
X742415Y37960D01*
X742410Y38000D01*
X742395Y38045D01*
X742385Y38085D01*
X742370Y38125D01*
X742350Y38165D01*
X742335Y38200D01*
X742315Y38240D01*
X742215Y38380D01*
X742185Y38410D01*
Y41840D01*
X742175Y41965D01*
X742135Y42090D01*
X742075Y42200D01*
X741995Y42300D01*
X741895Y42380D01*
X741785Y42440D01*
X741660Y42480D01*
X741535Y42490D01*
X741410Y42480D01*
X741285Y42440D01*
X741175Y42380D01*
X741075Y42300D01*
X740995Y42200D01*
X740935Y42090D01*
X740895Y41965D01*
X740885Y41840D01*
Y38410D01*
X740855Y38380D01*
X740755Y38240D01*
X740735Y38200D01*
X740720Y38165D01*
X740700Y38125D01*
X740685Y38085D01*
X740675Y38045D01*
X740660Y38000D01*
X740655Y37960D01*
X740645Y37920D01*
X740640Y37875D01*
Y37835D01*
X740635Y37790D01*
X740640Y37745D01*
Y37705D01*
X740645Y37660D01*
X740655Y37620D01*
X740660Y37580D01*
X740675Y37535D01*
X740685Y37495D01*
X740700Y37455D01*
X740720Y37415D01*
X740735Y37380D01*
X740755Y37340D01*
X740855Y37200D01*
X740885Y37170D01*
Y36040D01*
X740895Y35915D01*
X740935Y35790D01*
X740995Y35680D01*
X741075Y35580D01*
X741175Y35500D01*
X741285Y35440D01*
X741410Y35400D01*
X741535Y35390D01*
G37*
G36*
G01X736811D02*
X736936Y35400D01*
X737061Y35440D01*
X737171Y35500D01*
X737271Y35580D01*
X737351Y35680D01*
X737411Y35790D01*
X737451Y35915D01*
X737461Y36040D01*
Y37170D01*
X737491Y37200D01*
X737591Y37340D01*
X737611Y37380D01*
X737626Y37415D01*
X737646Y37455D01*
X737661Y37495D01*
X737671Y37535D01*
X737686Y37580D01*
X737691Y37620D01*
X737701Y37660D01*
X737706Y37705D01*
Y37745D01*
X737711Y37790D01*
X737706Y37835D01*
Y37875D01*
X737701Y37920D01*
X737691Y37960D01*
X737686Y38000D01*
X737671Y38045D01*
X737661Y38085D01*
X737646Y38125D01*
X737626Y38165D01*
X737611Y38200D01*
X737591Y38240D01*
X737491Y38380D01*
X737461Y38410D01*
Y41840D01*
X737451Y41965D01*
X737411Y42090D01*
X737351Y42200D01*
X737271Y42300D01*
X737171Y42380D01*
X737061Y42440D01*
X736936Y42480D01*
X736811Y42490D01*
X736686Y42480D01*
X736561Y42440D01*
X736451Y42380D01*
X736351Y42300D01*
X736271Y42200D01*
X736211Y42090D01*
X736171Y41965D01*
X736161Y41840D01*
Y38410D01*
X736131Y38380D01*
X736031Y38240D01*
X736011Y38200D01*
X735996Y38165D01*
X735976Y38125D01*
X735961Y38085D01*
X735951Y38045D01*
X735936Y38000D01*
X735931Y37960D01*
X735921Y37920D01*
X735916Y37875D01*
Y37835D01*
X735911Y37790D01*
X735916Y37745D01*
Y37705D01*
X735921Y37660D01*
X735931Y37620D01*
X735936Y37580D01*
X735951Y37535D01*
X735961Y37495D01*
X735976Y37455D01*
X735996Y37415D01*
X736011Y37380D01*
X736031Y37340D01*
X736131Y37200D01*
X736161Y37170D01*
Y36040D01*
X736171Y35915D01*
X736211Y35790D01*
X736271Y35680D01*
X736351Y35580D01*
X736451Y35500D01*
X736561Y35440D01*
X736686Y35400D01*
X736811Y35390D01*
G37*
G36*
G01X732086D02*
X732211Y35400D01*
X732336Y35440D01*
X732446Y35500D01*
X732546Y35580D01*
X732626Y35680D01*
X732686Y35790D01*
X732726Y35915D01*
X732736Y36040D01*
Y37170D01*
X732766Y37200D01*
X732866Y37340D01*
X732886Y37380D01*
X732901Y37415D01*
X732921Y37455D01*
X732936Y37495D01*
X732946Y37535D01*
X732961Y37580D01*
X732966Y37620D01*
X732976Y37660D01*
X732981Y37705D01*
Y37745D01*
X732986Y37790D01*
X732981Y37835D01*
Y37875D01*
X732976Y37920D01*
X732966Y37960D01*
X732961Y38000D01*
X732946Y38045D01*
X732936Y38085D01*
X732921Y38125D01*
X732901Y38165D01*
X732886Y38200D01*
X732866Y38240D01*
X732766Y38380D01*
X732736Y38410D01*
Y41840D01*
X732726Y41965D01*
X732686Y42090D01*
X732626Y42200D01*
X732546Y42300D01*
X732446Y42380D01*
X732336Y42440D01*
X732211Y42480D01*
X732086Y42490D01*
X731961Y42480D01*
X731836Y42440D01*
X731726Y42380D01*
X731626Y42300D01*
X731546Y42200D01*
X731486Y42090D01*
X731446Y41965D01*
X731436Y41840D01*
Y38410D01*
X731406Y38380D01*
X731306Y38240D01*
X731286Y38200D01*
X731271Y38165D01*
X731251Y38125D01*
X731236Y38085D01*
X731226Y38045D01*
X731211Y38000D01*
X731206Y37960D01*
X731196Y37920D01*
X731191Y37875D01*
Y37835D01*
X731186Y37790D01*
X731191Y37745D01*
Y37705D01*
X731196Y37660D01*
X731206Y37620D01*
X731211Y37580D01*
X731226Y37535D01*
X731236Y37495D01*
X731251Y37455D01*
X731271Y37415D01*
X731286Y37380D01*
X731306Y37340D01*
X731406Y37200D01*
X731436Y37170D01*
Y36040D01*
X731446Y35915D01*
X731486Y35790D01*
X731546Y35680D01*
X731626Y35580D01*
X731726Y35500D01*
X731836Y35440D01*
X731961Y35400D01*
X732086Y35390D01*
G37*
G36*
G01X727362D02*
X727487Y35400D01*
X727612Y35440D01*
X727722Y35500D01*
X727822Y35580D01*
X727902Y35680D01*
X727962Y35790D01*
X728002Y35915D01*
X728012Y36040D01*
Y37170D01*
X728042Y37200D01*
X728142Y37340D01*
X728162Y37380D01*
X728177Y37415D01*
X728197Y37455D01*
X728212Y37495D01*
X728222Y37535D01*
X728237Y37580D01*
X728242Y37620D01*
X728252Y37660D01*
X728257Y37705D01*
Y37745D01*
X728262Y37790D01*
X728257Y37835D01*
Y37875D01*
X728252Y37920D01*
X728242Y37960D01*
X728237Y38000D01*
X728222Y38045D01*
X728212Y38085D01*
X728197Y38125D01*
X728177Y38165D01*
X728162Y38200D01*
X728142Y38240D01*
X728042Y38380D01*
X728012Y38410D01*
Y41840D01*
X728002Y41965D01*
X727962Y42090D01*
X727902Y42200D01*
X727822Y42300D01*
X727722Y42380D01*
X727612Y42440D01*
X727487Y42480D01*
X727362Y42490D01*
X727237Y42480D01*
X727112Y42440D01*
X727002Y42380D01*
X726902Y42300D01*
X726822Y42200D01*
X726762Y42090D01*
X726722Y41965D01*
X726712Y41840D01*
Y38410D01*
X726682Y38380D01*
X726582Y38240D01*
X726562Y38200D01*
X726547Y38165D01*
X726527Y38125D01*
X726512Y38085D01*
X726502Y38045D01*
X726487Y38000D01*
X726482Y37960D01*
X726472Y37920D01*
X726467Y37875D01*
Y37835D01*
X726462Y37790D01*
X726467Y37745D01*
Y37705D01*
X726472Y37660D01*
X726482Y37620D01*
X726487Y37580D01*
X726502Y37535D01*
X726512Y37495D01*
X726527Y37455D01*
X726547Y37415D01*
X726562Y37380D01*
X726582Y37340D01*
X726682Y37200D01*
X726712Y37170D01*
Y36040D01*
X726722Y35915D01*
X726762Y35790D01*
X726822Y35680D01*
X726902Y35580D01*
X727002Y35500D01*
X727112Y35440D01*
X727237Y35400D01*
X727362Y35390D01*
G37*
G36*
G01X750984D02*
X751109Y35400D01*
X751234Y35440D01*
X751344Y35500D01*
X751444Y35580D01*
X751524Y35680D01*
X751584Y35790D01*
X751624Y35915D01*
X751634Y36040D01*
Y37170D01*
X751664Y37200D01*
X751764Y37340D01*
X751784Y37380D01*
X751799Y37415D01*
X751819Y37455D01*
X751834Y37495D01*
X751844Y37535D01*
X751859Y37580D01*
X751864Y37620D01*
X751874Y37660D01*
X751879Y37705D01*
Y37745D01*
X751884Y37790D01*
X751879Y37835D01*
Y37875D01*
X751874Y37920D01*
X751864Y37960D01*
X751859Y38000D01*
X751844Y38045D01*
X751834Y38085D01*
X751819Y38125D01*
X751799Y38165D01*
X751784Y38200D01*
X751764Y38240D01*
X751664Y38380D01*
X751634Y38410D01*
Y41840D01*
X751624Y41965D01*
X751584Y42090D01*
X751524Y42200D01*
X751444Y42300D01*
X751344Y42380D01*
X751234Y42440D01*
X751109Y42480D01*
X750984Y42490D01*
X750859Y42480D01*
X750734Y42440D01*
X750624Y42380D01*
X750524Y42300D01*
X750444Y42200D01*
X750384Y42090D01*
X750344Y41965D01*
X750334Y41840D01*
Y38410D01*
X750304Y38380D01*
X750204Y38240D01*
X750184Y38200D01*
X750169Y38165D01*
X750149Y38125D01*
X750134Y38085D01*
X750124Y38045D01*
X750109Y38000D01*
X750104Y37960D01*
X750094Y37920D01*
X750089Y37875D01*
Y37835D01*
X750084Y37790D01*
X750089Y37745D01*
Y37705D01*
X750094Y37660D01*
X750104Y37620D01*
X750109Y37580D01*
X750124Y37535D01*
X750134Y37495D01*
X750149Y37455D01*
X750169Y37415D01*
X750184Y37380D01*
X750204Y37340D01*
X750304Y37200D01*
X750334Y37170D01*
Y36040D01*
X750344Y35915D01*
X750384Y35790D01*
X750444Y35680D01*
X750524Y35580D01*
X750624Y35500D01*
X750734Y35440D01*
X750859Y35400D01*
X750984Y35390D01*
G37*
G36*
G01X746260D02*
X746385Y35400D01*
X746510Y35440D01*
X746620Y35500D01*
X746720Y35580D01*
X746800Y35680D01*
X746860Y35790D01*
X746900Y35915D01*
X746910Y36040D01*
Y37170D01*
X746940Y37200D01*
X747040Y37340D01*
X747060Y37380D01*
X747075Y37415D01*
X747095Y37455D01*
X747110Y37495D01*
X747120Y37535D01*
X747135Y37580D01*
X747140Y37620D01*
X747150Y37660D01*
X747155Y37705D01*
Y37745D01*
X747160Y37790D01*
X747155Y37835D01*
Y37875D01*
X747150Y37920D01*
X747140Y37960D01*
X747135Y38000D01*
X747120Y38045D01*
X747110Y38085D01*
X747095Y38125D01*
X747075Y38165D01*
X747060Y38200D01*
X747040Y38240D01*
X746940Y38380D01*
X746910Y38410D01*
Y41840D01*
X746900Y41965D01*
X746860Y42090D01*
X746800Y42200D01*
X746720Y42300D01*
X746620Y42380D01*
X746510Y42440D01*
X746385Y42480D01*
X746260Y42490D01*
X746135Y42480D01*
X746010Y42440D01*
X745900Y42380D01*
X745800Y42300D01*
X745720Y42200D01*
X745660Y42090D01*
X745620Y41965D01*
X745610Y41840D01*
Y38410D01*
X745580Y38380D01*
X745480Y38240D01*
X745460Y38200D01*
X745445Y38165D01*
X745425Y38125D01*
X745410Y38085D01*
X745400Y38045D01*
X745385Y38000D01*
X745380Y37960D01*
X745370Y37920D01*
X745365Y37875D01*
Y37835D01*
X745360Y37790D01*
X745365Y37745D01*
Y37705D01*
X745370Y37660D01*
X745380Y37620D01*
X745385Y37580D01*
X745400Y37535D01*
X745410Y37495D01*
X745425Y37455D01*
X745445Y37415D01*
X745460Y37380D01*
X745480Y37340D01*
X745580Y37200D01*
X745610Y37170D01*
Y36040D01*
X745620Y35915D01*
X745660Y35790D01*
X745720Y35680D01*
X745800Y35580D01*
X745900Y35500D01*
X746010Y35440D01*
X746135Y35400D01*
X746260Y35390D01*
G37*
G54D79*
X429500Y255413D03*
Y269587D03*
G36*
G01X500591Y250006D02*
X500466Y249996D01*
X500341Y249956D01*
X500231Y249896D01*
X500131Y249816D01*
X500051Y249716D01*
X499991Y249606D01*
X499951Y249481D01*
X499941Y249356D01*
Y247231D01*
X499911Y247201D01*
X499886Y247166D01*
X499856Y247131D01*
X499836Y247096D01*
X499811Y247061D01*
X499771Y246981D01*
X499726Y246861D01*
X499716Y246821D01*
X499706Y246776D01*
X499701Y246736D01*
X499691Y246691D01*
Y246521D01*
X499701Y246476D01*
X499706Y246436D01*
X499716Y246391D01*
X499726Y246351D01*
X499771Y246231D01*
X499811Y246151D01*
X499836Y246116D01*
X499856Y246081D01*
X499886Y246046D01*
X499911Y246011D01*
X499941Y245981D01*
Y243556D01*
X499951Y243431D01*
X499991Y243306D01*
X500051Y243196D01*
X500131Y243096D01*
X500231Y243016D01*
X500341Y242956D01*
X500466Y242916D01*
X500591Y242906D01*
X500716Y242916D01*
X500841Y242956D01*
X500951Y243016D01*
X501051Y243096D01*
X501131Y243196D01*
X501191Y243306D01*
X501231Y243431D01*
X501241Y243556D01*
Y245986D01*
X501271Y246016D01*
X501371Y246156D01*
X501391Y246196D01*
X501406Y246231D01*
X501426Y246271D01*
X501441Y246311D01*
X501451Y246351D01*
X501466Y246396D01*
X501471Y246436D01*
X501481Y246476D01*
X501486Y246521D01*
Y246561D01*
X501491Y246606D01*
X501486Y246651D01*
Y246691D01*
X501481Y246736D01*
X501471Y246776D01*
X501466Y246816D01*
X501451Y246861D01*
X501441Y246901D01*
X501426Y246941D01*
X501406Y246981D01*
X501391Y247016D01*
X501371Y247056D01*
X501271Y247196D01*
X501241Y247226D01*
Y249356D01*
X501231Y249481D01*
X501191Y249606D01*
X501131Y249716D01*
X501051Y249816D01*
X500951Y249896D01*
X500841Y249956D01*
X500716Y249996D01*
X500591Y250006D01*
G37*
G36*
G01X505315D02*
X505190Y249996D01*
X505065Y249956D01*
X504955Y249896D01*
X504855Y249816D01*
X504775Y249716D01*
X504715Y249606D01*
X504675Y249481D01*
X504665Y249356D01*
Y247231D01*
X504635Y247201D01*
X504610Y247166D01*
X504580Y247131D01*
X504560Y247096D01*
X504535Y247061D01*
X504495Y246981D01*
X504450Y246861D01*
X504440Y246821D01*
X504430Y246776D01*
X504425Y246736D01*
X504415Y246691D01*
Y246521D01*
X504425Y246476D01*
X504430Y246436D01*
X504440Y246391D01*
X504450Y246351D01*
X504495Y246231D01*
X504535Y246151D01*
X504560Y246116D01*
X504580Y246081D01*
X504610Y246046D01*
X504635Y246011D01*
X504665Y245981D01*
Y243556D01*
X504675Y243431D01*
X504715Y243306D01*
X504775Y243196D01*
X504855Y243096D01*
X504955Y243016D01*
X505065Y242956D01*
X505190Y242916D01*
X505315Y242906D01*
X505440Y242916D01*
X505565Y242956D01*
X505675Y243016D01*
X505775Y243096D01*
X505855Y243196D01*
X505915Y243306D01*
X505955Y243431D01*
X505965Y243556D01*
Y245986D01*
X505995Y246016D01*
X506095Y246156D01*
X506115Y246196D01*
X506130Y246231D01*
X506150Y246271D01*
X506165Y246311D01*
X506175Y246351D01*
X506190Y246396D01*
X506195Y246436D01*
X506205Y246476D01*
X506210Y246521D01*
Y246561D01*
X506215Y246606D01*
X506210Y246651D01*
Y246691D01*
X506205Y246736D01*
X506195Y246776D01*
X506190Y246816D01*
X506175Y246861D01*
X506165Y246901D01*
X506150Y246941D01*
X506130Y246981D01*
X506115Y247016D01*
X506095Y247056D01*
X505995Y247196D01*
X505965Y247226D01*
Y249356D01*
X505955Y249481D01*
X505915Y249606D01*
X505855Y249716D01*
X505775Y249816D01*
X505675Y249896D01*
X505565Y249956D01*
X505440Y249996D01*
X505315Y250006D01*
G37*
G36*
G01X510040D02*
X509915Y249996D01*
X509790Y249956D01*
X509680Y249896D01*
X509580Y249816D01*
X509500Y249716D01*
X509440Y249606D01*
X509400Y249481D01*
X509390Y249356D01*
Y247231D01*
X509360Y247201D01*
X509335Y247166D01*
X509305Y247131D01*
X509285Y247096D01*
X509260Y247061D01*
X509220Y246981D01*
X509175Y246861D01*
X509165Y246821D01*
X509155Y246776D01*
X509150Y246736D01*
X509140Y246691D01*
Y246521D01*
X509150Y246476D01*
X509155Y246436D01*
X509165Y246391D01*
X509175Y246351D01*
X509220Y246231D01*
X509260Y246151D01*
X509285Y246116D01*
X509305Y246081D01*
X509335Y246046D01*
X509360Y246011D01*
X509390Y245981D01*
Y243556D01*
X509400Y243431D01*
X509440Y243306D01*
X509500Y243196D01*
X509580Y243096D01*
X509680Y243016D01*
X509790Y242956D01*
X509915Y242916D01*
X510040Y242906D01*
X510165Y242916D01*
X510290Y242956D01*
X510400Y243016D01*
X510500Y243096D01*
X510580Y243196D01*
X510640Y243306D01*
X510680Y243431D01*
X510690Y243556D01*
Y245986D01*
X510720Y246016D01*
X510820Y246156D01*
X510840Y246196D01*
X510855Y246231D01*
X510875Y246271D01*
X510890Y246311D01*
X510900Y246351D01*
X510915Y246396D01*
X510920Y246436D01*
X510930Y246476D01*
X510935Y246521D01*
Y246561D01*
X510940Y246606D01*
X510935Y246651D01*
Y246691D01*
X510930Y246736D01*
X510920Y246776D01*
X510915Y246816D01*
X510900Y246861D01*
X510890Y246901D01*
X510875Y246941D01*
X510855Y246981D01*
X510840Y247016D01*
X510820Y247056D01*
X510720Y247196D01*
X510690Y247226D01*
Y249356D01*
X510680Y249481D01*
X510640Y249606D01*
X510580Y249716D01*
X510500Y249816D01*
X510400Y249896D01*
X510290Y249956D01*
X510165Y249996D01*
X510040Y250006D01*
G37*
G36*
G01X514764D02*
X514639Y249996D01*
X514514Y249956D01*
X514404Y249896D01*
X514304Y249816D01*
X514224Y249716D01*
X514164Y249606D01*
X514124Y249481D01*
X514114Y249356D01*
Y247231D01*
X514084Y247201D01*
X514059Y247166D01*
X514029Y247131D01*
X514009Y247096D01*
X513984Y247061D01*
X513944Y246981D01*
X513899Y246861D01*
X513889Y246821D01*
X513879Y246776D01*
X513874Y246736D01*
X513864Y246691D01*
Y246521D01*
X513874Y246476D01*
X513879Y246436D01*
X513889Y246391D01*
X513899Y246351D01*
X513944Y246231D01*
X513984Y246151D01*
X514009Y246116D01*
X514029Y246081D01*
X514059Y246046D01*
X514084Y246011D01*
X514114Y245981D01*
Y243556D01*
X514124Y243431D01*
X514164Y243306D01*
X514224Y243196D01*
X514304Y243096D01*
X514404Y243016D01*
X514514Y242956D01*
X514639Y242916D01*
X514764Y242906D01*
X514889Y242916D01*
X515014Y242956D01*
X515124Y243016D01*
X515224Y243096D01*
X515304Y243196D01*
X515364Y243306D01*
X515404Y243431D01*
X515414Y243556D01*
Y245986D01*
X515444Y246016D01*
X515544Y246156D01*
X515564Y246196D01*
X515579Y246231D01*
X515599Y246271D01*
X515614Y246311D01*
X515624Y246351D01*
X515639Y246396D01*
X515644Y246436D01*
X515654Y246476D01*
X515659Y246521D01*
Y246561D01*
X515664Y246606D01*
X515659Y246651D01*
Y246691D01*
X515654Y246736D01*
X515644Y246776D01*
X515639Y246816D01*
X515624Y246861D01*
X515614Y246901D01*
X515599Y246941D01*
X515579Y246981D01*
X515564Y247016D01*
X515544Y247056D01*
X515444Y247196D01*
X515414Y247226D01*
Y249356D01*
X515404Y249481D01*
X515364Y249606D01*
X515304Y249716D01*
X515224Y249816D01*
X515124Y249896D01*
X515014Y249956D01*
X514889Y249996D01*
X514764Y250006D01*
G37*
G36*
G01X519488D02*
X519363Y249996D01*
X519238Y249956D01*
X519128Y249896D01*
X519028Y249816D01*
X518948Y249716D01*
X518888Y249606D01*
X518848Y249481D01*
X518838Y249356D01*
Y247231D01*
X518808Y247201D01*
X518783Y247166D01*
X518753Y247131D01*
X518733Y247096D01*
X518708Y247061D01*
X518668Y246981D01*
X518623Y246861D01*
X518613Y246821D01*
X518603Y246776D01*
X518598Y246736D01*
X518588Y246691D01*
Y246521D01*
X518598Y246476D01*
X518603Y246436D01*
X518613Y246391D01*
X518623Y246351D01*
X518668Y246231D01*
X518708Y246151D01*
X518733Y246116D01*
X518753Y246081D01*
X518783Y246046D01*
X518808Y246011D01*
X518838Y245981D01*
Y243556D01*
X518848Y243431D01*
X518888Y243306D01*
X518948Y243196D01*
X519028Y243096D01*
X519128Y243016D01*
X519238Y242956D01*
X519363Y242916D01*
X519488Y242906D01*
X519613Y242916D01*
X519738Y242956D01*
X519848Y243016D01*
X519948Y243096D01*
X520028Y243196D01*
X520088Y243306D01*
X520128Y243431D01*
X520138Y243556D01*
Y245986D01*
X520168Y246016D01*
X520268Y246156D01*
X520288Y246196D01*
X520303Y246231D01*
X520323Y246271D01*
X520338Y246311D01*
X520348Y246351D01*
X520363Y246396D01*
X520368Y246436D01*
X520378Y246476D01*
X520383Y246521D01*
Y246561D01*
X520388Y246606D01*
X520383Y246651D01*
Y246691D01*
X520378Y246736D01*
X520368Y246776D01*
X520363Y246816D01*
X520348Y246861D01*
X520338Y246901D01*
X520323Y246941D01*
X520303Y246981D01*
X520288Y247016D01*
X520268Y247056D01*
X520168Y247196D01*
X520138Y247226D01*
Y249356D01*
X520128Y249481D01*
X520088Y249606D01*
X520028Y249716D01*
X519948Y249816D01*
X519848Y249896D01*
X519738Y249956D01*
X519613Y249996D01*
X519488Y250006D01*
G37*
G36*
G01X524213D02*
X524088Y249996D01*
X523963Y249956D01*
X523853Y249896D01*
X523753Y249816D01*
X523673Y249716D01*
X523613Y249606D01*
X523573Y249481D01*
X523563Y249356D01*
Y247231D01*
X523533Y247201D01*
X523508Y247166D01*
X523478Y247131D01*
X523458Y247096D01*
X523433Y247061D01*
X523393Y246981D01*
X523348Y246861D01*
X523338Y246821D01*
X523328Y246776D01*
X523323Y246736D01*
X523313Y246691D01*
Y246521D01*
X523323Y246476D01*
X523328Y246436D01*
X523338Y246391D01*
X523348Y246351D01*
X523393Y246231D01*
X523433Y246151D01*
X523458Y246116D01*
X523478Y246081D01*
X523508Y246046D01*
X523533Y246011D01*
X523563Y245981D01*
Y243556D01*
X523573Y243431D01*
X523613Y243306D01*
X523673Y243196D01*
X523753Y243096D01*
X523853Y243016D01*
X523963Y242956D01*
X524088Y242916D01*
X524213Y242906D01*
X524338Y242916D01*
X524463Y242956D01*
X524573Y243016D01*
X524673Y243096D01*
X524753Y243196D01*
X524813Y243306D01*
X524853Y243431D01*
X524863Y243556D01*
Y245986D01*
X524893Y246016D01*
X524993Y246156D01*
X525013Y246196D01*
X525028Y246231D01*
X525048Y246271D01*
X525063Y246311D01*
X525073Y246351D01*
X525088Y246396D01*
X525093Y246436D01*
X525103Y246476D01*
X525108Y246521D01*
Y246561D01*
X525113Y246606D01*
X525108Y246651D01*
Y246691D01*
X525103Y246736D01*
X525093Y246776D01*
X525088Y246816D01*
X525073Y246861D01*
X525063Y246901D01*
X525048Y246941D01*
X525028Y246981D01*
X525013Y247016D01*
X524993Y247056D01*
X524893Y247196D01*
X524863Y247226D01*
Y249356D01*
X524853Y249481D01*
X524813Y249606D01*
X524753Y249716D01*
X524673Y249816D01*
X524573Y249896D01*
X524463Y249956D01*
X524338Y249996D01*
X524213Y250006D01*
G37*
G36*
G01X528937D02*
X528812Y249996D01*
X528687Y249956D01*
X528577Y249896D01*
X528477Y249816D01*
X528397Y249716D01*
X528337Y249606D01*
X528297Y249481D01*
X528287Y249356D01*
Y247231D01*
X528257Y247201D01*
X528232Y247166D01*
X528202Y247131D01*
X528182Y247096D01*
X528157Y247061D01*
X528117Y246981D01*
X528072Y246861D01*
X528062Y246821D01*
X528052Y246776D01*
X528047Y246736D01*
X528037Y246691D01*
Y246521D01*
X528047Y246476D01*
X528052Y246436D01*
X528062Y246391D01*
X528072Y246351D01*
X528117Y246231D01*
X528157Y246151D01*
X528182Y246116D01*
X528202Y246081D01*
X528232Y246046D01*
X528257Y246011D01*
X528287Y245981D01*
Y243556D01*
X528297Y243431D01*
X528337Y243306D01*
X528397Y243196D01*
X528477Y243096D01*
X528577Y243016D01*
X528687Y242956D01*
X528812Y242916D01*
X528937Y242906D01*
X529062Y242916D01*
X529187Y242956D01*
X529297Y243016D01*
X529397Y243096D01*
X529477Y243196D01*
X529537Y243306D01*
X529577Y243431D01*
X529587Y243556D01*
Y245986D01*
X529617Y246016D01*
X529717Y246156D01*
X529737Y246196D01*
X529752Y246231D01*
X529772Y246271D01*
X529787Y246311D01*
X529797Y246351D01*
X529812Y246396D01*
X529817Y246436D01*
X529827Y246476D01*
X529832Y246521D01*
Y246561D01*
X529837Y246606D01*
X529832Y246651D01*
Y246691D01*
X529827Y246736D01*
X529817Y246776D01*
X529812Y246816D01*
X529797Y246861D01*
X529787Y246901D01*
X529772Y246941D01*
X529752Y246981D01*
X529737Y247016D01*
X529717Y247056D01*
X529617Y247196D01*
X529587Y247226D01*
Y249356D01*
X529577Y249481D01*
X529537Y249606D01*
X529477Y249716D01*
X529397Y249816D01*
X529297Y249896D01*
X529187Y249956D01*
X529062Y249996D01*
X528937Y250006D01*
G37*
G36*
G01X533662D02*
X533537Y249996D01*
X533412Y249956D01*
X533302Y249896D01*
X533202Y249816D01*
X533122Y249716D01*
X533062Y249606D01*
X533022Y249481D01*
X533012Y249356D01*
Y247231D01*
X532982Y247201D01*
X532957Y247166D01*
X532927Y247131D01*
X532907Y247096D01*
X532882Y247061D01*
X532842Y246981D01*
X532797Y246861D01*
X532787Y246821D01*
X532777Y246776D01*
X532772Y246736D01*
X532762Y246691D01*
Y246521D01*
X532772Y246476D01*
X532777Y246436D01*
X532787Y246391D01*
X532797Y246351D01*
X532842Y246231D01*
X532882Y246151D01*
X532907Y246116D01*
X532927Y246081D01*
X532957Y246046D01*
X532982Y246011D01*
X533012Y245981D01*
Y243556D01*
X533022Y243431D01*
X533062Y243306D01*
X533122Y243196D01*
X533202Y243096D01*
X533302Y243016D01*
X533412Y242956D01*
X533537Y242916D01*
X533662Y242906D01*
X533787Y242916D01*
X533912Y242956D01*
X534022Y243016D01*
X534122Y243096D01*
X534202Y243196D01*
X534262Y243306D01*
X534302Y243431D01*
X534312Y243556D01*
Y245986D01*
X534342Y246016D01*
X534442Y246156D01*
X534462Y246196D01*
X534477Y246231D01*
X534497Y246271D01*
X534512Y246311D01*
X534522Y246351D01*
X534537Y246396D01*
X534542Y246436D01*
X534552Y246476D01*
X534557Y246521D01*
Y246561D01*
X534562Y246606D01*
X534557Y246651D01*
Y246691D01*
X534552Y246736D01*
X534542Y246776D01*
X534537Y246816D01*
X534522Y246861D01*
X534512Y246901D01*
X534497Y246941D01*
X534477Y246981D01*
X534462Y247016D01*
X534442Y247056D01*
X534342Y247196D01*
X534312Y247226D01*
Y249356D01*
X534302Y249481D01*
X534262Y249606D01*
X534202Y249716D01*
X534122Y249816D01*
X534022Y249896D01*
X533912Y249956D01*
X533787Y249996D01*
X533662Y250006D01*
G37*
G36*
G01X538386D02*
X538261Y249996D01*
X538136Y249956D01*
X538026Y249896D01*
X537926Y249816D01*
X537846Y249716D01*
X537786Y249606D01*
X537746Y249481D01*
X537736Y249356D01*
Y247231D01*
X537706Y247201D01*
X537681Y247166D01*
X537651Y247131D01*
X537631Y247096D01*
X537606Y247061D01*
X537566Y246981D01*
X537521Y246861D01*
X537511Y246821D01*
X537501Y246776D01*
X537496Y246736D01*
X537486Y246691D01*
Y246521D01*
X537496Y246476D01*
X537501Y246436D01*
X537511Y246391D01*
X537521Y246351D01*
X537566Y246231D01*
X537606Y246151D01*
X537631Y246116D01*
X537651Y246081D01*
X537681Y246046D01*
X537706Y246011D01*
X537736Y245981D01*
Y243556D01*
X537746Y243431D01*
X537786Y243306D01*
X537846Y243196D01*
X537926Y243096D01*
X538026Y243016D01*
X538136Y242956D01*
X538261Y242916D01*
X538386Y242906D01*
X538511Y242916D01*
X538636Y242956D01*
X538746Y243016D01*
X538846Y243096D01*
X538926Y243196D01*
X538986Y243306D01*
X539026Y243431D01*
X539036Y243556D01*
Y245986D01*
X539066Y246016D01*
X539166Y246156D01*
X539186Y246196D01*
X539201Y246231D01*
X539221Y246271D01*
X539236Y246311D01*
X539246Y246351D01*
X539261Y246396D01*
X539266Y246436D01*
X539276Y246476D01*
X539281Y246521D01*
Y246561D01*
X539286Y246606D01*
X539281Y246651D01*
Y246691D01*
X539276Y246736D01*
X539266Y246776D01*
X539261Y246816D01*
X539246Y246861D01*
X539236Y246901D01*
X539221Y246941D01*
X539201Y246981D01*
X539186Y247016D01*
X539166Y247056D01*
X539066Y247196D01*
X539036Y247226D01*
Y249356D01*
X539026Y249481D01*
X538986Y249606D01*
X538926Y249716D01*
X538846Y249816D01*
X538746Y249896D01*
X538636Y249956D01*
X538511Y249996D01*
X538386Y250006D01*
G37*
G36*
G01X543110D02*
X542985Y249996D01*
X542860Y249956D01*
X542750Y249896D01*
X542650Y249816D01*
X542570Y249716D01*
X542510Y249606D01*
X542470Y249481D01*
X542460Y249356D01*
Y247231D01*
X542430Y247201D01*
X542405Y247166D01*
X542375Y247131D01*
X542355Y247096D01*
X542330Y247061D01*
X542290Y246981D01*
X542245Y246861D01*
X542235Y246821D01*
X542225Y246776D01*
X542220Y246736D01*
X542210Y246691D01*
Y246521D01*
X542220Y246476D01*
X542225Y246436D01*
X542235Y246391D01*
X542245Y246351D01*
X542290Y246231D01*
X542330Y246151D01*
X542355Y246116D01*
X542375Y246081D01*
X542405Y246046D01*
X542430Y246011D01*
X542460Y245981D01*
Y243556D01*
X542470Y243431D01*
X542510Y243306D01*
X542570Y243196D01*
X542650Y243096D01*
X542750Y243016D01*
X542860Y242956D01*
X542985Y242916D01*
X543110Y242906D01*
X543235Y242916D01*
X543360Y242956D01*
X543470Y243016D01*
X543570Y243096D01*
X543650Y243196D01*
X543710Y243306D01*
X543750Y243431D01*
X543760Y243556D01*
Y245986D01*
X543790Y246016D01*
X543890Y246156D01*
X543910Y246196D01*
X543925Y246231D01*
X543945Y246271D01*
X543960Y246311D01*
X543970Y246351D01*
X543985Y246396D01*
X543990Y246436D01*
X544000Y246476D01*
X544005Y246521D01*
Y246561D01*
X544010Y246606D01*
X544005Y246651D01*
Y246691D01*
X544000Y246736D01*
X543990Y246776D01*
X543985Y246816D01*
X543970Y246861D01*
X543960Y246901D01*
X543945Y246941D01*
X543925Y246981D01*
X543910Y247016D01*
X543890Y247056D01*
X543790Y247196D01*
X543760Y247226D01*
Y249356D01*
X543750Y249481D01*
X543710Y249606D01*
X543650Y249716D01*
X543570Y249816D01*
X543470Y249896D01*
X543360Y249956D01*
X543235Y249996D01*
X543110Y250006D01*
G37*
G36*
G01X547835D02*
X547710Y249996D01*
X547585Y249956D01*
X547475Y249896D01*
X547375Y249816D01*
X547295Y249716D01*
X547235Y249606D01*
X547195Y249481D01*
X547185Y249356D01*
Y247231D01*
X547155Y247201D01*
X547130Y247166D01*
X547100Y247131D01*
X547080Y247096D01*
X547055Y247061D01*
X547015Y246981D01*
X546970Y246861D01*
X546960Y246821D01*
X546950Y246776D01*
X546945Y246736D01*
X546935Y246691D01*
Y246521D01*
X546945Y246476D01*
X546950Y246436D01*
X546960Y246391D01*
X546970Y246351D01*
X547015Y246231D01*
X547055Y246151D01*
X547080Y246116D01*
X547100Y246081D01*
X547130Y246046D01*
X547155Y246011D01*
X547185Y245981D01*
Y243556D01*
X547195Y243431D01*
X547235Y243306D01*
X547295Y243196D01*
X547375Y243096D01*
X547475Y243016D01*
X547585Y242956D01*
X547710Y242916D01*
X547835Y242906D01*
X547960Y242916D01*
X548085Y242956D01*
X548195Y243016D01*
X548295Y243096D01*
X548375Y243196D01*
X548435Y243306D01*
X548475Y243431D01*
X548485Y243556D01*
Y245986D01*
X548515Y246016D01*
X548615Y246156D01*
X548635Y246196D01*
X548650Y246231D01*
X548670Y246271D01*
X548685Y246311D01*
X548695Y246351D01*
X548710Y246396D01*
X548715Y246436D01*
X548725Y246476D01*
X548730Y246521D01*
Y246561D01*
X548735Y246606D01*
X548730Y246651D01*
Y246691D01*
X548725Y246736D01*
X548715Y246776D01*
X548710Y246816D01*
X548695Y246861D01*
X548685Y246901D01*
X548670Y246941D01*
X548650Y246981D01*
X548635Y247016D01*
X548615Y247056D01*
X548515Y247196D01*
X548485Y247226D01*
Y249356D01*
X548475Y249481D01*
X548435Y249606D01*
X548375Y249716D01*
X548295Y249816D01*
X548195Y249896D01*
X548085Y249956D01*
X547960Y249996D01*
X547835Y250006D01*
G37*
G36*
G01X552559D02*
X552434Y249996D01*
X552309Y249956D01*
X552199Y249896D01*
X552099Y249816D01*
X552019Y249716D01*
X551959Y249606D01*
X551919Y249481D01*
X551909Y249356D01*
Y247231D01*
X551879Y247201D01*
X551854Y247166D01*
X551824Y247131D01*
X551804Y247096D01*
X551779Y247061D01*
X551739Y246981D01*
X551694Y246861D01*
X551684Y246821D01*
X551674Y246776D01*
X551669Y246736D01*
X551659Y246691D01*
Y246521D01*
X551669Y246476D01*
X551674Y246436D01*
X551684Y246391D01*
X551694Y246351D01*
X551739Y246231D01*
X551779Y246151D01*
X551804Y246116D01*
X551824Y246081D01*
X551854Y246046D01*
X551879Y246011D01*
X551909Y245981D01*
Y243556D01*
X551919Y243431D01*
X551959Y243306D01*
X552019Y243196D01*
X552099Y243096D01*
X552199Y243016D01*
X552309Y242956D01*
X552434Y242916D01*
X552559Y242906D01*
X552684Y242916D01*
X552809Y242956D01*
X552919Y243016D01*
X553019Y243096D01*
X553099Y243196D01*
X553159Y243306D01*
X553199Y243431D01*
X553209Y243556D01*
Y245986D01*
X553239Y246016D01*
X553339Y246156D01*
X553359Y246196D01*
X553374Y246231D01*
X553394Y246271D01*
X553409Y246311D01*
X553419Y246351D01*
X553434Y246396D01*
X553439Y246436D01*
X553449Y246476D01*
X553454Y246521D01*
Y246561D01*
X553459Y246606D01*
X553454Y246651D01*
Y246691D01*
X553449Y246736D01*
X553439Y246776D01*
X553434Y246816D01*
X553419Y246861D01*
X553409Y246901D01*
X553394Y246941D01*
X553374Y246981D01*
X553359Y247016D01*
X553339Y247056D01*
X553239Y247196D01*
X553209Y247226D01*
Y249356D01*
X553199Y249481D01*
X553159Y249606D01*
X553099Y249716D01*
X553019Y249816D01*
X552919Y249896D01*
X552809Y249956D01*
X552684Y249996D01*
X552559Y250006D01*
G37*
G36*
G01X557284D02*
X557159Y249996D01*
X557034Y249956D01*
X556924Y249896D01*
X556824Y249816D01*
X556744Y249716D01*
X556684Y249606D01*
X556644Y249481D01*
X556634Y249356D01*
Y247231D01*
X556604Y247201D01*
X556579Y247166D01*
X556549Y247131D01*
X556529Y247096D01*
X556504Y247061D01*
X556464Y246981D01*
X556419Y246861D01*
X556409Y246821D01*
X556399Y246776D01*
X556394Y246736D01*
X556384Y246691D01*
Y246521D01*
X556394Y246476D01*
X556399Y246436D01*
X556409Y246391D01*
X556419Y246351D01*
X556464Y246231D01*
X556504Y246151D01*
X556529Y246116D01*
X556549Y246081D01*
X556579Y246046D01*
X556604Y246011D01*
X556634Y245981D01*
Y243556D01*
X556644Y243431D01*
X556684Y243306D01*
X556744Y243196D01*
X556824Y243096D01*
X556924Y243016D01*
X557034Y242956D01*
X557159Y242916D01*
X557284Y242906D01*
X557409Y242916D01*
X557534Y242956D01*
X557644Y243016D01*
X557744Y243096D01*
X557824Y243196D01*
X557884Y243306D01*
X557924Y243431D01*
X557934Y243556D01*
Y245986D01*
X557964Y246016D01*
X558064Y246156D01*
X558084Y246196D01*
X558099Y246231D01*
X558119Y246271D01*
X558134Y246311D01*
X558144Y246351D01*
X558159Y246396D01*
X558164Y246436D01*
X558174Y246476D01*
X558179Y246521D01*
Y246561D01*
X558184Y246606D01*
X558179Y246651D01*
Y246691D01*
X558174Y246736D01*
X558164Y246776D01*
X558159Y246816D01*
X558144Y246861D01*
X558134Y246901D01*
X558119Y246941D01*
X558099Y246981D01*
X558084Y247016D01*
X558064Y247056D01*
X557964Y247196D01*
X557934Y247226D01*
Y249356D01*
X557924Y249481D01*
X557884Y249606D01*
X557824Y249716D01*
X557744Y249816D01*
X557644Y249896D01*
X557534Y249956D01*
X557409Y249996D01*
X557284Y250006D01*
G37*
G36*
G01X562008D02*
X561883Y249996D01*
X561758Y249956D01*
X561648Y249896D01*
X561548Y249816D01*
X561468Y249716D01*
X561408Y249606D01*
X561368Y249481D01*
X561358Y249356D01*
Y247231D01*
X561328Y247201D01*
X561303Y247166D01*
X561273Y247131D01*
X561253Y247096D01*
X561228Y247061D01*
X561188Y246981D01*
X561143Y246861D01*
X561133Y246821D01*
X561123Y246776D01*
X561118Y246736D01*
X561108Y246691D01*
Y246521D01*
X561118Y246476D01*
X561123Y246436D01*
X561133Y246391D01*
X561143Y246351D01*
X561188Y246231D01*
X561228Y246151D01*
X561253Y246116D01*
X561273Y246081D01*
X561303Y246046D01*
X561328Y246011D01*
X561358Y245981D01*
Y243556D01*
X561368Y243431D01*
X561408Y243306D01*
X561468Y243196D01*
X561548Y243096D01*
X561648Y243016D01*
X561758Y242956D01*
X561883Y242916D01*
X562008Y242906D01*
X562133Y242916D01*
X562258Y242956D01*
X562368Y243016D01*
X562468Y243096D01*
X562548Y243196D01*
X562608Y243306D01*
X562648Y243431D01*
X562658Y243556D01*
Y245986D01*
X562688Y246016D01*
X562788Y246156D01*
X562808Y246196D01*
X562823Y246231D01*
X562843Y246271D01*
X562858Y246311D01*
X562868Y246351D01*
X562883Y246396D01*
X562888Y246436D01*
X562898Y246476D01*
X562903Y246521D01*
Y246561D01*
X562908Y246606D01*
X562903Y246651D01*
Y246691D01*
X562898Y246736D01*
X562888Y246776D01*
X562883Y246816D01*
X562868Y246861D01*
X562858Y246901D01*
X562843Y246941D01*
X562823Y246981D01*
X562808Y247016D01*
X562788Y247056D01*
X562688Y247196D01*
X562658Y247226D01*
Y249356D01*
X562648Y249481D01*
X562608Y249606D01*
X562548Y249716D01*
X562468Y249816D01*
X562368Y249896D01*
X562258Y249956D01*
X562133Y249996D01*
X562008Y250006D01*
G37*
G36*
G01X566733D02*
X566608Y249996D01*
X566483Y249956D01*
X566373Y249896D01*
X566273Y249816D01*
X566193Y249716D01*
X566133Y249606D01*
X566093Y249481D01*
X566083Y249356D01*
Y247231D01*
X566053Y247201D01*
X566028Y247166D01*
X565998Y247131D01*
X565978Y247096D01*
X565953Y247061D01*
X565913Y246981D01*
X565868Y246861D01*
X565858Y246821D01*
X565848Y246776D01*
X565843Y246736D01*
X565833Y246691D01*
Y246521D01*
X565843Y246476D01*
X565848Y246436D01*
X565858Y246391D01*
X565868Y246351D01*
X565913Y246231D01*
X565953Y246151D01*
X565978Y246116D01*
X565998Y246081D01*
X566028Y246046D01*
X566053Y246011D01*
X566083Y245981D01*
Y243556D01*
X566093Y243431D01*
X566133Y243306D01*
X566193Y243196D01*
X566273Y243096D01*
X566373Y243016D01*
X566483Y242956D01*
X566608Y242916D01*
X566733Y242906D01*
X566858Y242916D01*
X566983Y242956D01*
X567093Y243016D01*
X567193Y243096D01*
X567273Y243196D01*
X567333Y243306D01*
X567373Y243431D01*
X567383Y243556D01*
Y245986D01*
X567413Y246016D01*
X567513Y246156D01*
X567533Y246196D01*
X567548Y246231D01*
X567568Y246271D01*
X567583Y246311D01*
X567593Y246351D01*
X567608Y246396D01*
X567613Y246436D01*
X567623Y246476D01*
X567628Y246521D01*
Y246561D01*
X567633Y246606D01*
X567628Y246651D01*
Y246691D01*
X567623Y246736D01*
X567613Y246776D01*
X567608Y246816D01*
X567593Y246861D01*
X567583Y246901D01*
X567568Y246941D01*
X567548Y246981D01*
X567533Y247016D01*
X567513Y247056D01*
X567413Y247196D01*
X567383Y247226D01*
Y249356D01*
X567373Y249481D01*
X567333Y249606D01*
X567273Y249716D01*
X567193Y249816D01*
X567093Y249896D01*
X566983Y249956D01*
X566858Y249996D01*
X566733Y250006D01*
G37*
G36*
G01X571457D02*
X571332Y249996D01*
X571207Y249956D01*
X571097Y249896D01*
X570997Y249816D01*
X570917Y249716D01*
X570857Y249606D01*
X570817Y249481D01*
X570807Y249356D01*
Y247231D01*
X570777Y247201D01*
X570752Y247166D01*
X570722Y247131D01*
X570702Y247096D01*
X570677Y247061D01*
X570637Y246981D01*
X570592Y246861D01*
X570582Y246821D01*
X570572Y246776D01*
X570567Y246736D01*
X570557Y246691D01*
Y246521D01*
X570567Y246476D01*
X570572Y246436D01*
X570582Y246391D01*
X570592Y246351D01*
X570637Y246231D01*
X570677Y246151D01*
X570702Y246116D01*
X570722Y246081D01*
X570752Y246046D01*
X570777Y246011D01*
X570807Y245981D01*
Y243556D01*
X570817Y243431D01*
X570857Y243306D01*
X570917Y243196D01*
X570997Y243096D01*
X571097Y243016D01*
X571207Y242956D01*
X571332Y242916D01*
X571457Y242906D01*
X571582Y242916D01*
X571707Y242956D01*
X571817Y243016D01*
X571917Y243096D01*
X571997Y243196D01*
X572057Y243306D01*
X572097Y243431D01*
X572107Y243556D01*
Y245986D01*
X572137Y246016D01*
X572237Y246156D01*
X572257Y246196D01*
X572272Y246231D01*
X572292Y246271D01*
X572307Y246311D01*
X572317Y246351D01*
X572332Y246396D01*
X572337Y246436D01*
X572347Y246476D01*
X572352Y246521D01*
Y246561D01*
X572357Y246606D01*
X572352Y246651D01*
Y246691D01*
X572347Y246736D01*
X572337Y246776D01*
X572332Y246816D01*
X572317Y246861D01*
X572307Y246901D01*
X572292Y246941D01*
X572272Y246981D01*
X572257Y247016D01*
X572237Y247056D01*
X572137Y247196D01*
X572107Y247226D01*
Y249356D01*
X572097Y249481D01*
X572057Y249606D01*
X571997Y249716D01*
X571917Y249816D01*
X571817Y249896D01*
X571707Y249956D01*
X571582Y249996D01*
X571457Y250006D01*
G37*
G36*
G01X576181D02*
X576056Y249996D01*
X575931Y249956D01*
X575821Y249896D01*
X575721Y249816D01*
X575641Y249716D01*
X575581Y249606D01*
X575541Y249481D01*
X575531Y249356D01*
Y247231D01*
X575501Y247201D01*
X575476Y247166D01*
X575446Y247131D01*
X575426Y247096D01*
X575401Y247061D01*
X575361Y246981D01*
X575316Y246861D01*
X575306Y246821D01*
X575296Y246776D01*
X575291Y246736D01*
X575281Y246691D01*
Y246521D01*
X575291Y246476D01*
X575296Y246436D01*
X575306Y246391D01*
X575316Y246351D01*
X575361Y246231D01*
X575401Y246151D01*
X575426Y246116D01*
X575446Y246081D01*
X575476Y246046D01*
X575501Y246011D01*
X575531Y245981D01*
Y243556D01*
X575541Y243431D01*
X575581Y243306D01*
X575641Y243196D01*
X575721Y243096D01*
X575821Y243016D01*
X575931Y242956D01*
X576056Y242916D01*
X576181Y242906D01*
X576306Y242916D01*
X576431Y242956D01*
X576541Y243016D01*
X576641Y243096D01*
X576721Y243196D01*
X576781Y243306D01*
X576821Y243431D01*
X576831Y243556D01*
Y245986D01*
X576861Y246016D01*
X576961Y246156D01*
X576981Y246196D01*
X576996Y246231D01*
X577016Y246271D01*
X577031Y246311D01*
X577041Y246351D01*
X577056Y246396D01*
X577061Y246436D01*
X577071Y246476D01*
X577076Y246521D01*
Y246561D01*
X577081Y246606D01*
X577076Y246651D01*
Y246691D01*
X577071Y246736D01*
X577061Y246776D01*
X577056Y246816D01*
X577041Y246861D01*
X577031Y246901D01*
X577016Y246941D01*
X576996Y246981D01*
X576981Y247016D01*
X576961Y247056D01*
X576861Y247196D01*
X576831Y247226D01*
Y249356D01*
X576821Y249481D01*
X576781Y249606D01*
X576721Y249716D01*
X576641Y249816D01*
X576541Y249896D01*
X576431Y249956D01*
X576306Y249996D01*
X576181Y250006D01*
G37*
G36*
G01X580906D02*
X580781Y249996D01*
X580656Y249956D01*
X580546Y249896D01*
X580446Y249816D01*
X580366Y249716D01*
X580306Y249606D01*
X580266Y249481D01*
X580256Y249356D01*
Y247231D01*
X580226Y247201D01*
X580201Y247166D01*
X580171Y247131D01*
X580151Y247096D01*
X580126Y247061D01*
X580086Y246981D01*
X580041Y246861D01*
X580031Y246821D01*
X580021Y246776D01*
X580016Y246736D01*
X580006Y246691D01*
Y246521D01*
X580016Y246476D01*
X580021Y246436D01*
X580031Y246391D01*
X580041Y246351D01*
X580086Y246231D01*
X580126Y246151D01*
X580151Y246116D01*
X580171Y246081D01*
X580201Y246046D01*
X580226Y246011D01*
X580256Y245981D01*
Y243556D01*
X580266Y243431D01*
X580306Y243306D01*
X580366Y243196D01*
X580446Y243096D01*
X580546Y243016D01*
X580656Y242956D01*
X580781Y242916D01*
X580906Y242906D01*
X581031Y242916D01*
X581156Y242956D01*
X581266Y243016D01*
X581366Y243096D01*
X581446Y243196D01*
X581506Y243306D01*
X581546Y243431D01*
X581556Y243556D01*
Y245986D01*
X581586Y246016D01*
X581686Y246156D01*
X581706Y246196D01*
X581721Y246231D01*
X581741Y246271D01*
X581756Y246311D01*
X581766Y246351D01*
X581781Y246396D01*
X581786Y246436D01*
X581796Y246476D01*
X581801Y246521D01*
Y246561D01*
X581806Y246606D01*
X581801Y246651D01*
Y246691D01*
X581796Y246736D01*
X581786Y246776D01*
X581781Y246816D01*
X581766Y246861D01*
X581756Y246901D01*
X581741Y246941D01*
X581721Y246981D01*
X581706Y247016D01*
X581686Y247056D01*
X581586Y247196D01*
X581556Y247226D01*
Y249356D01*
X581546Y249481D01*
X581506Y249606D01*
X581446Y249716D01*
X581366Y249816D01*
X581266Y249896D01*
X581156Y249956D01*
X581031Y249996D01*
X580906Y250006D01*
G37*
G36*
G01X585630D02*
X585505Y249996D01*
X585380Y249956D01*
X585270Y249896D01*
X585170Y249816D01*
X585090Y249716D01*
X585030Y249606D01*
X584990Y249481D01*
X584980Y249356D01*
Y247231D01*
X584950Y247201D01*
X584925Y247166D01*
X584895Y247131D01*
X584875Y247096D01*
X584850Y247061D01*
X584810Y246981D01*
X584765Y246861D01*
X584755Y246821D01*
X584745Y246776D01*
X584740Y246736D01*
X584730Y246691D01*
Y246521D01*
X584740Y246476D01*
X584745Y246436D01*
X584755Y246391D01*
X584765Y246351D01*
X584810Y246231D01*
X584850Y246151D01*
X584875Y246116D01*
X584895Y246081D01*
X584925Y246046D01*
X584950Y246011D01*
X584980Y245981D01*
Y243556D01*
X584990Y243431D01*
X585030Y243306D01*
X585090Y243196D01*
X585170Y243096D01*
X585270Y243016D01*
X585380Y242956D01*
X585505Y242916D01*
X585630Y242906D01*
X585755Y242916D01*
X585880Y242956D01*
X585990Y243016D01*
X586090Y243096D01*
X586170Y243196D01*
X586230Y243306D01*
X586270Y243431D01*
X586280Y243556D01*
Y245986D01*
X586310Y246016D01*
X586410Y246156D01*
X586430Y246196D01*
X586445Y246231D01*
X586465Y246271D01*
X586480Y246311D01*
X586490Y246351D01*
X586505Y246396D01*
X586510Y246436D01*
X586520Y246476D01*
X586525Y246521D01*
Y246561D01*
X586530Y246606D01*
X586525Y246651D01*
Y246691D01*
X586520Y246736D01*
X586510Y246776D01*
X586505Y246816D01*
X586490Y246861D01*
X586480Y246901D01*
X586465Y246941D01*
X586445Y246981D01*
X586430Y247016D01*
X586410Y247056D01*
X586310Y247196D01*
X586280Y247226D01*
Y249356D01*
X586270Y249481D01*
X586230Y249606D01*
X586170Y249716D01*
X586090Y249816D01*
X585990Y249896D01*
X585880Y249956D01*
X585755Y249996D01*
X585630Y250006D01*
G37*
G36*
G01X590355D02*
X590230Y249996D01*
X590105Y249956D01*
X589995Y249896D01*
X589895Y249816D01*
X589815Y249716D01*
X589755Y249606D01*
X589715Y249481D01*
X589705Y249356D01*
Y247231D01*
X589675Y247201D01*
X589650Y247166D01*
X589620Y247131D01*
X589600Y247096D01*
X589575Y247061D01*
X589535Y246981D01*
X589490Y246861D01*
X589480Y246821D01*
X589470Y246776D01*
X589465Y246736D01*
X589455Y246691D01*
Y246521D01*
X589465Y246476D01*
X589470Y246436D01*
X589480Y246391D01*
X589490Y246351D01*
X589535Y246231D01*
X589575Y246151D01*
X589600Y246116D01*
X589620Y246081D01*
X589650Y246046D01*
X589675Y246011D01*
X589705Y245981D01*
Y243556D01*
X589715Y243431D01*
X589755Y243306D01*
X589815Y243196D01*
X589895Y243096D01*
X589995Y243016D01*
X590105Y242956D01*
X590230Y242916D01*
X590355Y242906D01*
X590480Y242916D01*
X590605Y242956D01*
X590715Y243016D01*
X590815Y243096D01*
X590895Y243196D01*
X590955Y243306D01*
X590995Y243431D01*
X591005Y243556D01*
Y245986D01*
X591035Y246016D01*
X591135Y246156D01*
X591155Y246196D01*
X591170Y246231D01*
X591190Y246271D01*
X591205Y246311D01*
X591215Y246351D01*
X591230Y246396D01*
X591235Y246436D01*
X591245Y246476D01*
X591250Y246521D01*
Y246561D01*
X591255Y246606D01*
X591250Y246651D01*
Y246691D01*
X591245Y246736D01*
X591235Y246776D01*
X591230Y246816D01*
X591215Y246861D01*
X591205Y246901D01*
X591190Y246941D01*
X591170Y246981D01*
X591155Y247016D01*
X591135Y247056D01*
X591035Y247196D01*
X591005Y247226D01*
Y249356D01*
X590995Y249481D01*
X590955Y249606D01*
X590895Y249716D01*
X590815Y249816D01*
X590715Y249896D01*
X590605Y249956D01*
X590480Y249996D01*
X590355Y250006D01*
G37*
G36*
G01X595079D02*
X594954Y249996D01*
X594829Y249956D01*
X594719Y249896D01*
X594619Y249816D01*
X594539Y249716D01*
X594479Y249606D01*
X594439Y249481D01*
X594429Y249356D01*
Y247231D01*
X594399Y247201D01*
X594374Y247166D01*
X594344Y247131D01*
X594324Y247096D01*
X594299Y247061D01*
X594259Y246981D01*
X594214Y246861D01*
X594204Y246821D01*
X594194Y246776D01*
X594189Y246736D01*
X594179Y246691D01*
Y246521D01*
X594189Y246476D01*
X594194Y246436D01*
X594204Y246391D01*
X594214Y246351D01*
X594259Y246231D01*
X594299Y246151D01*
X594324Y246116D01*
X594344Y246081D01*
X594374Y246046D01*
X594399Y246011D01*
X594429Y245981D01*
Y243556D01*
X594439Y243431D01*
X594479Y243306D01*
X594539Y243196D01*
X594619Y243096D01*
X594719Y243016D01*
X594829Y242956D01*
X594954Y242916D01*
X595079Y242906D01*
X595204Y242916D01*
X595329Y242956D01*
X595439Y243016D01*
X595539Y243096D01*
X595619Y243196D01*
X595679Y243306D01*
X595719Y243431D01*
X595729Y243556D01*
Y245986D01*
X595759Y246016D01*
X595859Y246156D01*
X595879Y246196D01*
X595894Y246231D01*
X595914Y246271D01*
X595929Y246311D01*
X595939Y246351D01*
X595954Y246396D01*
X595959Y246436D01*
X595969Y246476D01*
X595974Y246521D01*
Y246561D01*
X595979Y246606D01*
X595974Y246651D01*
Y246691D01*
X595969Y246736D01*
X595959Y246776D01*
X595954Y246816D01*
X595939Y246861D01*
X595929Y246901D01*
X595914Y246941D01*
X595894Y246981D01*
X595879Y247016D01*
X595859Y247056D01*
X595759Y247196D01*
X595729Y247226D01*
Y249356D01*
X595719Y249481D01*
X595679Y249606D01*
X595619Y249716D01*
X595539Y249816D01*
X595439Y249896D01*
X595329Y249956D01*
X595204Y249996D01*
X595079Y250006D01*
G37*
G36*
G01X599803D02*
X599678Y249996D01*
X599553Y249956D01*
X599443Y249896D01*
X599343Y249816D01*
X599263Y249716D01*
X599203Y249606D01*
X599163Y249481D01*
X599153Y249356D01*
Y247231D01*
X599123Y247201D01*
X599098Y247166D01*
X599068Y247131D01*
X599048Y247096D01*
X599023Y247061D01*
X598983Y246981D01*
X598938Y246861D01*
X598928Y246821D01*
X598918Y246776D01*
X598913Y246736D01*
X598903Y246691D01*
Y246521D01*
X598913Y246476D01*
X598918Y246436D01*
X598928Y246391D01*
X598938Y246351D01*
X598983Y246231D01*
X599023Y246151D01*
X599048Y246116D01*
X599068Y246081D01*
X599098Y246046D01*
X599123Y246011D01*
X599153Y245981D01*
Y243556D01*
X599163Y243431D01*
X599203Y243306D01*
X599263Y243196D01*
X599343Y243096D01*
X599443Y243016D01*
X599553Y242956D01*
X599678Y242916D01*
X599803Y242906D01*
X599928Y242916D01*
X600053Y242956D01*
X600163Y243016D01*
X600263Y243096D01*
X600343Y243196D01*
X600403Y243306D01*
X600443Y243431D01*
X600453Y243556D01*
Y245986D01*
X600483Y246016D01*
X600583Y246156D01*
X600603Y246196D01*
X600618Y246231D01*
X600638Y246271D01*
X600653Y246311D01*
X600663Y246351D01*
X600678Y246396D01*
X600683Y246436D01*
X600693Y246476D01*
X600698Y246521D01*
Y246561D01*
X600703Y246606D01*
X600698Y246651D01*
Y246691D01*
X600693Y246736D01*
X600683Y246776D01*
X600678Y246816D01*
X600663Y246861D01*
X600653Y246901D01*
X600638Y246941D01*
X600618Y246981D01*
X600603Y247016D01*
X600583Y247056D01*
X600483Y247196D01*
X600453Y247226D01*
Y249356D01*
X600443Y249481D01*
X600403Y249606D01*
X600343Y249716D01*
X600263Y249816D01*
X600163Y249896D01*
X600053Y249956D01*
X599928Y249996D01*
X599803Y250006D01*
G37*
G36*
G01X604528D02*
X604403Y249996D01*
X604278Y249956D01*
X604168Y249896D01*
X604068Y249816D01*
X603988Y249716D01*
X603928Y249606D01*
X603888Y249481D01*
X603878Y249356D01*
Y247231D01*
X603848Y247201D01*
X603823Y247166D01*
X603793Y247131D01*
X603773Y247096D01*
X603748Y247061D01*
X603708Y246981D01*
X603663Y246861D01*
X603653Y246821D01*
X603643Y246776D01*
X603638Y246736D01*
X603628Y246691D01*
Y246521D01*
X603638Y246476D01*
X603643Y246436D01*
X603653Y246391D01*
X603663Y246351D01*
X603708Y246231D01*
X603748Y246151D01*
X603773Y246116D01*
X603793Y246081D01*
X603823Y246046D01*
X603848Y246011D01*
X603878Y245981D01*
Y243556D01*
X603888Y243431D01*
X603928Y243306D01*
X603988Y243196D01*
X604068Y243096D01*
X604168Y243016D01*
X604278Y242956D01*
X604403Y242916D01*
X604528Y242906D01*
X604653Y242916D01*
X604778Y242956D01*
X604888Y243016D01*
X604988Y243096D01*
X605068Y243196D01*
X605128Y243306D01*
X605168Y243431D01*
X605178Y243556D01*
Y245986D01*
X605208Y246016D01*
X605308Y246156D01*
X605328Y246196D01*
X605343Y246231D01*
X605363Y246271D01*
X605378Y246311D01*
X605388Y246351D01*
X605403Y246396D01*
X605408Y246436D01*
X605418Y246476D01*
X605423Y246521D01*
Y246561D01*
X605428Y246606D01*
X605423Y246651D01*
Y246691D01*
X605418Y246736D01*
X605408Y246776D01*
X605403Y246816D01*
X605388Y246861D01*
X605378Y246901D01*
X605363Y246941D01*
X605343Y246981D01*
X605328Y247016D01*
X605308Y247056D01*
X605208Y247196D01*
X605178Y247226D01*
Y249356D01*
X605168Y249481D01*
X605128Y249606D01*
X605068Y249716D01*
X604988Y249816D01*
X604888Y249896D01*
X604778Y249956D01*
X604653Y249996D01*
X604528Y250006D01*
G37*
G36*
G01X609252D02*
X609127Y249996D01*
X609002Y249956D01*
X608892Y249896D01*
X608792Y249816D01*
X608712Y249716D01*
X608652Y249606D01*
X608612Y249481D01*
X608602Y249356D01*
Y247231D01*
X608572Y247201D01*
X608547Y247166D01*
X608517Y247131D01*
X608497Y247096D01*
X608472Y247061D01*
X608432Y246981D01*
X608387Y246861D01*
X608377Y246821D01*
X608367Y246776D01*
X608362Y246736D01*
X608352Y246691D01*
Y246521D01*
X608362Y246476D01*
X608367Y246436D01*
X608377Y246391D01*
X608387Y246351D01*
X608432Y246231D01*
X608472Y246151D01*
X608497Y246116D01*
X608517Y246081D01*
X608547Y246046D01*
X608572Y246011D01*
X608602Y245981D01*
Y243556D01*
X608612Y243431D01*
X608652Y243306D01*
X608712Y243196D01*
X608792Y243096D01*
X608892Y243016D01*
X609002Y242956D01*
X609127Y242916D01*
X609252Y242906D01*
X609377Y242916D01*
X609502Y242956D01*
X609612Y243016D01*
X609712Y243096D01*
X609792Y243196D01*
X609852Y243306D01*
X609892Y243431D01*
X609902Y243556D01*
Y245986D01*
X609932Y246016D01*
X610032Y246156D01*
X610052Y246196D01*
X610067Y246231D01*
X610087Y246271D01*
X610102Y246311D01*
X610112Y246351D01*
X610127Y246396D01*
X610132Y246436D01*
X610142Y246476D01*
X610147Y246521D01*
Y246561D01*
X610152Y246606D01*
X610147Y246651D01*
Y246691D01*
X610142Y246736D01*
X610132Y246776D01*
X610127Y246816D01*
X610112Y246861D01*
X610102Y246901D01*
X610087Y246941D01*
X610067Y246981D01*
X610052Y247016D01*
X610032Y247056D01*
X609932Y247196D01*
X609902Y247226D01*
Y249356D01*
X609892Y249481D01*
X609852Y249606D01*
X609792Y249716D01*
X609712Y249816D01*
X609612Y249896D01*
X609502Y249956D01*
X609377Y249996D01*
X609252Y250006D01*
G37*
G36*
G01X613977D02*
X613852Y249996D01*
X613727Y249956D01*
X613617Y249896D01*
X613517Y249816D01*
X613437Y249716D01*
X613377Y249606D01*
X613337Y249481D01*
X613327Y249356D01*
Y247231D01*
X613297Y247201D01*
X613272Y247166D01*
X613242Y247131D01*
X613222Y247096D01*
X613197Y247061D01*
X613157Y246981D01*
X613112Y246861D01*
X613102Y246821D01*
X613092Y246776D01*
X613087Y246736D01*
X613077Y246691D01*
Y246521D01*
X613087Y246476D01*
X613092Y246436D01*
X613102Y246391D01*
X613112Y246351D01*
X613157Y246231D01*
X613197Y246151D01*
X613222Y246116D01*
X613242Y246081D01*
X613272Y246046D01*
X613297Y246011D01*
X613327Y245981D01*
Y243556D01*
X613337Y243431D01*
X613377Y243306D01*
X613437Y243196D01*
X613517Y243096D01*
X613617Y243016D01*
X613727Y242956D01*
X613852Y242916D01*
X613977Y242906D01*
X614102Y242916D01*
X614227Y242956D01*
X614337Y243016D01*
X614437Y243096D01*
X614517Y243196D01*
X614577Y243306D01*
X614617Y243431D01*
X614627Y243556D01*
Y245986D01*
X614657Y246016D01*
X614757Y246156D01*
X614777Y246196D01*
X614792Y246231D01*
X614812Y246271D01*
X614827Y246311D01*
X614837Y246351D01*
X614852Y246396D01*
X614857Y246436D01*
X614867Y246476D01*
X614872Y246521D01*
Y246561D01*
X614877Y246606D01*
X614872Y246651D01*
Y246691D01*
X614867Y246736D01*
X614857Y246776D01*
X614852Y246816D01*
X614837Y246861D01*
X614827Y246901D01*
X614812Y246941D01*
X614792Y246981D01*
X614777Y247016D01*
X614757Y247056D01*
X614657Y247196D01*
X614627Y247226D01*
Y249356D01*
X614617Y249481D01*
X614577Y249606D01*
X614517Y249716D01*
X614437Y249816D01*
X614337Y249896D01*
X614227Y249956D01*
X614102Y249996D01*
X613977Y250006D01*
G37*
G36*
G01X618701D02*
X618576Y249996D01*
X618451Y249956D01*
X618341Y249896D01*
X618241Y249816D01*
X618161Y249716D01*
X618101Y249606D01*
X618061Y249481D01*
X618051Y249356D01*
Y247231D01*
X618021Y247201D01*
X617996Y247166D01*
X617966Y247131D01*
X617946Y247096D01*
X617921Y247061D01*
X617881Y246981D01*
X617836Y246861D01*
X617826Y246821D01*
X617816Y246776D01*
X617811Y246736D01*
X617801Y246691D01*
Y246521D01*
X617811Y246476D01*
X617816Y246436D01*
X617826Y246391D01*
X617836Y246351D01*
X617881Y246231D01*
X617921Y246151D01*
X617946Y246116D01*
X617966Y246081D01*
X617996Y246046D01*
X618021Y246011D01*
X618051Y245981D01*
Y243556D01*
X618061Y243431D01*
X618101Y243306D01*
X618161Y243196D01*
X618241Y243096D01*
X618341Y243016D01*
X618451Y242956D01*
X618576Y242916D01*
X618701Y242906D01*
X618826Y242916D01*
X618951Y242956D01*
X619061Y243016D01*
X619161Y243096D01*
X619241Y243196D01*
X619301Y243306D01*
X619341Y243431D01*
X619351Y243556D01*
Y245986D01*
X619381Y246016D01*
X619481Y246156D01*
X619501Y246196D01*
X619516Y246231D01*
X619536Y246271D01*
X619551Y246311D01*
X619561Y246351D01*
X619576Y246396D01*
X619581Y246436D01*
X619591Y246476D01*
X619596Y246521D01*
Y246561D01*
X619601Y246606D01*
X619596Y246651D01*
Y246691D01*
X619591Y246736D01*
X619581Y246776D01*
X619576Y246816D01*
X619561Y246861D01*
X619551Y246901D01*
X619536Y246941D01*
X619516Y246981D01*
X619501Y247016D01*
X619481Y247056D01*
X619381Y247196D01*
X619351Y247226D01*
Y249356D01*
X619341Y249481D01*
X619301Y249606D01*
X619241Y249716D01*
X619161Y249816D01*
X619061Y249896D01*
X618951Y249956D01*
X618826Y249996D01*
X618701Y250006D01*
G37*
G36*
G01X623425D02*
X623300Y249996D01*
X623175Y249956D01*
X623065Y249896D01*
X622965Y249816D01*
X622885Y249716D01*
X622825Y249606D01*
X622785Y249481D01*
X622775Y249356D01*
Y247231D01*
X622745Y247201D01*
X622720Y247166D01*
X622690Y247131D01*
X622670Y247096D01*
X622645Y247061D01*
X622605Y246981D01*
X622560Y246861D01*
X622550Y246821D01*
X622540Y246776D01*
X622535Y246736D01*
X622525Y246691D01*
Y246521D01*
X622535Y246476D01*
X622540Y246436D01*
X622550Y246391D01*
X622560Y246351D01*
X622605Y246231D01*
X622645Y246151D01*
X622670Y246116D01*
X622690Y246081D01*
X622720Y246046D01*
X622745Y246011D01*
X622775Y245981D01*
Y243556D01*
X622785Y243431D01*
X622825Y243306D01*
X622885Y243196D01*
X622965Y243096D01*
X623065Y243016D01*
X623175Y242956D01*
X623300Y242916D01*
X623425Y242906D01*
X623550Y242916D01*
X623675Y242956D01*
X623785Y243016D01*
X623885Y243096D01*
X623965Y243196D01*
X624025Y243306D01*
X624065Y243431D01*
X624075Y243556D01*
Y245986D01*
X624105Y246016D01*
X624205Y246156D01*
X624225Y246196D01*
X624240Y246231D01*
X624260Y246271D01*
X624275Y246311D01*
X624285Y246351D01*
X624300Y246396D01*
X624305Y246436D01*
X624315Y246476D01*
X624320Y246521D01*
Y246561D01*
X624325Y246606D01*
X624320Y246651D01*
Y246691D01*
X624315Y246736D01*
X624305Y246776D01*
X624300Y246816D01*
X624285Y246861D01*
X624275Y246901D01*
X624260Y246941D01*
X624240Y246981D01*
X624225Y247016D01*
X624205Y247056D01*
X624105Y247196D01*
X624075Y247226D01*
Y249356D01*
X624065Y249481D01*
X624025Y249606D01*
X623965Y249716D01*
X623885Y249816D01*
X623785Y249896D01*
X623675Y249956D01*
X623550Y249996D01*
X623425Y250006D01*
G37*
G36*
G01X628150D02*
X628025Y249996D01*
X627900Y249956D01*
X627790Y249896D01*
X627690Y249816D01*
X627610Y249716D01*
X627550Y249606D01*
X627510Y249481D01*
X627500Y249356D01*
Y247231D01*
X627470Y247201D01*
X627445Y247166D01*
X627415Y247131D01*
X627395Y247096D01*
X627370Y247061D01*
X627330Y246981D01*
X627285Y246861D01*
X627275Y246821D01*
X627265Y246776D01*
X627260Y246736D01*
X627250Y246691D01*
Y246521D01*
X627260Y246476D01*
X627265Y246436D01*
X627275Y246391D01*
X627285Y246351D01*
X627330Y246231D01*
X627370Y246151D01*
X627395Y246116D01*
X627415Y246081D01*
X627445Y246046D01*
X627470Y246011D01*
X627500Y245981D01*
Y243556D01*
X627510Y243431D01*
X627550Y243306D01*
X627610Y243196D01*
X627690Y243096D01*
X627790Y243016D01*
X627900Y242956D01*
X628025Y242916D01*
X628150Y242906D01*
X628275Y242916D01*
X628400Y242956D01*
X628510Y243016D01*
X628610Y243096D01*
X628690Y243196D01*
X628750Y243306D01*
X628790Y243431D01*
X628800Y243556D01*
Y245986D01*
X628830Y246016D01*
X628930Y246156D01*
X628950Y246196D01*
X628965Y246231D01*
X628985Y246271D01*
X629000Y246311D01*
X629010Y246351D01*
X629025Y246396D01*
X629030Y246436D01*
X629040Y246476D01*
X629045Y246521D01*
Y246561D01*
X629050Y246606D01*
X629045Y246651D01*
Y246691D01*
X629040Y246736D01*
X629030Y246776D01*
X629025Y246816D01*
X629010Y246861D01*
X629000Y246901D01*
X628985Y246941D01*
X628965Y246981D01*
X628950Y247016D01*
X628930Y247056D01*
X628830Y247196D01*
X628800Y247226D01*
Y249356D01*
X628790Y249481D01*
X628750Y249606D01*
X628690Y249716D01*
X628610Y249816D01*
X628510Y249896D01*
X628400Y249956D01*
X628275Y249996D01*
X628150Y250006D01*
G37*
G36*
G01X632874D02*
X632749Y249996D01*
X632624Y249956D01*
X632514Y249896D01*
X632414Y249816D01*
X632334Y249716D01*
X632274Y249606D01*
X632234Y249481D01*
X632224Y249356D01*
Y247231D01*
X632194Y247201D01*
X632169Y247166D01*
X632139Y247131D01*
X632119Y247096D01*
X632094Y247061D01*
X632054Y246981D01*
X632009Y246861D01*
X631999Y246821D01*
X631989Y246776D01*
X631984Y246736D01*
X631974Y246691D01*
Y246521D01*
X631984Y246476D01*
X631989Y246436D01*
X631999Y246391D01*
X632009Y246351D01*
X632054Y246231D01*
X632094Y246151D01*
X632119Y246116D01*
X632139Y246081D01*
X632169Y246046D01*
X632194Y246011D01*
X632224Y245981D01*
Y243556D01*
X632234Y243431D01*
X632274Y243306D01*
X632334Y243196D01*
X632414Y243096D01*
X632514Y243016D01*
X632624Y242956D01*
X632749Y242916D01*
X632874Y242906D01*
X632999Y242916D01*
X633124Y242956D01*
X633234Y243016D01*
X633334Y243096D01*
X633414Y243196D01*
X633474Y243306D01*
X633514Y243431D01*
X633524Y243556D01*
Y245986D01*
X633554Y246016D01*
X633654Y246156D01*
X633674Y246196D01*
X633689Y246231D01*
X633709Y246271D01*
X633724Y246311D01*
X633734Y246351D01*
X633749Y246396D01*
X633754Y246436D01*
X633764Y246476D01*
X633769Y246521D01*
Y246561D01*
X633774Y246606D01*
X633769Y246651D01*
Y246691D01*
X633764Y246736D01*
X633754Y246776D01*
X633749Y246816D01*
X633734Y246861D01*
X633724Y246901D01*
X633709Y246941D01*
X633689Y246981D01*
X633674Y247016D01*
X633654Y247056D01*
X633554Y247196D01*
X633524Y247226D01*
Y249356D01*
X633514Y249481D01*
X633474Y249606D01*
X633414Y249716D01*
X633334Y249816D01*
X633234Y249896D01*
X633124Y249956D01*
X632999Y249996D01*
X632874Y250006D01*
G37*
G36*
G01X637599D02*
X637474Y249996D01*
X637349Y249956D01*
X637239Y249896D01*
X637139Y249816D01*
X637059Y249716D01*
X636999Y249606D01*
X636959Y249481D01*
X636949Y249356D01*
Y247231D01*
X636919Y247201D01*
X636894Y247166D01*
X636864Y247131D01*
X636844Y247096D01*
X636819Y247061D01*
X636779Y246981D01*
X636734Y246861D01*
X636724Y246821D01*
X636714Y246776D01*
X636709Y246736D01*
X636699Y246691D01*
Y246521D01*
X636709Y246476D01*
X636714Y246436D01*
X636724Y246391D01*
X636734Y246351D01*
X636779Y246231D01*
X636819Y246151D01*
X636844Y246116D01*
X636864Y246081D01*
X636894Y246046D01*
X636919Y246011D01*
X636949Y245981D01*
Y243556D01*
X636959Y243431D01*
X636999Y243306D01*
X637059Y243196D01*
X637139Y243096D01*
X637239Y243016D01*
X637349Y242956D01*
X637474Y242916D01*
X637599Y242906D01*
X637724Y242916D01*
X637849Y242956D01*
X637959Y243016D01*
X638059Y243096D01*
X638139Y243196D01*
X638199Y243306D01*
X638239Y243431D01*
X638249Y243556D01*
Y245986D01*
X638279Y246016D01*
X638379Y246156D01*
X638399Y246196D01*
X638414Y246231D01*
X638434Y246271D01*
X638449Y246311D01*
X638459Y246351D01*
X638474Y246396D01*
X638479Y246436D01*
X638489Y246476D01*
X638494Y246521D01*
Y246561D01*
X638499Y246606D01*
X638494Y246651D01*
Y246691D01*
X638489Y246736D01*
X638479Y246776D01*
X638474Y246816D01*
X638459Y246861D01*
X638449Y246901D01*
X638434Y246941D01*
X638414Y246981D01*
X638399Y247016D01*
X638379Y247056D01*
X638279Y247196D01*
X638249Y247226D01*
Y249356D01*
X638239Y249481D01*
X638199Y249606D01*
X638139Y249716D01*
X638059Y249816D01*
X637959Y249896D01*
X637849Y249956D01*
X637724Y249996D01*
X637599Y250006D01*
G37*
G36*
G01X642323D02*
X642198Y249996D01*
X642073Y249956D01*
X641963Y249896D01*
X641863Y249816D01*
X641783Y249716D01*
X641723Y249606D01*
X641683Y249481D01*
X641673Y249356D01*
Y247231D01*
X641643Y247201D01*
X641618Y247166D01*
X641588Y247131D01*
X641568Y247096D01*
X641543Y247061D01*
X641503Y246981D01*
X641458Y246861D01*
X641448Y246821D01*
X641438Y246776D01*
X641433Y246736D01*
X641423Y246691D01*
Y246521D01*
X641433Y246476D01*
X641438Y246436D01*
X641448Y246391D01*
X641458Y246351D01*
X641503Y246231D01*
X641543Y246151D01*
X641568Y246116D01*
X641588Y246081D01*
X641618Y246046D01*
X641643Y246011D01*
X641673Y245981D01*
Y243556D01*
X641683Y243431D01*
X641723Y243306D01*
X641783Y243196D01*
X641863Y243096D01*
X641963Y243016D01*
X642073Y242956D01*
X642198Y242916D01*
X642323Y242906D01*
X642448Y242916D01*
X642573Y242956D01*
X642683Y243016D01*
X642783Y243096D01*
X642863Y243196D01*
X642923Y243306D01*
X642963Y243431D01*
X642973Y243556D01*
Y245986D01*
X643003Y246016D01*
X643103Y246156D01*
X643123Y246196D01*
X643138Y246231D01*
X643158Y246271D01*
X643173Y246311D01*
X643183Y246351D01*
X643198Y246396D01*
X643203Y246436D01*
X643213Y246476D01*
X643218Y246521D01*
Y246561D01*
X643223Y246606D01*
X643218Y246651D01*
Y246691D01*
X643213Y246736D01*
X643203Y246776D01*
X643198Y246816D01*
X643183Y246861D01*
X643173Y246901D01*
X643158Y246941D01*
X643138Y246981D01*
X643123Y247016D01*
X643103Y247056D01*
X643003Y247196D01*
X642973Y247226D01*
Y249356D01*
X642963Y249481D01*
X642923Y249606D01*
X642863Y249716D01*
X642783Y249816D01*
X642683Y249896D01*
X642573Y249956D01*
X642448Y249996D01*
X642323Y250006D01*
G37*
G36*
G01X647047D02*
X646922Y249996D01*
X646797Y249956D01*
X646687Y249896D01*
X646587Y249816D01*
X646507Y249716D01*
X646447Y249606D01*
X646407Y249481D01*
X646397Y249356D01*
Y247231D01*
X646367Y247201D01*
X646342Y247166D01*
X646312Y247131D01*
X646292Y247096D01*
X646267Y247061D01*
X646227Y246981D01*
X646182Y246861D01*
X646172Y246821D01*
X646162Y246776D01*
X646157Y246736D01*
X646147Y246691D01*
Y246521D01*
X646157Y246476D01*
X646162Y246436D01*
X646172Y246391D01*
X646182Y246351D01*
X646227Y246231D01*
X646267Y246151D01*
X646292Y246116D01*
X646312Y246081D01*
X646342Y246046D01*
X646367Y246011D01*
X646397Y245981D01*
Y243556D01*
X646407Y243431D01*
X646447Y243306D01*
X646507Y243196D01*
X646587Y243096D01*
X646687Y243016D01*
X646797Y242956D01*
X646922Y242916D01*
X647047Y242906D01*
X647172Y242916D01*
X647297Y242956D01*
X647407Y243016D01*
X647507Y243096D01*
X647587Y243196D01*
X647647Y243306D01*
X647687Y243431D01*
X647697Y243556D01*
Y245986D01*
X647727Y246016D01*
X647827Y246156D01*
X647847Y246196D01*
X647862Y246231D01*
X647882Y246271D01*
X647897Y246311D01*
X647907Y246351D01*
X647922Y246396D01*
X647927Y246436D01*
X647937Y246476D01*
X647942Y246521D01*
Y246561D01*
X647947Y246606D01*
X647942Y246651D01*
Y246691D01*
X647937Y246736D01*
X647927Y246776D01*
X647922Y246816D01*
X647907Y246861D01*
X647897Y246901D01*
X647882Y246941D01*
X647862Y246981D01*
X647847Y247016D01*
X647827Y247056D01*
X647727Y247196D01*
X647697Y247226D01*
Y249356D01*
X647687Y249481D01*
X647647Y249606D01*
X647587Y249716D01*
X647507Y249816D01*
X647407Y249896D01*
X647297Y249956D01*
X647172Y249996D01*
X647047Y250006D01*
G37*
G36*
G01X651772D02*
X651647Y249996D01*
X651522Y249956D01*
X651412Y249896D01*
X651312Y249816D01*
X651232Y249716D01*
X651172Y249606D01*
X651132Y249481D01*
X651122Y249356D01*
Y247231D01*
X651092Y247201D01*
X651067Y247166D01*
X651037Y247131D01*
X651017Y247096D01*
X650992Y247061D01*
X650952Y246981D01*
X650907Y246861D01*
X650897Y246821D01*
X650887Y246776D01*
X650882Y246736D01*
X650872Y246691D01*
Y246521D01*
X650882Y246476D01*
X650887Y246436D01*
X650897Y246391D01*
X650907Y246351D01*
X650952Y246231D01*
X650992Y246151D01*
X651017Y246116D01*
X651037Y246081D01*
X651067Y246046D01*
X651092Y246011D01*
X651122Y245981D01*
Y243556D01*
X651132Y243431D01*
X651172Y243306D01*
X651232Y243196D01*
X651312Y243096D01*
X651412Y243016D01*
X651522Y242956D01*
X651647Y242916D01*
X651772Y242906D01*
X651897Y242916D01*
X652022Y242956D01*
X652132Y243016D01*
X652232Y243096D01*
X652312Y243196D01*
X652372Y243306D01*
X652412Y243431D01*
X652422Y243556D01*
Y245986D01*
X652452Y246016D01*
X652552Y246156D01*
X652572Y246196D01*
X652587Y246231D01*
X652607Y246271D01*
X652622Y246311D01*
X652632Y246351D01*
X652647Y246396D01*
X652652Y246436D01*
X652662Y246476D01*
X652667Y246521D01*
Y246561D01*
X652672Y246606D01*
X652667Y246651D01*
Y246691D01*
X652662Y246736D01*
X652652Y246776D01*
X652647Y246816D01*
X652632Y246861D01*
X652622Y246901D01*
X652607Y246941D01*
X652587Y246981D01*
X652572Y247016D01*
X652552Y247056D01*
X652452Y247196D01*
X652422Y247226D01*
Y249356D01*
X652412Y249481D01*
X652372Y249606D01*
X652312Y249716D01*
X652232Y249816D01*
X652132Y249896D01*
X652022Y249956D01*
X651897Y249996D01*
X651772Y250006D01*
G37*
G36*
G01X665945D02*
X665820Y249996D01*
X665695Y249956D01*
X665585Y249896D01*
X665485Y249816D01*
X665405Y249716D01*
X665345Y249606D01*
X665305Y249481D01*
X665295Y249356D01*
Y247231D01*
X665265Y247201D01*
X665240Y247166D01*
X665210Y247131D01*
X665190Y247096D01*
X665165Y247061D01*
X665125Y246981D01*
X665080Y246861D01*
X665070Y246821D01*
X665060Y246776D01*
X665055Y246736D01*
X665045Y246691D01*
Y246521D01*
X665055Y246476D01*
X665060Y246436D01*
X665070Y246391D01*
X665080Y246351D01*
X665125Y246231D01*
X665165Y246151D01*
X665190Y246116D01*
X665210Y246081D01*
X665240Y246046D01*
X665265Y246011D01*
X665295Y245981D01*
Y243556D01*
X665305Y243431D01*
X665345Y243306D01*
X665405Y243196D01*
X665485Y243096D01*
X665585Y243016D01*
X665695Y242956D01*
X665820Y242916D01*
X665945Y242906D01*
X666070Y242916D01*
X666195Y242956D01*
X666305Y243016D01*
X666405Y243096D01*
X666485Y243196D01*
X666545Y243306D01*
X666585Y243431D01*
X666595Y243556D01*
Y245986D01*
X666625Y246016D01*
X666725Y246156D01*
X666745Y246196D01*
X666760Y246231D01*
X666780Y246271D01*
X666795Y246311D01*
X666805Y246351D01*
X666820Y246396D01*
X666825Y246436D01*
X666835Y246476D01*
X666840Y246521D01*
Y246561D01*
X666845Y246606D01*
X666840Y246651D01*
Y246691D01*
X666835Y246736D01*
X666825Y246776D01*
X666820Y246816D01*
X666805Y246861D01*
X666795Y246901D01*
X666780Y246941D01*
X666760Y246981D01*
X666745Y247016D01*
X666725Y247056D01*
X666625Y247196D01*
X666595Y247226D01*
Y249356D01*
X666585Y249481D01*
X666545Y249606D01*
X666485Y249716D01*
X666405Y249816D01*
X666305Y249896D01*
X666195Y249956D01*
X666070Y249996D01*
X665945Y250006D01*
G37*
G36*
G01X670670D02*
X670545Y249996D01*
X670420Y249956D01*
X670310Y249896D01*
X670210Y249816D01*
X670130Y249716D01*
X670070Y249606D01*
X670030Y249481D01*
X670020Y249356D01*
Y247231D01*
X669990Y247201D01*
X669965Y247166D01*
X669935Y247131D01*
X669915Y247096D01*
X669890Y247061D01*
X669850Y246981D01*
X669805Y246861D01*
X669795Y246821D01*
X669785Y246776D01*
X669780Y246736D01*
X669770Y246691D01*
Y246521D01*
X669780Y246476D01*
X669785Y246436D01*
X669795Y246391D01*
X669805Y246351D01*
X669850Y246231D01*
X669890Y246151D01*
X669915Y246116D01*
X669935Y246081D01*
X669965Y246046D01*
X669990Y246011D01*
X670020Y245981D01*
Y243556D01*
X670030Y243431D01*
X670070Y243306D01*
X670130Y243196D01*
X670210Y243096D01*
X670310Y243016D01*
X670420Y242956D01*
X670545Y242916D01*
X670670Y242906D01*
X670795Y242916D01*
X670920Y242956D01*
X671030Y243016D01*
X671130Y243096D01*
X671210Y243196D01*
X671270Y243306D01*
X671310Y243431D01*
X671320Y243556D01*
Y245986D01*
X671350Y246016D01*
X671450Y246156D01*
X671470Y246196D01*
X671485Y246231D01*
X671505Y246271D01*
X671520Y246311D01*
X671530Y246351D01*
X671545Y246396D01*
X671550Y246436D01*
X671560Y246476D01*
X671565Y246521D01*
Y246561D01*
X671570Y246606D01*
X671565Y246651D01*
Y246691D01*
X671560Y246736D01*
X671550Y246776D01*
X671545Y246816D01*
X671530Y246861D01*
X671520Y246901D01*
X671505Y246941D01*
X671485Y246981D01*
X671470Y247016D01*
X671450Y247056D01*
X671350Y247196D01*
X671320Y247226D01*
Y249356D01*
X671310Y249481D01*
X671270Y249606D01*
X671210Y249716D01*
X671130Y249816D01*
X671030Y249896D01*
X670920Y249956D01*
X670795Y249996D01*
X670670Y250006D01*
G37*
G36*
G01X675394D02*
X675269Y249996D01*
X675144Y249956D01*
X675034Y249896D01*
X674934Y249816D01*
X674854Y249716D01*
X674794Y249606D01*
X674754Y249481D01*
X674744Y249356D01*
Y247231D01*
X674714Y247201D01*
X674689Y247166D01*
X674659Y247131D01*
X674639Y247096D01*
X674614Y247061D01*
X674574Y246981D01*
X674529Y246861D01*
X674519Y246821D01*
X674509Y246776D01*
X674504Y246736D01*
X674494Y246691D01*
Y246521D01*
X674504Y246476D01*
X674509Y246436D01*
X674519Y246391D01*
X674529Y246351D01*
X674574Y246231D01*
X674614Y246151D01*
X674639Y246116D01*
X674659Y246081D01*
X674689Y246046D01*
X674714Y246011D01*
X674744Y245981D01*
Y243556D01*
X674754Y243431D01*
X674794Y243306D01*
X674854Y243196D01*
X674934Y243096D01*
X675034Y243016D01*
X675144Y242956D01*
X675269Y242916D01*
X675394Y242906D01*
X675519Y242916D01*
X675644Y242956D01*
X675754Y243016D01*
X675854Y243096D01*
X675934Y243196D01*
X675994Y243306D01*
X676034Y243431D01*
X676044Y243556D01*
Y245986D01*
X676074Y246016D01*
X676174Y246156D01*
X676194Y246196D01*
X676209Y246231D01*
X676229Y246271D01*
X676244Y246311D01*
X676254Y246351D01*
X676269Y246396D01*
X676274Y246436D01*
X676284Y246476D01*
X676289Y246521D01*
Y246561D01*
X676294Y246606D01*
X676289Y246651D01*
Y246691D01*
X676284Y246736D01*
X676274Y246776D01*
X676269Y246816D01*
X676254Y246861D01*
X676244Y246901D01*
X676229Y246941D01*
X676209Y246981D01*
X676194Y247016D01*
X676174Y247056D01*
X676074Y247196D01*
X676044Y247226D01*
Y249356D01*
X676034Y249481D01*
X675994Y249606D01*
X675934Y249716D01*
X675854Y249816D01*
X675754Y249896D01*
X675644Y249956D01*
X675519Y249996D01*
X675394Y250006D01*
G37*
G36*
G01X680118D02*
X679993Y249996D01*
X679868Y249956D01*
X679758Y249896D01*
X679658Y249816D01*
X679578Y249716D01*
X679518Y249606D01*
X679478Y249481D01*
X679468Y249356D01*
Y247231D01*
X679438Y247201D01*
X679413Y247166D01*
X679383Y247131D01*
X679363Y247096D01*
X679338Y247061D01*
X679298Y246981D01*
X679253Y246861D01*
X679243Y246821D01*
X679233Y246776D01*
X679228Y246736D01*
X679218Y246691D01*
Y246521D01*
X679228Y246476D01*
X679233Y246436D01*
X679243Y246391D01*
X679253Y246351D01*
X679298Y246231D01*
X679338Y246151D01*
X679363Y246116D01*
X679383Y246081D01*
X679413Y246046D01*
X679438Y246011D01*
X679468Y245981D01*
Y243556D01*
X679478Y243431D01*
X679518Y243306D01*
X679578Y243196D01*
X679658Y243096D01*
X679758Y243016D01*
X679868Y242956D01*
X679993Y242916D01*
X680118Y242906D01*
X680243Y242916D01*
X680368Y242956D01*
X680478Y243016D01*
X680578Y243096D01*
X680658Y243196D01*
X680718Y243306D01*
X680758Y243431D01*
X680768Y243556D01*
Y245986D01*
X680798Y246016D01*
X680898Y246156D01*
X680918Y246196D01*
X680933Y246231D01*
X680953Y246271D01*
X680968Y246311D01*
X680978Y246351D01*
X680993Y246396D01*
X680998Y246436D01*
X681008Y246476D01*
X681013Y246521D01*
Y246561D01*
X681018Y246606D01*
X681013Y246651D01*
Y246691D01*
X681008Y246736D01*
X680998Y246776D01*
X680993Y246816D01*
X680978Y246861D01*
X680968Y246901D01*
X680953Y246941D01*
X680933Y246981D01*
X680918Y247016D01*
X680898Y247056D01*
X680798Y247196D01*
X680768Y247226D01*
Y249356D01*
X680758Y249481D01*
X680718Y249606D01*
X680658Y249716D01*
X680578Y249816D01*
X680478Y249896D01*
X680368Y249956D01*
X680243Y249996D01*
X680118Y250006D01*
G37*
G36*
G01X684843D02*
X684718Y249996D01*
X684593Y249956D01*
X684483Y249896D01*
X684383Y249816D01*
X684303Y249716D01*
X684243Y249606D01*
X684203Y249481D01*
X684193Y249356D01*
Y247231D01*
X684163Y247201D01*
X684138Y247166D01*
X684108Y247131D01*
X684088Y247096D01*
X684063Y247061D01*
X684023Y246981D01*
X683978Y246861D01*
X683968Y246821D01*
X683958Y246776D01*
X683953Y246736D01*
X683943Y246691D01*
Y246521D01*
X683953Y246476D01*
X683958Y246436D01*
X683968Y246391D01*
X683978Y246351D01*
X684023Y246231D01*
X684063Y246151D01*
X684088Y246116D01*
X684108Y246081D01*
X684138Y246046D01*
X684163Y246011D01*
X684193Y245981D01*
Y243556D01*
X684203Y243431D01*
X684243Y243306D01*
X684303Y243196D01*
X684383Y243096D01*
X684483Y243016D01*
X684593Y242956D01*
X684718Y242916D01*
X684843Y242906D01*
X684968Y242916D01*
X685093Y242956D01*
X685203Y243016D01*
X685303Y243096D01*
X685383Y243196D01*
X685443Y243306D01*
X685483Y243431D01*
X685493Y243556D01*
Y245986D01*
X685523Y246016D01*
X685623Y246156D01*
X685643Y246196D01*
X685658Y246231D01*
X685678Y246271D01*
X685693Y246311D01*
X685703Y246351D01*
X685718Y246396D01*
X685723Y246436D01*
X685733Y246476D01*
X685738Y246521D01*
Y246561D01*
X685743Y246606D01*
X685738Y246651D01*
Y246691D01*
X685733Y246736D01*
X685723Y246776D01*
X685718Y246816D01*
X685703Y246861D01*
X685693Y246901D01*
X685678Y246941D01*
X685658Y246981D01*
X685643Y247016D01*
X685623Y247056D01*
X685523Y247196D01*
X685493Y247226D01*
Y249356D01*
X685483Y249481D01*
X685443Y249606D01*
X685383Y249716D01*
X685303Y249816D01*
X685203Y249896D01*
X685093Y249956D01*
X684968Y249996D01*
X684843Y250006D01*
G37*
G36*
G01X689567D02*
X689442Y249996D01*
X689317Y249956D01*
X689207Y249896D01*
X689107Y249816D01*
X689027Y249716D01*
X688967Y249606D01*
X688927Y249481D01*
X688917Y249356D01*
Y247231D01*
X688887Y247201D01*
X688862Y247166D01*
X688832Y247131D01*
X688812Y247096D01*
X688787Y247061D01*
X688747Y246981D01*
X688702Y246861D01*
X688692Y246821D01*
X688682Y246776D01*
X688677Y246736D01*
X688667Y246691D01*
Y246521D01*
X688677Y246476D01*
X688682Y246436D01*
X688692Y246391D01*
X688702Y246351D01*
X688747Y246231D01*
X688787Y246151D01*
X688812Y246116D01*
X688832Y246081D01*
X688862Y246046D01*
X688887Y246011D01*
X688917Y245981D01*
Y243556D01*
X688927Y243431D01*
X688967Y243306D01*
X689027Y243196D01*
X689107Y243096D01*
X689207Y243016D01*
X689317Y242956D01*
X689442Y242916D01*
X689567Y242906D01*
X689692Y242916D01*
X689817Y242956D01*
X689927Y243016D01*
X690027Y243096D01*
X690107Y243196D01*
X690167Y243306D01*
X690207Y243431D01*
X690217Y243556D01*
Y245986D01*
X690247Y246016D01*
X690347Y246156D01*
X690367Y246196D01*
X690382Y246231D01*
X690402Y246271D01*
X690417Y246311D01*
X690427Y246351D01*
X690442Y246396D01*
X690447Y246436D01*
X690457Y246476D01*
X690462Y246521D01*
Y246561D01*
X690467Y246606D01*
X690462Y246651D01*
Y246691D01*
X690457Y246736D01*
X690447Y246776D01*
X690442Y246816D01*
X690427Y246861D01*
X690417Y246901D01*
X690402Y246941D01*
X690382Y246981D01*
X690367Y247016D01*
X690347Y247056D01*
X690247Y247196D01*
X690217Y247226D01*
Y249356D01*
X690207Y249481D01*
X690167Y249606D01*
X690107Y249716D01*
X690027Y249816D01*
X689927Y249896D01*
X689817Y249956D01*
X689692Y249996D01*
X689567Y250006D01*
G37*
G36*
G01X694292D02*
X694167Y249996D01*
X694042Y249956D01*
X693932Y249896D01*
X693832Y249816D01*
X693752Y249716D01*
X693692Y249606D01*
X693652Y249481D01*
X693642Y249356D01*
Y247231D01*
X693612Y247201D01*
X693587Y247166D01*
X693557Y247131D01*
X693537Y247096D01*
X693512Y247061D01*
X693472Y246981D01*
X693427Y246861D01*
X693417Y246821D01*
X693407Y246776D01*
X693402Y246736D01*
X693392Y246691D01*
Y246521D01*
X693402Y246476D01*
X693407Y246436D01*
X693417Y246391D01*
X693427Y246351D01*
X693472Y246231D01*
X693512Y246151D01*
X693537Y246116D01*
X693557Y246081D01*
X693587Y246046D01*
X693612Y246011D01*
X693642Y245981D01*
Y243556D01*
X693652Y243431D01*
X693692Y243306D01*
X693752Y243196D01*
X693832Y243096D01*
X693932Y243016D01*
X694042Y242956D01*
X694167Y242916D01*
X694292Y242906D01*
X694417Y242916D01*
X694542Y242956D01*
X694652Y243016D01*
X694752Y243096D01*
X694832Y243196D01*
X694892Y243306D01*
X694932Y243431D01*
X694942Y243556D01*
Y245986D01*
X694972Y246016D01*
X695072Y246156D01*
X695092Y246196D01*
X695107Y246231D01*
X695127Y246271D01*
X695142Y246311D01*
X695152Y246351D01*
X695167Y246396D01*
X695172Y246436D01*
X695182Y246476D01*
X695187Y246521D01*
Y246561D01*
X695192Y246606D01*
X695187Y246651D01*
Y246691D01*
X695182Y246736D01*
X695172Y246776D01*
X695167Y246816D01*
X695152Y246861D01*
X695142Y246901D01*
X695127Y246941D01*
X695107Y246981D01*
X695092Y247016D01*
X695072Y247056D01*
X694972Y247196D01*
X694942Y247226D01*
Y249356D01*
X694932Y249481D01*
X694892Y249606D01*
X694832Y249716D01*
X694752Y249816D01*
X694652Y249896D01*
X694542Y249956D01*
X694417Y249996D01*
X694292Y250006D01*
G37*
G36*
G01X699016D02*
X698891Y249996D01*
X698766Y249956D01*
X698656Y249896D01*
X698556Y249816D01*
X698476Y249716D01*
X698416Y249606D01*
X698376Y249481D01*
X698366Y249356D01*
Y247231D01*
X698336Y247201D01*
X698311Y247166D01*
X698281Y247131D01*
X698261Y247096D01*
X698236Y247061D01*
X698196Y246981D01*
X698151Y246861D01*
X698141Y246821D01*
X698131Y246776D01*
X698126Y246736D01*
X698116Y246691D01*
Y246521D01*
X698126Y246476D01*
X698131Y246436D01*
X698141Y246391D01*
X698151Y246351D01*
X698196Y246231D01*
X698236Y246151D01*
X698261Y246116D01*
X698281Y246081D01*
X698311Y246046D01*
X698336Y246011D01*
X698366Y245981D01*
Y243556D01*
X698376Y243431D01*
X698416Y243306D01*
X698476Y243196D01*
X698556Y243096D01*
X698656Y243016D01*
X698766Y242956D01*
X698891Y242916D01*
X699016Y242906D01*
X699141Y242916D01*
X699266Y242956D01*
X699376Y243016D01*
X699476Y243096D01*
X699556Y243196D01*
X699616Y243306D01*
X699656Y243431D01*
X699666Y243556D01*
Y245986D01*
X699696Y246016D01*
X699796Y246156D01*
X699816Y246196D01*
X699831Y246231D01*
X699851Y246271D01*
X699866Y246311D01*
X699876Y246351D01*
X699891Y246396D01*
X699896Y246436D01*
X699906Y246476D01*
X699911Y246521D01*
Y246561D01*
X699916Y246606D01*
X699911Y246651D01*
Y246691D01*
X699906Y246736D01*
X699896Y246776D01*
X699891Y246816D01*
X699876Y246861D01*
X699866Y246901D01*
X699851Y246941D01*
X699831Y246981D01*
X699816Y247016D01*
X699796Y247056D01*
X699696Y247196D01*
X699666Y247226D01*
Y249356D01*
X699656Y249481D01*
X699616Y249606D01*
X699556Y249716D01*
X699476Y249816D01*
X699376Y249896D01*
X699266Y249956D01*
X699141Y249996D01*
X699016Y250006D01*
G37*
G36*
G01X703740D02*
X703615Y249996D01*
X703490Y249956D01*
X703380Y249896D01*
X703280Y249816D01*
X703200Y249716D01*
X703140Y249606D01*
X703100Y249481D01*
X703090Y249356D01*
Y247231D01*
X703060Y247201D01*
X703035Y247166D01*
X703005Y247131D01*
X702985Y247096D01*
X702960Y247061D01*
X702920Y246981D01*
X702875Y246861D01*
X702865Y246821D01*
X702855Y246776D01*
X702850Y246736D01*
X702840Y246691D01*
Y246521D01*
X702850Y246476D01*
X702855Y246436D01*
X702865Y246391D01*
X702875Y246351D01*
X702920Y246231D01*
X702960Y246151D01*
X702985Y246116D01*
X703005Y246081D01*
X703035Y246046D01*
X703060Y246011D01*
X703090Y245981D01*
Y243556D01*
X703100Y243431D01*
X703140Y243306D01*
X703200Y243196D01*
X703280Y243096D01*
X703380Y243016D01*
X703490Y242956D01*
X703615Y242916D01*
X703740Y242906D01*
X703865Y242916D01*
X703990Y242956D01*
X704100Y243016D01*
X704200Y243096D01*
X704280Y243196D01*
X704340Y243306D01*
X704380Y243431D01*
X704390Y243556D01*
Y245986D01*
X704420Y246016D01*
X704520Y246156D01*
X704540Y246196D01*
X704555Y246231D01*
X704575Y246271D01*
X704590Y246311D01*
X704600Y246351D01*
X704615Y246396D01*
X704620Y246436D01*
X704630Y246476D01*
X704635Y246521D01*
Y246561D01*
X704640Y246606D01*
X704635Y246651D01*
Y246691D01*
X704630Y246736D01*
X704620Y246776D01*
X704615Y246816D01*
X704600Y246861D01*
X704590Y246901D01*
X704575Y246941D01*
X704555Y246981D01*
X704540Y247016D01*
X704520Y247056D01*
X704420Y247196D01*
X704390Y247226D01*
Y249356D01*
X704380Y249481D01*
X704340Y249606D01*
X704280Y249716D01*
X704200Y249816D01*
X704100Y249896D01*
X703990Y249956D01*
X703865Y249996D01*
X703740Y250006D01*
G37*
G36*
G01X708465D02*
X708340Y249996D01*
X708215Y249956D01*
X708105Y249896D01*
X708005Y249816D01*
X707925Y249716D01*
X707865Y249606D01*
X707825Y249481D01*
X707815Y249356D01*
Y247231D01*
X707785Y247201D01*
X707760Y247166D01*
X707730Y247131D01*
X707710Y247096D01*
X707685Y247061D01*
X707645Y246981D01*
X707600Y246861D01*
X707590Y246821D01*
X707580Y246776D01*
X707575Y246736D01*
X707565Y246691D01*
Y246521D01*
X707575Y246476D01*
X707580Y246436D01*
X707590Y246391D01*
X707600Y246351D01*
X707645Y246231D01*
X707685Y246151D01*
X707710Y246116D01*
X707730Y246081D01*
X707760Y246046D01*
X707785Y246011D01*
X707815Y245981D01*
Y243556D01*
X707825Y243431D01*
X707865Y243306D01*
X707925Y243196D01*
X708005Y243096D01*
X708105Y243016D01*
X708215Y242956D01*
X708340Y242916D01*
X708465Y242906D01*
X708590Y242916D01*
X708715Y242956D01*
X708825Y243016D01*
X708925Y243096D01*
X709005Y243196D01*
X709065Y243306D01*
X709105Y243431D01*
X709115Y243556D01*
Y245986D01*
X709145Y246016D01*
X709245Y246156D01*
X709265Y246196D01*
X709280Y246231D01*
X709300Y246271D01*
X709315Y246311D01*
X709325Y246351D01*
X709340Y246396D01*
X709345Y246436D01*
X709355Y246476D01*
X709360Y246521D01*
Y246561D01*
X709365Y246606D01*
X709360Y246651D01*
Y246691D01*
X709355Y246736D01*
X709345Y246776D01*
X709340Y246816D01*
X709325Y246861D01*
X709315Y246901D01*
X709300Y246941D01*
X709280Y246981D01*
X709265Y247016D01*
X709245Y247056D01*
X709145Y247196D01*
X709115Y247226D01*
Y249356D01*
X709105Y249481D01*
X709065Y249606D01*
X709005Y249716D01*
X708925Y249816D01*
X708825Y249896D01*
X708715Y249956D01*
X708590Y249996D01*
X708465Y250006D01*
G37*
G36*
G01X713189D02*
X713064Y249996D01*
X712939Y249956D01*
X712829Y249896D01*
X712729Y249816D01*
X712649Y249716D01*
X712589Y249606D01*
X712549Y249481D01*
X712539Y249356D01*
Y247231D01*
X712509Y247201D01*
X712484Y247166D01*
X712454Y247131D01*
X712434Y247096D01*
X712409Y247061D01*
X712369Y246981D01*
X712324Y246861D01*
X712314Y246821D01*
X712304Y246776D01*
X712299Y246736D01*
X712289Y246691D01*
Y246521D01*
X712299Y246476D01*
X712304Y246436D01*
X712314Y246391D01*
X712324Y246351D01*
X712369Y246231D01*
X712409Y246151D01*
X712434Y246116D01*
X712454Y246081D01*
X712484Y246046D01*
X712509Y246011D01*
X712539Y245981D01*
Y243556D01*
X712549Y243431D01*
X712589Y243306D01*
X712649Y243196D01*
X712729Y243096D01*
X712829Y243016D01*
X712939Y242956D01*
X713064Y242916D01*
X713189Y242906D01*
X713314Y242916D01*
X713439Y242956D01*
X713549Y243016D01*
X713649Y243096D01*
X713729Y243196D01*
X713789Y243306D01*
X713829Y243431D01*
X713839Y243556D01*
Y245986D01*
X713869Y246016D01*
X713969Y246156D01*
X713989Y246196D01*
X714004Y246231D01*
X714024Y246271D01*
X714039Y246311D01*
X714049Y246351D01*
X714064Y246396D01*
X714069Y246436D01*
X714079Y246476D01*
X714084Y246521D01*
Y246561D01*
X714089Y246606D01*
X714084Y246651D01*
Y246691D01*
X714079Y246736D01*
X714069Y246776D01*
X714064Y246816D01*
X714049Y246861D01*
X714039Y246901D01*
X714024Y246941D01*
X714004Y246981D01*
X713989Y247016D01*
X713969Y247056D01*
X713869Y247196D01*
X713839Y247226D01*
Y249356D01*
X713829Y249481D01*
X713789Y249606D01*
X713729Y249716D01*
X713649Y249816D01*
X713549Y249896D01*
X713439Y249956D01*
X713314Y249996D01*
X713189Y250006D01*
G37*
G36*
G01X717914D02*
X717789Y249996D01*
X717664Y249956D01*
X717554Y249896D01*
X717454Y249816D01*
X717374Y249716D01*
X717314Y249606D01*
X717274Y249481D01*
X717264Y249356D01*
Y247231D01*
X717234Y247201D01*
X717209Y247166D01*
X717179Y247131D01*
X717159Y247096D01*
X717134Y247061D01*
X717094Y246981D01*
X717049Y246861D01*
X717039Y246821D01*
X717029Y246776D01*
X717024Y246736D01*
X717014Y246691D01*
Y246521D01*
X717024Y246476D01*
X717029Y246436D01*
X717039Y246391D01*
X717049Y246351D01*
X717094Y246231D01*
X717134Y246151D01*
X717159Y246116D01*
X717179Y246081D01*
X717209Y246046D01*
X717234Y246011D01*
X717264Y245981D01*
Y243556D01*
X717274Y243431D01*
X717314Y243306D01*
X717374Y243196D01*
X717454Y243096D01*
X717554Y243016D01*
X717664Y242956D01*
X717789Y242916D01*
X717914Y242906D01*
X718039Y242916D01*
X718164Y242956D01*
X718274Y243016D01*
X718374Y243096D01*
X718454Y243196D01*
X718514Y243306D01*
X718554Y243431D01*
X718564Y243556D01*
Y245986D01*
X718594Y246016D01*
X718694Y246156D01*
X718714Y246196D01*
X718729Y246231D01*
X718749Y246271D01*
X718764Y246311D01*
X718774Y246351D01*
X718789Y246396D01*
X718794Y246436D01*
X718804Y246476D01*
X718809Y246521D01*
Y246561D01*
X718814Y246606D01*
X718809Y246651D01*
Y246691D01*
X718804Y246736D01*
X718794Y246776D01*
X718789Y246816D01*
X718774Y246861D01*
X718764Y246901D01*
X718749Y246941D01*
X718729Y246981D01*
X718714Y247016D01*
X718694Y247056D01*
X718594Y247196D01*
X718564Y247226D01*
Y249356D01*
X718554Y249481D01*
X718514Y249606D01*
X718454Y249716D01*
X718374Y249816D01*
X718274Y249896D01*
X718164Y249956D01*
X718039Y249996D01*
X717914Y250006D01*
G37*
G36*
G01X722638D02*
X722513Y249996D01*
X722388Y249956D01*
X722278Y249896D01*
X722178Y249816D01*
X722098Y249716D01*
X722038Y249606D01*
X721998Y249481D01*
X721988Y249356D01*
Y247231D01*
X721958Y247201D01*
X721933Y247166D01*
X721903Y247131D01*
X721883Y247096D01*
X721858Y247061D01*
X721818Y246981D01*
X721773Y246861D01*
X721763Y246821D01*
X721753Y246776D01*
X721748Y246736D01*
X721738Y246691D01*
Y246521D01*
X721748Y246476D01*
X721753Y246436D01*
X721763Y246391D01*
X721773Y246351D01*
X721818Y246231D01*
X721858Y246151D01*
X721883Y246116D01*
X721903Y246081D01*
X721933Y246046D01*
X721958Y246011D01*
X721988Y245981D01*
Y243556D01*
X721998Y243431D01*
X722038Y243306D01*
X722098Y243196D01*
X722178Y243096D01*
X722278Y243016D01*
X722388Y242956D01*
X722513Y242916D01*
X722638Y242906D01*
X722763Y242916D01*
X722888Y242956D01*
X722998Y243016D01*
X723098Y243096D01*
X723178Y243196D01*
X723238Y243306D01*
X723278Y243431D01*
X723288Y243556D01*
Y245986D01*
X723318Y246016D01*
X723418Y246156D01*
X723438Y246196D01*
X723453Y246231D01*
X723473Y246271D01*
X723488Y246311D01*
X723498Y246351D01*
X723513Y246396D01*
X723518Y246436D01*
X723528Y246476D01*
X723533Y246521D01*
Y246561D01*
X723538Y246606D01*
X723533Y246651D01*
Y246691D01*
X723528Y246736D01*
X723518Y246776D01*
X723513Y246816D01*
X723498Y246861D01*
X723488Y246901D01*
X723473Y246941D01*
X723453Y246981D01*
X723438Y247016D01*
X723418Y247056D01*
X723318Y247196D01*
X723288Y247226D01*
Y249356D01*
X723278Y249481D01*
X723238Y249606D01*
X723178Y249716D01*
X723098Y249816D01*
X722998Y249896D01*
X722888Y249956D01*
X722763Y249996D01*
X722638Y250006D01*
G37*
G36*
G01X727362D02*
X727237Y249996D01*
X727112Y249956D01*
X727002Y249896D01*
X726902Y249816D01*
X726822Y249716D01*
X726762Y249606D01*
X726722Y249481D01*
X726712Y249356D01*
Y247231D01*
X726682Y247201D01*
X726657Y247166D01*
X726627Y247131D01*
X726607Y247096D01*
X726582Y247061D01*
X726542Y246981D01*
X726497Y246861D01*
X726487Y246821D01*
X726477Y246776D01*
X726472Y246736D01*
X726462Y246691D01*
Y246521D01*
X726472Y246476D01*
X726477Y246436D01*
X726487Y246391D01*
X726497Y246351D01*
X726542Y246231D01*
X726582Y246151D01*
X726607Y246116D01*
X726627Y246081D01*
X726657Y246046D01*
X726682Y246011D01*
X726712Y245981D01*
Y243556D01*
X726722Y243431D01*
X726762Y243306D01*
X726822Y243196D01*
X726902Y243096D01*
X727002Y243016D01*
X727112Y242956D01*
X727237Y242916D01*
X727362Y242906D01*
X727487Y242916D01*
X727612Y242956D01*
X727722Y243016D01*
X727822Y243096D01*
X727902Y243196D01*
X727962Y243306D01*
X728002Y243431D01*
X728012Y243556D01*
Y245986D01*
X728042Y246016D01*
X728142Y246156D01*
X728162Y246196D01*
X728177Y246231D01*
X728197Y246271D01*
X728212Y246311D01*
X728222Y246351D01*
X728237Y246396D01*
X728242Y246436D01*
X728252Y246476D01*
X728257Y246521D01*
Y246561D01*
X728262Y246606D01*
X728257Y246651D01*
Y246691D01*
X728252Y246736D01*
X728242Y246776D01*
X728237Y246816D01*
X728222Y246861D01*
X728212Y246901D01*
X728197Y246941D01*
X728177Y246981D01*
X728162Y247016D01*
X728142Y247056D01*
X728042Y247196D01*
X728012Y247226D01*
Y249356D01*
X728002Y249481D01*
X727962Y249606D01*
X727902Y249716D01*
X727822Y249816D01*
X727722Y249896D01*
X727612Y249956D01*
X727487Y249996D01*
X727362Y250006D01*
G37*
G36*
G01X732087D02*
X731962Y249996D01*
X731837Y249956D01*
X731727Y249896D01*
X731627Y249816D01*
X731547Y249716D01*
X731487Y249606D01*
X731447Y249481D01*
X731437Y249356D01*
Y247231D01*
X731407Y247201D01*
X731382Y247166D01*
X731352Y247131D01*
X731332Y247096D01*
X731307Y247061D01*
X731267Y246981D01*
X731222Y246861D01*
X731212Y246821D01*
X731202Y246776D01*
X731197Y246736D01*
X731187Y246691D01*
Y246521D01*
X731197Y246476D01*
X731202Y246436D01*
X731212Y246391D01*
X731222Y246351D01*
X731267Y246231D01*
X731307Y246151D01*
X731332Y246116D01*
X731352Y246081D01*
X731382Y246046D01*
X731407Y246011D01*
X731437Y245981D01*
Y243556D01*
X731447Y243431D01*
X731487Y243306D01*
X731547Y243196D01*
X731627Y243096D01*
X731727Y243016D01*
X731837Y242956D01*
X731962Y242916D01*
X732087Y242906D01*
X732212Y242916D01*
X732337Y242956D01*
X732447Y243016D01*
X732547Y243096D01*
X732627Y243196D01*
X732687Y243306D01*
X732727Y243431D01*
X732737Y243556D01*
Y245986D01*
X732767Y246016D01*
X732867Y246156D01*
X732887Y246196D01*
X732902Y246231D01*
X732922Y246271D01*
X732937Y246311D01*
X732947Y246351D01*
X732962Y246396D01*
X732967Y246436D01*
X732977Y246476D01*
X732982Y246521D01*
Y246561D01*
X732987Y246606D01*
X732982Y246651D01*
Y246691D01*
X732977Y246736D01*
X732967Y246776D01*
X732962Y246816D01*
X732947Y246861D01*
X732937Y246901D01*
X732922Y246941D01*
X732902Y246981D01*
X732887Y247016D01*
X732867Y247056D01*
X732767Y247196D01*
X732737Y247226D01*
Y249356D01*
X732727Y249481D01*
X732687Y249606D01*
X732627Y249716D01*
X732547Y249816D01*
X732447Y249896D01*
X732337Y249956D01*
X732212Y249996D01*
X732087Y250006D01*
G37*
G36*
G01X736811D02*
X736686Y249996D01*
X736561Y249956D01*
X736451Y249896D01*
X736351Y249816D01*
X736271Y249716D01*
X736211Y249606D01*
X736171Y249481D01*
X736161Y249356D01*
Y247231D01*
X736131Y247201D01*
X736106Y247166D01*
X736076Y247131D01*
X736056Y247096D01*
X736031Y247061D01*
X735991Y246981D01*
X735946Y246861D01*
X735936Y246821D01*
X735926Y246776D01*
X735921Y246736D01*
X735911Y246691D01*
Y246521D01*
X735921Y246476D01*
X735926Y246436D01*
X735936Y246391D01*
X735946Y246351D01*
X735991Y246231D01*
X736031Y246151D01*
X736056Y246116D01*
X736076Y246081D01*
X736106Y246046D01*
X736131Y246011D01*
X736161Y245981D01*
Y243556D01*
X736171Y243431D01*
X736211Y243306D01*
X736271Y243196D01*
X736351Y243096D01*
X736451Y243016D01*
X736561Y242956D01*
X736686Y242916D01*
X736811Y242906D01*
X736936Y242916D01*
X737061Y242956D01*
X737171Y243016D01*
X737271Y243096D01*
X737351Y243196D01*
X737411Y243306D01*
X737451Y243431D01*
X737461Y243556D01*
Y245986D01*
X737491Y246016D01*
X737591Y246156D01*
X737611Y246196D01*
X737626Y246231D01*
X737646Y246271D01*
X737661Y246311D01*
X737671Y246351D01*
X737686Y246396D01*
X737691Y246436D01*
X737701Y246476D01*
X737706Y246521D01*
Y246561D01*
X737711Y246606D01*
X737706Y246651D01*
Y246691D01*
X737701Y246736D01*
X737691Y246776D01*
X737686Y246816D01*
X737671Y246861D01*
X737661Y246901D01*
X737646Y246941D01*
X737626Y246981D01*
X737611Y247016D01*
X737591Y247056D01*
X737491Y247196D01*
X737461Y247226D01*
Y249356D01*
X737451Y249481D01*
X737411Y249606D01*
X737351Y249716D01*
X737271Y249816D01*
X737171Y249896D01*
X737061Y249956D01*
X736936Y249996D01*
X736811Y250006D01*
G37*
G36*
G01X741536D02*
X741411Y249996D01*
X741286Y249956D01*
X741176Y249896D01*
X741076Y249816D01*
X740996Y249716D01*
X740936Y249606D01*
X740896Y249481D01*
X740886Y249356D01*
Y247231D01*
X740856Y247201D01*
X740831Y247166D01*
X740801Y247131D01*
X740781Y247096D01*
X740756Y247061D01*
X740716Y246981D01*
X740671Y246861D01*
X740661Y246821D01*
X740651Y246776D01*
X740646Y246736D01*
X740636Y246691D01*
Y246521D01*
X740646Y246476D01*
X740651Y246436D01*
X740661Y246391D01*
X740671Y246351D01*
X740716Y246231D01*
X740756Y246151D01*
X740781Y246116D01*
X740801Y246081D01*
X740831Y246046D01*
X740856Y246011D01*
X740886Y245981D01*
Y243556D01*
X740896Y243431D01*
X740936Y243306D01*
X740996Y243196D01*
X741076Y243096D01*
X741176Y243016D01*
X741286Y242956D01*
X741411Y242916D01*
X741536Y242906D01*
X741661Y242916D01*
X741786Y242956D01*
X741896Y243016D01*
X741996Y243096D01*
X742076Y243196D01*
X742136Y243306D01*
X742176Y243431D01*
X742186Y243556D01*
Y245986D01*
X742216Y246016D01*
X742316Y246156D01*
X742336Y246196D01*
X742351Y246231D01*
X742371Y246271D01*
X742386Y246311D01*
X742396Y246351D01*
X742411Y246396D01*
X742416Y246436D01*
X742426Y246476D01*
X742431Y246521D01*
Y246561D01*
X742436Y246606D01*
X742431Y246651D01*
Y246691D01*
X742426Y246736D01*
X742416Y246776D01*
X742411Y246816D01*
X742396Y246861D01*
X742386Y246901D01*
X742371Y246941D01*
X742351Y246981D01*
X742336Y247016D01*
X742316Y247056D01*
X742216Y247196D01*
X742186Y247226D01*
Y249356D01*
X742176Y249481D01*
X742136Y249606D01*
X742076Y249716D01*
X741996Y249816D01*
X741896Y249896D01*
X741786Y249956D01*
X741661Y249996D01*
X741536Y250006D01*
G37*
G36*
G01X746260D02*
X746135Y249996D01*
X746010Y249956D01*
X745900Y249896D01*
X745800Y249816D01*
X745720Y249716D01*
X745660Y249606D01*
X745620Y249481D01*
X745610Y249356D01*
Y247231D01*
X745580Y247201D01*
X745555Y247166D01*
X745525Y247131D01*
X745505Y247096D01*
X745480Y247061D01*
X745440Y246981D01*
X745395Y246861D01*
X745385Y246821D01*
X745375Y246776D01*
X745370Y246736D01*
X745360Y246691D01*
Y246521D01*
X745370Y246476D01*
X745375Y246436D01*
X745385Y246391D01*
X745395Y246351D01*
X745440Y246231D01*
X745480Y246151D01*
X745505Y246116D01*
X745525Y246081D01*
X745555Y246046D01*
X745580Y246011D01*
X745610Y245981D01*
Y243556D01*
X745620Y243431D01*
X745660Y243306D01*
X745720Y243196D01*
X745800Y243096D01*
X745900Y243016D01*
X746010Y242956D01*
X746135Y242916D01*
X746260Y242906D01*
X746385Y242916D01*
X746510Y242956D01*
X746620Y243016D01*
X746720Y243096D01*
X746800Y243196D01*
X746860Y243306D01*
X746900Y243431D01*
X746910Y243556D01*
Y245986D01*
X746940Y246016D01*
X747040Y246156D01*
X747060Y246196D01*
X747075Y246231D01*
X747095Y246271D01*
X747110Y246311D01*
X747120Y246351D01*
X747135Y246396D01*
X747140Y246436D01*
X747150Y246476D01*
X747155Y246521D01*
Y246561D01*
X747160Y246606D01*
X747155Y246651D01*
Y246691D01*
X747150Y246736D01*
X747140Y246776D01*
X747135Y246816D01*
X747120Y246861D01*
X747110Y246901D01*
X747095Y246941D01*
X747075Y246981D01*
X747060Y247016D01*
X747040Y247056D01*
X746940Y247196D01*
X746910Y247226D01*
Y249356D01*
X746900Y249481D01*
X746860Y249606D01*
X746800Y249716D01*
X746720Y249816D01*
X746620Y249896D01*
X746510Y249956D01*
X746385Y249996D01*
X746260Y250006D01*
G37*
G54D97*
X787246Y280709D03*
G36*
G01X502953Y250006D02*
X502828Y249996D01*
X502703Y249956D01*
X502593Y249896D01*
X502493Y249816D01*
X502413Y249716D01*
X502353Y249606D01*
X502313Y249481D01*
X502303Y249356D01*
Y248226D01*
X502273Y248196D01*
X502173Y248056D01*
X502153Y248016D01*
X502138Y247981D01*
X502118Y247941D01*
X502103Y247901D01*
X502093Y247861D01*
X502078Y247816D01*
X502073Y247776D01*
X502063Y247736D01*
X502058Y247691D01*
Y247651D01*
X502053Y247606D01*
X502058Y247561D01*
Y247521D01*
X502063Y247476D01*
X502073Y247436D01*
X502078Y247396D01*
X502093Y247351D01*
X502103Y247311D01*
X502118Y247271D01*
X502138Y247231D01*
X502153Y247196D01*
X502173Y247156D01*
X502273Y247016D01*
X502303Y246986D01*
Y243556D01*
X502313Y243431D01*
X502353Y243306D01*
X502413Y243196D01*
X502493Y243096D01*
X502593Y243016D01*
X502703Y242956D01*
X502828Y242916D01*
X502953Y242906D01*
X503078Y242916D01*
X503203Y242956D01*
X503313Y243016D01*
X503413Y243096D01*
X503493Y243196D01*
X503553Y243306D01*
X503593Y243431D01*
X503603Y243556D01*
Y246986D01*
X503633Y247016D01*
X503733Y247156D01*
X503753Y247196D01*
X503768Y247231D01*
X503788Y247271D01*
X503803Y247311D01*
X503813Y247351D01*
X503828Y247396D01*
X503833Y247436D01*
X503843Y247476D01*
X503848Y247521D01*
Y247561D01*
X503853Y247606D01*
X503848Y247651D01*
Y247691D01*
X503843Y247736D01*
X503833Y247776D01*
X503828Y247816D01*
X503813Y247861D01*
X503803Y247901D01*
X503788Y247941D01*
X503768Y247981D01*
X503753Y248016D01*
X503733Y248056D01*
X503633Y248196D01*
X503603Y248226D01*
Y249356D01*
X503593Y249481D01*
X503553Y249606D01*
X503493Y249716D01*
X503413Y249816D01*
X503313Y249896D01*
X503203Y249956D01*
X503078Y249996D01*
X502953Y250006D01*
G37*
G36*
G01X507677D02*
X507552Y249996D01*
X507427Y249956D01*
X507317Y249896D01*
X507217Y249816D01*
X507137Y249716D01*
X507077Y249606D01*
X507037Y249481D01*
X507027Y249356D01*
Y248226D01*
X506997Y248196D01*
X506897Y248056D01*
X506877Y248016D01*
X506862Y247981D01*
X506842Y247941D01*
X506827Y247901D01*
X506817Y247861D01*
X506802Y247816D01*
X506797Y247776D01*
X506787Y247736D01*
X506782Y247691D01*
Y247651D01*
X506777Y247606D01*
X506782Y247561D01*
Y247521D01*
X506787Y247476D01*
X506797Y247436D01*
X506802Y247396D01*
X506817Y247351D01*
X506827Y247311D01*
X506842Y247271D01*
X506862Y247231D01*
X506877Y247196D01*
X506897Y247156D01*
X506997Y247016D01*
X507027Y246986D01*
Y243556D01*
X507037Y243431D01*
X507077Y243306D01*
X507137Y243196D01*
X507217Y243096D01*
X507317Y243016D01*
X507427Y242956D01*
X507552Y242916D01*
X507677Y242906D01*
X507802Y242916D01*
X507927Y242956D01*
X508037Y243016D01*
X508137Y243096D01*
X508217Y243196D01*
X508277Y243306D01*
X508317Y243431D01*
X508327Y243556D01*
Y246986D01*
X508357Y247016D01*
X508457Y247156D01*
X508477Y247196D01*
X508492Y247231D01*
X508512Y247271D01*
X508527Y247311D01*
X508537Y247351D01*
X508552Y247396D01*
X508557Y247436D01*
X508567Y247476D01*
X508572Y247521D01*
Y247561D01*
X508577Y247606D01*
X508572Y247651D01*
Y247691D01*
X508567Y247736D01*
X508557Y247776D01*
X508552Y247816D01*
X508537Y247861D01*
X508527Y247901D01*
X508512Y247941D01*
X508492Y247981D01*
X508477Y248016D01*
X508457Y248056D01*
X508357Y248196D01*
X508327Y248226D01*
Y249356D01*
X508317Y249481D01*
X508277Y249606D01*
X508217Y249716D01*
X508137Y249816D01*
X508037Y249896D01*
X507927Y249956D01*
X507802Y249996D01*
X507677Y250006D01*
G37*
G36*
G01X512402D02*
X512277Y249996D01*
X512152Y249956D01*
X512042Y249896D01*
X511942Y249816D01*
X511862Y249716D01*
X511802Y249606D01*
X511762Y249481D01*
X511752Y249356D01*
Y248226D01*
X511722Y248196D01*
X511622Y248056D01*
X511602Y248016D01*
X511587Y247981D01*
X511567Y247941D01*
X511552Y247901D01*
X511542Y247861D01*
X511527Y247816D01*
X511522Y247776D01*
X511512Y247736D01*
X511507Y247691D01*
Y247651D01*
X511502Y247606D01*
X511507Y247561D01*
Y247521D01*
X511512Y247476D01*
X511522Y247436D01*
X511527Y247396D01*
X511542Y247351D01*
X511552Y247311D01*
X511567Y247271D01*
X511587Y247231D01*
X511602Y247196D01*
X511622Y247156D01*
X511722Y247016D01*
X511752Y246986D01*
Y243556D01*
X511762Y243431D01*
X511802Y243306D01*
X511862Y243196D01*
X511942Y243096D01*
X512042Y243016D01*
X512152Y242956D01*
X512277Y242916D01*
X512402Y242906D01*
X512527Y242916D01*
X512652Y242956D01*
X512762Y243016D01*
X512862Y243096D01*
X512942Y243196D01*
X513002Y243306D01*
X513042Y243431D01*
X513052Y243556D01*
Y246986D01*
X513082Y247016D01*
X513182Y247156D01*
X513202Y247196D01*
X513217Y247231D01*
X513237Y247271D01*
X513252Y247311D01*
X513262Y247351D01*
X513277Y247396D01*
X513282Y247436D01*
X513292Y247476D01*
X513297Y247521D01*
Y247561D01*
X513302Y247606D01*
X513297Y247651D01*
Y247691D01*
X513292Y247736D01*
X513282Y247776D01*
X513277Y247816D01*
X513262Y247861D01*
X513252Y247901D01*
X513237Y247941D01*
X513217Y247981D01*
X513202Y248016D01*
X513182Y248056D01*
X513082Y248196D01*
X513052Y248226D01*
Y249356D01*
X513042Y249481D01*
X513002Y249606D01*
X512942Y249716D01*
X512862Y249816D01*
X512762Y249896D01*
X512652Y249956D01*
X512527Y249996D01*
X512402Y250006D01*
G37*
G36*
G01X517126D02*
X517001Y249996D01*
X516876Y249956D01*
X516766Y249896D01*
X516666Y249816D01*
X516586Y249716D01*
X516526Y249606D01*
X516486Y249481D01*
X516476Y249356D01*
Y248226D01*
X516446Y248196D01*
X516346Y248056D01*
X516326Y248016D01*
X516311Y247981D01*
X516291Y247941D01*
X516276Y247901D01*
X516266Y247861D01*
X516251Y247816D01*
X516246Y247776D01*
X516236Y247736D01*
X516231Y247691D01*
Y247651D01*
X516226Y247606D01*
X516231Y247561D01*
Y247521D01*
X516236Y247476D01*
X516246Y247436D01*
X516251Y247396D01*
X516266Y247351D01*
X516276Y247311D01*
X516291Y247271D01*
X516311Y247231D01*
X516326Y247196D01*
X516346Y247156D01*
X516446Y247016D01*
X516476Y246986D01*
Y243556D01*
X516486Y243431D01*
X516526Y243306D01*
X516586Y243196D01*
X516666Y243096D01*
X516766Y243016D01*
X516876Y242956D01*
X517001Y242916D01*
X517126Y242906D01*
X517251Y242916D01*
X517376Y242956D01*
X517486Y243016D01*
X517586Y243096D01*
X517666Y243196D01*
X517726Y243306D01*
X517766Y243431D01*
X517776Y243556D01*
Y246986D01*
X517806Y247016D01*
X517906Y247156D01*
X517926Y247196D01*
X517941Y247231D01*
X517961Y247271D01*
X517976Y247311D01*
X517986Y247351D01*
X518001Y247396D01*
X518006Y247436D01*
X518016Y247476D01*
X518021Y247521D01*
Y247561D01*
X518026Y247606D01*
X518021Y247651D01*
Y247691D01*
X518016Y247736D01*
X518006Y247776D01*
X518001Y247816D01*
X517986Y247861D01*
X517976Y247901D01*
X517961Y247941D01*
X517941Y247981D01*
X517926Y248016D01*
X517906Y248056D01*
X517806Y248196D01*
X517776Y248226D01*
Y249356D01*
X517766Y249481D01*
X517726Y249606D01*
X517666Y249716D01*
X517586Y249816D01*
X517486Y249896D01*
X517376Y249956D01*
X517251Y249996D01*
X517126Y250006D01*
G37*
G36*
G01X521851D02*
X521726Y249996D01*
X521601Y249956D01*
X521491Y249896D01*
X521391Y249816D01*
X521311Y249716D01*
X521251Y249606D01*
X521211Y249481D01*
X521201Y249356D01*
Y248226D01*
X521171Y248196D01*
X521071Y248056D01*
X521051Y248016D01*
X521036Y247981D01*
X521016Y247941D01*
X521001Y247901D01*
X520991Y247861D01*
X520976Y247816D01*
X520971Y247776D01*
X520961Y247736D01*
X520956Y247691D01*
Y247651D01*
X520951Y247606D01*
X520956Y247561D01*
Y247521D01*
X520961Y247476D01*
X520971Y247436D01*
X520976Y247396D01*
X520991Y247351D01*
X521001Y247311D01*
X521016Y247271D01*
X521036Y247231D01*
X521051Y247196D01*
X521071Y247156D01*
X521171Y247016D01*
X521201Y246986D01*
Y243556D01*
X521211Y243431D01*
X521251Y243306D01*
X521311Y243196D01*
X521391Y243096D01*
X521491Y243016D01*
X521601Y242956D01*
X521726Y242916D01*
X521851Y242906D01*
X521976Y242916D01*
X522101Y242956D01*
X522211Y243016D01*
X522311Y243096D01*
X522391Y243196D01*
X522451Y243306D01*
X522491Y243431D01*
X522501Y243556D01*
Y246986D01*
X522531Y247016D01*
X522631Y247156D01*
X522651Y247196D01*
X522666Y247231D01*
X522686Y247271D01*
X522701Y247311D01*
X522711Y247351D01*
X522726Y247396D01*
X522731Y247436D01*
X522741Y247476D01*
X522746Y247521D01*
Y247561D01*
X522751Y247606D01*
X522746Y247651D01*
Y247691D01*
X522741Y247736D01*
X522731Y247776D01*
X522726Y247816D01*
X522711Y247861D01*
X522701Y247901D01*
X522686Y247941D01*
X522666Y247981D01*
X522651Y248016D01*
X522631Y248056D01*
X522531Y248196D01*
X522501Y248226D01*
Y249356D01*
X522491Y249481D01*
X522451Y249606D01*
X522391Y249716D01*
X522311Y249816D01*
X522211Y249896D01*
X522101Y249956D01*
X521976Y249996D01*
X521851Y250006D01*
G37*
G36*
G01X526575D02*
X526450Y249996D01*
X526325Y249956D01*
X526215Y249896D01*
X526115Y249816D01*
X526035Y249716D01*
X525975Y249606D01*
X525935Y249481D01*
X525925Y249356D01*
Y248226D01*
X525895Y248196D01*
X525795Y248056D01*
X525775Y248016D01*
X525760Y247981D01*
X525740Y247941D01*
X525725Y247901D01*
X525715Y247861D01*
X525700Y247816D01*
X525695Y247776D01*
X525685Y247736D01*
X525680Y247691D01*
Y247651D01*
X525675Y247606D01*
X525680Y247561D01*
Y247521D01*
X525685Y247476D01*
X525695Y247436D01*
X525700Y247396D01*
X525715Y247351D01*
X525725Y247311D01*
X525740Y247271D01*
X525760Y247231D01*
X525775Y247196D01*
X525795Y247156D01*
X525895Y247016D01*
X525925Y246986D01*
Y243556D01*
X525935Y243431D01*
X525975Y243306D01*
X526035Y243196D01*
X526115Y243096D01*
X526215Y243016D01*
X526325Y242956D01*
X526450Y242916D01*
X526575Y242906D01*
X526700Y242916D01*
X526825Y242956D01*
X526935Y243016D01*
X527035Y243096D01*
X527115Y243196D01*
X527175Y243306D01*
X527215Y243431D01*
X527225Y243556D01*
Y246986D01*
X527255Y247016D01*
X527355Y247156D01*
X527375Y247196D01*
X527390Y247231D01*
X527410Y247271D01*
X527425Y247311D01*
X527435Y247351D01*
X527450Y247396D01*
X527455Y247436D01*
X527465Y247476D01*
X527470Y247521D01*
Y247561D01*
X527475Y247606D01*
X527470Y247651D01*
Y247691D01*
X527465Y247736D01*
X527455Y247776D01*
X527450Y247816D01*
X527435Y247861D01*
X527425Y247901D01*
X527410Y247941D01*
X527390Y247981D01*
X527375Y248016D01*
X527355Y248056D01*
X527255Y248196D01*
X527225Y248226D01*
Y249356D01*
X527215Y249481D01*
X527175Y249606D01*
X527115Y249716D01*
X527035Y249816D01*
X526935Y249896D01*
X526825Y249956D01*
X526700Y249996D01*
X526575Y250006D01*
G37*
G36*
G01X531299D02*
X531174Y249996D01*
X531049Y249956D01*
X530939Y249896D01*
X530839Y249816D01*
X530759Y249716D01*
X530699Y249606D01*
X530659Y249481D01*
X530649Y249356D01*
Y248226D01*
X530619Y248196D01*
X530519Y248056D01*
X530499Y248016D01*
X530484Y247981D01*
X530464Y247941D01*
X530449Y247901D01*
X530439Y247861D01*
X530424Y247816D01*
X530419Y247776D01*
X530409Y247736D01*
X530404Y247691D01*
Y247651D01*
X530399Y247606D01*
X530404Y247561D01*
Y247521D01*
X530409Y247476D01*
X530419Y247436D01*
X530424Y247396D01*
X530439Y247351D01*
X530449Y247311D01*
X530464Y247271D01*
X530484Y247231D01*
X530499Y247196D01*
X530519Y247156D01*
X530619Y247016D01*
X530649Y246986D01*
Y243556D01*
X530659Y243431D01*
X530699Y243306D01*
X530759Y243196D01*
X530839Y243096D01*
X530939Y243016D01*
X531049Y242956D01*
X531174Y242916D01*
X531299Y242906D01*
X531424Y242916D01*
X531549Y242956D01*
X531659Y243016D01*
X531759Y243096D01*
X531839Y243196D01*
X531899Y243306D01*
X531939Y243431D01*
X531949Y243556D01*
Y246986D01*
X531979Y247016D01*
X532079Y247156D01*
X532099Y247196D01*
X532114Y247231D01*
X532134Y247271D01*
X532149Y247311D01*
X532159Y247351D01*
X532174Y247396D01*
X532179Y247436D01*
X532189Y247476D01*
X532194Y247521D01*
Y247561D01*
X532199Y247606D01*
X532194Y247651D01*
Y247691D01*
X532189Y247736D01*
X532179Y247776D01*
X532174Y247816D01*
X532159Y247861D01*
X532149Y247901D01*
X532134Y247941D01*
X532114Y247981D01*
X532099Y248016D01*
X532079Y248056D01*
X531979Y248196D01*
X531949Y248226D01*
Y249356D01*
X531939Y249481D01*
X531899Y249606D01*
X531839Y249716D01*
X531759Y249816D01*
X531659Y249896D01*
X531549Y249956D01*
X531424Y249996D01*
X531299Y250006D01*
G37*
G36*
G01X536024D02*
X535899Y249996D01*
X535774Y249956D01*
X535664Y249896D01*
X535564Y249816D01*
X535484Y249716D01*
X535424Y249606D01*
X535384Y249481D01*
X535374Y249356D01*
Y248226D01*
X535344Y248196D01*
X535244Y248056D01*
X535224Y248016D01*
X535209Y247981D01*
X535189Y247941D01*
X535174Y247901D01*
X535164Y247861D01*
X535149Y247816D01*
X535144Y247776D01*
X535134Y247736D01*
X535129Y247691D01*
Y247651D01*
X535124Y247606D01*
X535129Y247561D01*
Y247521D01*
X535134Y247476D01*
X535144Y247436D01*
X535149Y247396D01*
X535164Y247351D01*
X535174Y247311D01*
X535189Y247271D01*
X535209Y247231D01*
X535224Y247196D01*
X535244Y247156D01*
X535344Y247016D01*
X535374Y246986D01*
Y243556D01*
X535384Y243431D01*
X535424Y243306D01*
X535484Y243196D01*
X535564Y243096D01*
X535664Y243016D01*
X535774Y242956D01*
X535899Y242916D01*
X536024Y242906D01*
X536149Y242916D01*
X536274Y242956D01*
X536384Y243016D01*
X536484Y243096D01*
X536564Y243196D01*
X536624Y243306D01*
X536664Y243431D01*
X536674Y243556D01*
Y246986D01*
X536704Y247016D01*
X536804Y247156D01*
X536824Y247196D01*
X536839Y247231D01*
X536859Y247271D01*
X536874Y247311D01*
X536884Y247351D01*
X536899Y247396D01*
X536904Y247436D01*
X536914Y247476D01*
X536919Y247521D01*
Y247561D01*
X536924Y247606D01*
X536919Y247651D01*
Y247691D01*
X536914Y247736D01*
X536904Y247776D01*
X536899Y247816D01*
X536884Y247861D01*
X536874Y247901D01*
X536859Y247941D01*
X536839Y247981D01*
X536824Y248016D01*
X536804Y248056D01*
X536704Y248196D01*
X536674Y248226D01*
Y249356D01*
X536664Y249481D01*
X536624Y249606D01*
X536564Y249716D01*
X536484Y249816D01*
X536384Y249896D01*
X536274Y249956D01*
X536149Y249996D01*
X536024Y250006D01*
G37*
G36*
G01X540748D02*
X540623Y249996D01*
X540498Y249956D01*
X540388Y249896D01*
X540288Y249816D01*
X540208Y249716D01*
X540148Y249606D01*
X540108Y249481D01*
X540098Y249356D01*
Y248226D01*
X540068Y248196D01*
X539968Y248056D01*
X539948Y248016D01*
X539933Y247981D01*
X539913Y247941D01*
X539898Y247901D01*
X539888Y247861D01*
X539873Y247816D01*
X539868Y247776D01*
X539858Y247736D01*
X539853Y247691D01*
Y247651D01*
X539848Y247606D01*
X539853Y247561D01*
Y247521D01*
X539858Y247476D01*
X539868Y247436D01*
X539873Y247396D01*
X539888Y247351D01*
X539898Y247311D01*
X539913Y247271D01*
X539933Y247231D01*
X539948Y247196D01*
X539968Y247156D01*
X540068Y247016D01*
X540098Y246986D01*
Y243556D01*
X540108Y243431D01*
X540148Y243306D01*
X540208Y243196D01*
X540288Y243096D01*
X540388Y243016D01*
X540498Y242956D01*
X540623Y242916D01*
X540748Y242906D01*
X540873Y242916D01*
X540998Y242956D01*
X541108Y243016D01*
X541208Y243096D01*
X541288Y243196D01*
X541348Y243306D01*
X541388Y243431D01*
X541398Y243556D01*
Y246986D01*
X541428Y247016D01*
X541528Y247156D01*
X541548Y247196D01*
X541563Y247231D01*
X541583Y247271D01*
X541598Y247311D01*
X541608Y247351D01*
X541623Y247396D01*
X541628Y247436D01*
X541638Y247476D01*
X541643Y247521D01*
Y247561D01*
X541648Y247606D01*
X541643Y247651D01*
Y247691D01*
X541638Y247736D01*
X541628Y247776D01*
X541623Y247816D01*
X541608Y247861D01*
X541598Y247901D01*
X541583Y247941D01*
X541563Y247981D01*
X541548Y248016D01*
X541528Y248056D01*
X541428Y248196D01*
X541398Y248226D01*
Y249356D01*
X541388Y249481D01*
X541348Y249606D01*
X541288Y249716D01*
X541208Y249816D01*
X541108Y249896D01*
X540998Y249956D01*
X540873Y249996D01*
X540748Y250006D01*
G37*
G36*
G01X545473D02*
X545348Y249996D01*
X545223Y249956D01*
X545113Y249896D01*
X545013Y249816D01*
X544933Y249716D01*
X544873Y249606D01*
X544833Y249481D01*
X544823Y249356D01*
Y248226D01*
X544793Y248196D01*
X544693Y248056D01*
X544673Y248016D01*
X544658Y247981D01*
X544638Y247941D01*
X544623Y247901D01*
X544613Y247861D01*
X544598Y247816D01*
X544593Y247776D01*
X544583Y247736D01*
X544578Y247691D01*
Y247651D01*
X544573Y247606D01*
X544578Y247561D01*
Y247521D01*
X544583Y247476D01*
X544593Y247436D01*
X544598Y247396D01*
X544613Y247351D01*
X544623Y247311D01*
X544638Y247271D01*
X544658Y247231D01*
X544673Y247196D01*
X544693Y247156D01*
X544793Y247016D01*
X544823Y246986D01*
Y243556D01*
X544833Y243431D01*
X544873Y243306D01*
X544933Y243196D01*
X545013Y243096D01*
X545113Y243016D01*
X545223Y242956D01*
X545348Y242916D01*
X545473Y242906D01*
X545598Y242916D01*
X545723Y242956D01*
X545833Y243016D01*
X545933Y243096D01*
X546013Y243196D01*
X546073Y243306D01*
X546113Y243431D01*
X546123Y243556D01*
Y246986D01*
X546153Y247016D01*
X546253Y247156D01*
X546273Y247196D01*
X546288Y247231D01*
X546308Y247271D01*
X546323Y247311D01*
X546333Y247351D01*
X546348Y247396D01*
X546353Y247436D01*
X546363Y247476D01*
X546368Y247521D01*
Y247561D01*
X546373Y247606D01*
X546368Y247651D01*
Y247691D01*
X546363Y247736D01*
X546353Y247776D01*
X546348Y247816D01*
X546333Y247861D01*
X546323Y247901D01*
X546308Y247941D01*
X546288Y247981D01*
X546273Y248016D01*
X546253Y248056D01*
X546153Y248196D01*
X546123Y248226D01*
Y249356D01*
X546113Y249481D01*
X546073Y249606D01*
X546013Y249716D01*
X545933Y249816D01*
X545833Y249896D01*
X545723Y249956D01*
X545598Y249996D01*
X545473Y250006D01*
G37*
G36*
G01X550197D02*
X550072Y249996D01*
X549947Y249956D01*
X549837Y249896D01*
X549737Y249816D01*
X549657Y249716D01*
X549597Y249606D01*
X549557Y249481D01*
X549547Y249356D01*
Y248226D01*
X549517Y248196D01*
X549417Y248056D01*
X549397Y248016D01*
X549382Y247981D01*
X549362Y247941D01*
X549347Y247901D01*
X549337Y247861D01*
X549322Y247816D01*
X549317Y247776D01*
X549307Y247736D01*
X549302Y247691D01*
Y247651D01*
X549297Y247606D01*
X549302Y247561D01*
Y247521D01*
X549307Y247476D01*
X549317Y247436D01*
X549322Y247396D01*
X549337Y247351D01*
X549347Y247311D01*
X549362Y247271D01*
X549382Y247231D01*
X549397Y247196D01*
X549417Y247156D01*
X549517Y247016D01*
X549547Y246986D01*
Y243556D01*
X549557Y243431D01*
X549597Y243306D01*
X549657Y243196D01*
X549737Y243096D01*
X549837Y243016D01*
X549947Y242956D01*
X550072Y242916D01*
X550197Y242906D01*
X550322Y242916D01*
X550447Y242956D01*
X550557Y243016D01*
X550657Y243096D01*
X550737Y243196D01*
X550797Y243306D01*
X550837Y243431D01*
X550847Y243556D01*
Y246986D01*
X550877Y247016D01*
X550977Y247156D01*
X550997Y247196D01*
X551012Y247231D01*
X551032Y247271D01*
X551047Y247311D01*
X551057Y247351D01*
X551072Y247396D01*
X551077Y247436D01*
X551087Y247476D01*
X551092Y247521D01*
Y247561D01*
X551097Y247606D01*
X551092Y247651D01*
Y247691D01*
X551087Y247736D01*
X551077Y247776D01*
X551072Y247816D01*
X551057Y247861D01*
X551047Y247901D01*
X551032Y247941D01*
X551012Y247981D01*
X550997Y248016D01*
X550977Y248056D01*
X550877Y248196D01*
X550847Y248226D01*
Y249356D01*
X550837Y249481D01*
X550797Y249606D01*
X550737Y249716D01*
X550657Y249816D01*
X550557Y249896D01*
X550447Y249956D01*
X550322Y249996D01*
X550197Y250006D01*
G37*
G36*
G01X554922D02*
X554797Y249996D01*
X554672Y249956D01*
X554562Y249896D01*
X554462Y249816D01*
X554382Y249716D01*
X554322Y249606D01*
X554282Y249481D01*
X554272Y249356D01*
Y248226D01*
X554242Y248196D01*
X554142Y248056D01*
X554122Y248016D01*
X554107Y247981D01*
X554087Y247941D01*
X554072Y247901D01*
X554062Y247861D01*
X554047Y247816D01*
X554042Y247776D01*
X554032Y247736D01*
X554027Y247691D01*
Y247651D01*
X554022Y247606D01*
X554027Y247561D01*
Y247521D01*
X554032Y247476D01*
X554042Y247436D01*
X554047Y247396D01*
X554062Y247351D01*
X554072Y247311D01*
X554087Y247271D01*
X554107Y247231D01*
X554122Y247196D01*
X554142Y247156D01*
X554242Y247016D01*
X554272Y246986D01*
Y243556D01*
X554282Y243431D01*
X554322Y243306D01*
X554382Y243196D01*
X554462Y243096D01*
X554562Y243016D01*
X554672Y242956D01*
X554797Y242916D01*
X554922Y242906D01*
X555047Y242916D01*
X555172Y242956D01*
X555282Y243016D01*
X555382Y243096D01*
X555462Y243196D01*
X555522Y243306D01*
X555562Y243431D01*
X555572Y243556D01*
Y246986D01*
X555602Y247016D01*
X555702Y247156D01*
X555722Y247196D01*
X555737Y247231D01*
X555757Y247271D01*
X555772Y247311D01*
X555782Y247351D01*
X555797Y247396D01*
X555802Y247436D01*
X555812Y247476D01*
X555817Y247521D01*
Y247561D01*
X555822Y247606D01*
X555817Y247651D01*
Y247691D01*
X555812Y247736D01*
X555802Y247776D01*
X555797Y247816D01*
X555782Y247861D01*
X555772Y247901D01*
X555757Y247941D01*
X555737Y247981D01*
X555722Y248016D01*
X555702Y248056D01*
X555602Y248196D01*
X555572Y248226D01*
Y249356D01*
X555562Y249481D01*
X555522Y249606D01*
X555462Y249716D01*
X555382Y249816D01*
X555282Y249896D01*
X555172Y249956D01*
X555047Y249996D01*
X554922Y250006D01*
G37*
G36*
G01X559646D02*
X559521Y249996D01*
X559396Y249956D01*
X559286Y249896D01*
X559186Y249816D01*
X559106Y249716D01*
X559046Y249606D01*
X559006Y249481D01*
X558996Y249356D01*
Y248226D01*
X558966Y248196D01*
X558866Y248056D01*
X558846Y248016D01*
X558831Y247981D01*
X558811Y247941D01*
X558796Y247901D01*
X558786Y247861D01*
X558771Y247816D01*
X558766Y247776D01*
X558756Y247736D01*
X558751Y247691D01*
Y247651D01*
X558746Y247606D01*
X558751Y247561D01*
Y247521D01*
X558756Y247476D01*
X558766Y247436D01*
X558771Y247396D01*
X558786Y247351D01*
X558796Y247311D01*
X558811Y247271D01*
X558831Y247231D01*
X558846Y247196D01*
X558866Y247156D01*
X558966Y247016D01*
X558996Y246986D01*
Y243556D01*
X559006Y243431D01*
X559046Y243306D01*
X559106Y243196D01*
X559186Y243096D01*
X559286Y243016D01*
X559396Y242956D01*
X559521Y242916D01*
X559646Y242906D01*
X559771Y242916D01*
X559896Y242956D01*
X560006Y243016D01*
X560106Y243096D01*
X560186Y243196D01*
X560246Y243306D01*
X560286Y243431D01*
X560296Y243556D01*
Y246986D01*
X560326Y247016D01*
X560426Y247156D01*
X560446Y247196D01*
X560461Y247231D01*
X560481Y247271D01*
X560496Y247311D01*
X560506Y247351D01*
X560521Y247396D01*
X560526Y247436D01*
X560536Y247476D01*
X560541Y247521D01*
Y247561D01*
X560546Y247606D01*
X560541Y247651D01*
Y247691D01*
X560536Y247736D01*
X560526Y247776D01*
X560521Y247816D01*
X560506Y247861D01*
X560496Y247901D01*
X560481Y247941D01*
X560461Y247981D01*
X560446Y248016D01*
X560426Y248056D01*
X560326Y248196D01*
X560296Y248226D01*
Y249356D01*
X560286Y249481D01*
X560246Y249606D01*
X560186Y249716D01*
X560106Y249816D01*
X560006Y249896D01*
X559896Y249956D01*
X559771Y249996D01*
X559646Y250006D01*
G37*
G36*
G01X564370D02*
X564245Y249996D01*
X564120Y249956D01*
X564010Y249896D01*
X563910Y249816D01*
X563830Y249716D01*
X563770Y249606D01*
X563730Y249481D01*
X563720Y249356D01*
Y248226D01*
X563690Y248196D01*
X563590Y248056D01*
X563570Y248016D01*
X563555Y247981D01*
X563535Y247941D01*
X563520Y247901D01*
X563510Y247861D01*
X563495Y247816D01*
X563490Y247776D01*
X563480Y247736D01*
X563475Y247691D01*
Y247651D01*
X563470Y247606D01*
X563475Y247561D01*
Y247521D01*
X563480Y247476D01*
X563490Y247436D01*
X563495Y247396D01*
X563510Y247351D01*
X563520Y247311D01*
X563535Y247271D01*
X563555Y247231D01*
X563570Y247196D01*
X563590Y247156D01*
X563690Y247016D01*
X563720Y246986D01*
Y243556D01*
X563730Y243431D01*
X563770Y243306D01*
X563830Y243196D01*
X563910Y243096D01*
X564010Y243016D01*
X564120Y242956D01*
X564245Y242916D01*
X564370Y242906D01*
X564495Y242916D01*
X564620Y242956D01*
X564730Y243016D01*
X564830Y243096D01*
X564910Y243196D01*
X564970Y243306D01*
X565010Y243431D01*
X565020Y243556D01*
Y246986D01*
X565050Y247016D01*
X565150Y247156D01*
X565170Y247196D01*
X565185Y247231D01*
X565205Y247271D01*
X565220Y247311D01*
X565230Y247351D01*
X565245Y247396D01*
X565250Y247436D01*
X565260Y247476D01*
X565265Y247521D01*
Y247561D01*
X565270Y247606D01*
X565265Y247651D01*
Y247691D01*
X565260Y247736D01*
X565250Y247776D01*
X565245Y247816D01*
X565230Y247861D01*
X565220Y247901D01*
X565205Y247941D01*
X565185Y247981D01*
X565170Y248016D01*
X565150Y248056D01*
X565050Y248196D01*
X565020Y248226D01*
Y249356D01*
X565010Y249481D01*
X564970Y249606D01*
X564910Y249716D01*
X564830Y249816D01*
X564730Y249896D01*
X564620Y249956D01*
X564495Y249996D01*
X564370Y250006D01*
G37*
G36*
G01X569095D02*
X568970Y249996D01*
X568845Y249956D01*
X568735Y249896D01*
X568635Y249816D01*
X568555Y249716D01*
X568495Y249606D01*
X568455Y249481D01*
X568445Y249356D01*
Y248226D01*
X568415Y248196D01*
X568315Y248056D01*
X568295Y248016D01*
X568280Y247981D01*
X568260Y247941D01*
X568245Y247901D01*
X568235Y247861D01*
X568220Y247816D01*
X568215Y247776D01*
X568205Y247736D01*
X568200Y247691D01*
Y247651D01*
X568195Y247606D01*
X568200Y247561D01*
Y247521D01*
X568205Y247476D01*
X568215Y247436D01*
X568220Y247396D01*
X568235Y247351D01*
X568245Y247311D01*
X568260Y247271D01*
X568280Y247231D01*
X568295Y247196D01*
X568315Y247156D01*
X568415Y247016D01*
X568445Y246986D01*
Y243556D01*
X568455Y243431D01*
X568495Y243306D01*
X568555Y243196D01*
X568635Y243096D01*
X568735Y243016D01*
X568845Y242956D01*
X568970Y242916D01*
X569095Y242906D01*
X569220Y242916D01*
X569345Y242956D01*
X569455Y243016D01*
X569555Y243096D01*
X569635Y243196D01*
X569695Y243306D01*
X569735Y243431D01*
X569745Y243556D01*
Y246986D01*
X569775Y247016D01*
X569875Y247156D01*
X569895Y247196D01*
X569910Y247231D01*
X569930Y247271D01*
X569945Y247311D01*
X569955Y247351D01*
X569970Y247396D01*
X569975Y247436D01*
X569985Y247476D01*
X569990Y247521D01*
Y247561D01*
X569995Y247606D01*
X569990Y247651D01*
Y247691D01*
X569985Y247736D01*
X569975Y247776D01*
X569970Y247816D01*
X569955Y247861D01*
X569945Y247901D01*
X569930Y247941D01*
X569910Y247981D01*
X569895Y248016D01*
X569875Y248056D01*
X569775Y248196D01*
X569745Y248226D01*
Y249356D01*
X569735Y249481D01*
X569695Y249606D01*
X569635Y249716D01*
X569555Y249816D01*
X569455Y249896D01*
X569345Y249956D01*
X569220Y249996D01*
X569095Y250006D01*
G37*
G36*
G01X573819D02*
X573694Y249996D01*
X573569Y249956D01*
X573459Y249896D01*
X573359Y249816D01*
X573279Y249716D01*
X573219Y249606D01*
X573179Y249481D01*
X573169Y249356D01*
Y248226D01*
X573139Y248196D01*
X573039Y248056D01*
X573019Y248016D01*
X573004Y247981D01*
X572984Y247941D01*
X572969Y247901D01*
X572959Y247861D01*
X572944Y247816D01*
X572939Y247776D01*
X572929Y247736D01*
X572924Y247691D01*
Y247651D01*
X572919Y247606D01*
X572924Y247561D01*
Y247521D01*
X572929Y247476D01*
X572939Y247436D01*
X572944Y247396D01*
X572959Y247351D01*
X572969Y247311D01*
X572984Y247271D01*
X573004Y247231D01*
X573019Y247196D01*
X573039Y247156D01*
X573139Y247016D01*
X573169Y246986D01*
Y243556D01*
X573179Y243431D01*
X573219Y243306D01*
X573279Y243196D01*
X573359Y243096D01*
X573459Y243016D01*
X573569Y242956D01*
X573694Y242916D01*
X573819Y242906D01*
X573944Y242916D01*
X574069Y242956D01*
X574179Y243016D01*
X574279Y243096D01*
X574359Y243196D01*
X574419Y243306D01*
X574459Y243431D01*
X574469Y243556D01*
Y246986D01*
X574499Y247016D01*
X574599Y247156D01*
X574619Y247196D01*
X574634Y247231D01*
X574654Y247271D01*
X574669Y247311D01*
X574679Y247351D01*
X574694Y247396D01*
X574699Y247436D01*
X574709Y247476D01*
X574714Y247521D01*
Y247561D01*
X574719Y247606D01*
X574714Y247651D01*
Y247691D01*
X574709Y247736D01*
X574699Y247776D01*
X574694Y247816D01*
X574679Y247861D01*
X574669Y247901D01*
X574654Y247941D01*
X574634Y247981D01*
X574619Y248016D01*
X574599Y248056D01*
X574499Y248196D01*
X574469Y248226D01*
Y249356D01*
X574459Y249481D01*
X574419Y249606D01*
X574359Y249716D01*
X574279Y249816D01*
X574179Y249896D01*
X574069Y249956D01*
X573944Y249996D01*
X573819Y250006D01*
G37*
G36*
G01X578544D02*
X578419Y249996D01*
X578294Y249956D01*
X578184Y249896D01*
X578084Y249816D01*
X578004Y249716D01*
X577944Y249606D01*
X577904Y249481D01*
X577894Y249356D01*
Y248226D01*
X577864Y248196D01*
X577764Y248056D01*
X577744Y248016D01*
X577729Y247981D01*
X577709Y247941D01*
X577694Y247901D01*
X577684Y247861D01*
X577669Y247816D01*
X577664Y247776D01*
X577654Y247736D01*
X577649Y247691D01*
Y247651D01*
X577644Y247606D01*
X577649Y247561D01*
Y247521D01*
X577654Y247476D01*
X577664Y247436D01*
X577669Y247396D01*
X577684Y247351D01*
X577694Y247311D01*
X577709Y247271D01*
X577729Y247231D01*
X577744Y247196D01*
X577764Y247156D01*
X577864Y247016D01*
X577894Y246986D01*
Y243556D01*
X577904Y243431D01*
X577944Y243306D01*
X578004Y243196D01*
X578084Y243096D01*
X578184Y243016D01*
X578294Y242956D01*
X578419Y242916D01*
X578544Y242906D01*
X578669Y242916D01*
X578794Y242956D01*
X578904Y243016D01*
X579004Y243096D01*
X579084Y243196D01*
X579144Y243306D01*
X579184Y243431D01*
X579194Y243556D01*
Y246986D01*
X579224Y247016D01*
X579324Y247156D01*
X579344Y247196D01*
X579359Y247231D01*
X579379Y247271D01*
X579394Y247311D01*
X579404Y247351D01*
X579419Y247396D01*
X579424Y247436D01*
X579434Y247476D01*
X579439Y247521D01*
Y247561D01*
X579444Y247606D01*
X579439Y247651D01*
Y247691D01*
X579434Y247736D01*
X579424Y247776D01*
X579419Y247816D01*
X579404Y247861D01*
X579394Y247901D01*
X579379Y247941D01*
X579359Y247981D01*
X579344Y248016D01*
X579324Y248056D01*
X579224Y248196D01*
X579194Y248226D01*
Y249356D01*
X579184Y249481D01*
X579144Y249606D01*
X579084Y249716D01*
X579004Y249816D01*
X578904Y249896D01*
X578794Y249956D01*
X578669Y249996D01*
X578544Y250006D01*
G37*
G36*
G01X583268D02*
X583143Y249996D01*
X583018Y249956D01*
X582908Y249896D01*
X582808Y249816D01*
X582728Y249716D01*
X582668Y249606D01*
X582628Y249481D01*
X582618Y249356D01*
Y248226D01*
X582588Y248196D01*
X582488Y248056D01*
X582468Y248016D01*
X582453Y247981D01*
X582433Y247941D01*
X582418Y247901D01*
X582408Y247861D01*
X582393Y247816D01*
X582388Y247776D01*
X582378Y247736D01*
X582373Y247691D01*
Y247651D01*
X582368Y247606D01*
X582373Y247561D01*
Y247521D01*
X582378Y247476D01*
X582388Y247436D01*
X582393Y247396D01*
X582408Y247351D01*
X582418Y247311D01*
X582433Y247271D01*
X582453Y247231D01*
X582468Y247196D01*
X582488Y247156D01*
X582588Y247016D01*
X582618Y246986D01*
Y243556D01*
X582628Y243431D01*
X582668Y243306D01*
X582728Y243196D01*
X582808Y243096D01*
X582908Y243016D01*
X583018Y242956D01*
X583143Y242916D01*
X583268Y242906D01*
X583393Y242916D01*
X583518Y242956D01*
X583628Y243016D01*
X583728Y243096D01*
X583808Y243196D01*
X583868Y243306D01*
X583908Y243431D01*
X583918Y243556D01*
Y246986D01*
X583948Y247016D01*
X584048Y247156D01*
X584068Y247196D01*
X584083Y247231D01*
X584103Y247271D01*
X584118Y247311D01*
X584128Y247351D01*
X584143Y247396D01*
X584148Y247436D01*
X584158Y247476D01*
X584163Y247521D01*
Y247561D01*
X584168Y247606D01*
X584163Y247651D01*
Y247691D01*
X584158Y247736D01*
X584148Y247776D01*
X584143Y247816D01*
X584128Y247861D01*
X584118Y247901D01*
X584103Y247941D01*
X584083Y247981D01*
X584068Y248016D01*
X584048Y248056D01*
X583948Y248196D01*
X583918Y248226D01*
Y249356D01*
X583908Y249481D01*
X583868Y249606D01*
X583808Y249716D01*
X583728Y249816D01*
X583628Y249896D01*
X583518Y249956D01*
X583393Y249996D01*
X583268Y250006D01*
G37*
G36*
G01X587992D02*
X587867Y249996D01*
X587742Y249956D01*
X587632Y249896D01*
X587532Y249816D01*
X587452Y249716D01*
X587392Y249606D01*
X587352Y249481D01*
X587342Y249356D01*
Y248226D01*
X587312Y248196D01*
X587212Y248056D01*
X587192Y248016D01*
X587177Y247981D01*
X587157Y247941D01*
X587142Y247901D01*
X587132Y247861D01*
X587117Y247816D01*
X587112Y247776D01*
X587102Y247736D01*
X587097Y247691D01*
Y247651D01*
X587092Y247606D01*
X587097Y247561D01*
Y247521D01*
X587102Y247476D01*
X587112Y247436D01*
X587117Y247396D01*
X587132Y247351D01*
X587142Y247311D01*
X587157Y247271D01*
X587177Y247231D01*
X587192Y247196D01*
X587212Y247156D01*
X587312Y247016D01*
X587342Y246986D01*
Y243556D01*
X587352Y243431D01*
X587392Y243306D01*
X587452Y243196D01*
X587532Y243096D01*
X587632Y243016D01*
X587742Y242956D01*
X587867Y242916D01*
X587992Y242906D01*
X588117Y242916D01*
X588242Y242956D01*
X588352Y243016D01*
X588452Y243096D01*
X588532Y243196D01*
X588592Y243306D01*
X588632Y243431D01*
X588642Y243556D01*
Y246986D01*
X588672Y247016D01*
X588772Y247156D01*
X588792Y247196D01*
X588807Y247231D01*
X588827Y247271D01*
X588842Y247311D01*
X588852Y247351D01*
X588867Y247396D01*
X588872Y247436D01*
X588882Y247476D01*
X588887Y247521D01*
Y247561D01*
X588892Y247606D01*
X588887Y247651D01*
Y247691D01*
X588882Y247736D01*
X588872Y247776D01*
X588867Y247816D01*
X588852Y247861D01*
X588842Y247901D01*
X588827Y247941D01*
X588807Y247981D01*
X588792Y248016D01*
X588772Y248056D01*
X588672Y248196D01*
X588642Y248226D01*
Y249356D01*
X588632Y249481D01*
X588592Y249606D01*
X588532Y249716D01*
X588452Y249816D01*
X588352Y249896D01*
X588242Y249956D01*
X588117Y249996D01*
X587992Y250006D01*
G37*
G36*
G01X592717D02*
X592592Y249996D01*
X592467Y249956D01*
X592357Y249896D01*
X592257Y249816D01*
X592177Y249716D01*
X592117Y249606D01*
X592077Y249481D01*
X592067Y249356D01*
Y248226D01*
X592037Y248196D01*
X591937Y248056D01*
X591917Y248016D01*
X591902Y247981D01*
X591882Y247941D01*
X591867Y247901D01*
X591857Y247861D01*
X591842Y247816D01*
X591837Y247776D01*
X591827Y247736D01*
X591822Y247691D01*
Y247651D01*
X591817Y247606D01*
X591822Y247561D01*
Y247521D01*
X591827Y247476D01*
X591837Y247436D01*
X591842Y247396D01*
X591857Y247351D01*
X591867Y247311D01*
X591882Y247271D01*
X591902Y247231D01*
X591917Y247196D01*
X591937Y247156D01*
X592037Y247016D01*
X592067Y246986D01*
Y243556D01*
X592077Y243431D01*
X592117Y243306D01*
X592177Y243196D01*
X592257Y243096D01*
X592357Y243016D01*
X592467Y242956D01*
X592592Y242916D01*
X592717Y242906D01*
X592842Y242916D01*
X592967Y242956D01*
X593077Y243016D01*
X593177Y243096D01*
X593257Y243196D01*
X593317Y243306D01*
X593357Y243431D01*
X593367Y243556D01*
Y246986D01*
X593397Y247016D01*
X593497Y247156D01*
X593517Y247196D01*
X593532Y247231D01*
X593552Y247271D01*
X593567Y247311D01*
X593577Y247351D01*
X593592Y247396D01*
X593597Y247436D01*
X593607Y247476D01*
X593612Y247521D01*
Y247561D01*
X593617Y247606D01*
X593612Y247651D01*
Y247691D01*
X593607Y247736D01*
X593597Y247776D01*
X593592Y247816D01*
X593577Y247861D01*
X593567Y247901D01*
X593552Y247941D01*
X593532Y247981D01*
X593517Y248016D01*
X593497Y248056D01*
X593397Y248196D01*
X593367Y248226D01*
Y249356D01*
X593357Y249481D01*
X593317Y249606D01*
X593257Y249716D01*
X593177Y249816D01*
X593077Y249896D01*
X592967Y249956D01*
X592842Y249996D01*
X592717Y250006D01*
G37*
G36*
G01X597441D02*
X597316Y249996D01*
X597191Y249956D01*
X597081Y249896D01*
X596981Y249816D01*
X596901Y249716D01*
X596841Y249606D01*
X596801Y249481D01*
X596791Y249356D01*
Y248226D01*
X596761Y248196D01*
X596661Y248056D01*
X596641Y248016D01*
X596626Y247981D01*
X596606Y247941D01*
X596591Y247901D01*
X596581Y247861D01*
X596566Y247816D01*
X596561Y247776D01*
X596551Y247736D01*
X596546Y247691D01*
Y247651D01*
X596541Y247606D01*
X596546Y247561D01*
Y247521D01*
X596551Y247476D01*
X596561Y247436D01*
X596566Y247396D01*
X596581Y247351D01*
X596591Y247311D01*
X596606Y247271D01*
X596626Y247231D01*
X596641Y247196D01*
X596661Y247156D01*
X596761Y247016D01*
X596791Y246986D01*
Y243556D01*
X596801Y243431D01*
X596841Y243306D01*
X596901Y243196D01*
X596981Y243096D01*
X597081Y243016D01*
X597191Y242956D01*
X597316Y242916D01*
X597441Y242906D01*
X597566Y242916D01*
X597691Y242956D01*
X597801Y243016D01*
X597901Y243096D01*
X597981Y243196D01*
X598041Y243306D01*
X598081Y243431D01*
X598091Y243556D01*
Y246986D01*
X598121Y247016D01*
X598221Y247156D01*
X598241Y247196D01*
X598256Y247231D01*
X598276Y247271D01*
X598291Y247311D01*
X598301Y247351D01*
X598316Y247396D01*
X598321Y247436D01*
X598331Y247476D01*
X598336Y247521D01*
Y247561D01*
X598341Y247606D01*
X598336Y247651D01*
Y247691D01*
X598331Y247736D01*
X598321Y247776D01*
X598316Y247816D01*
X598301Y247861D01*
X598291Y247901D01*
X598276Y247941D01*
X598256Y247981D01*
X598241Y248016D01*
X598221Y248056D01*
X598121Y248196D01*
X598091Y248226D01*
Y249356D01*
X598081Y249481D01*
X598041Y249606D01*
X597981Y249716D01*
X597901Y249816D01*
X597801Y249896D01*
X597691Y249956D01*
X597566Y249996D01*
X597441Y250006D01*
G37*
G36*
G01X602166D02*
X602041Y249996D01*
X601916Y249956D01*
X601806Y249896D01*
X601706Y249816D01*
X601626Y249716D01*
X601566Y249606D01*
X601526Y249481D01*
X601516Y249356D01*
Y248226D01*
X601486Y248196D01*
X601386Y248056D01*
X601366Y248016D01*
X601351Y247981D01*
X601331Y247941D01*
X601316Y247901D01*
X601306Y247861D01*
X601291Y247816D01*
X601286Y247776D01*
X601276Y247736D01*
X601271Y247691D01*
Y247651D01*
X601266Y247606D01*
X601271Y247561D01*
Y247521D01*
X601276Y247476D01*
X601286Y247436D01*
X601291Y247396D01*
X601306Y247351D01*
X601316Y247311D01*
X601331Y247271D01*
X601351Y247231D01*
X601366Y247196D01*
X601386Y247156D01*
X601486Y247016D01*
X601516Y246986D01*
Y243556D01*
X601526Y243431D01*
X601566Y243306D01*
X601626Y243196D01*
X601706Y243096D01*
X601806Y243016D01*
X601916Y242956D01*
X602041Y242916D01*
X602166Y242906D01*
X602291Y242916D01*
X602416Y242956D01*
X602526Y243016D01*
X602626Y243096D01*
X602706Y243196D01*
X602766Y243306D01*
X602806Y243431D01*
X602816Y243556D01*
Y246986D01*
X602846Y247016D01*
X602946Y247156D01*
X602966Y247196D01*
X602981Y247231D01*
X603001Y247271D01*
X603016Y247311D01*
X603026Y247351D01*
X603041Y247396D01*
X603046Y247436D01*
X603056Y247476D01*
X603061Y247521D01*
Y247561D01*
X603066Y247606D01*
X603061Y247651D01*
Y247691D01*
X603056Y247736D01*
X603046Y247776D01*
X603041Y247816D01*
X603026Y247861D01*
X603016Y247901D01*
X603001Y247941D01*
X602981Y247981D01*
X602966Y248016D01*
X602946Y248056D01*
X602846Y248196D01*
X602816Y248226D01*
Y249356D01*
X602806Y249481D01*
X602766Y249606D01*
X602706Y249716D01*
X602626Y249816D01*
X602526Y249896D01*
X602416Y249956D01*
X602291Y249996D01*
X602166Y250006D01*
G37*
G36*
G01X606890D02*
X606765Y249996D01*
X606640Y249956D01*
X606530Y249896D01*
X606430Y249816D01*
X606350Y249716D01*
X606290Y249606D01*
X606250Y249481D01*
X606240Y249356D01*
Y248226D01*
X606210Y248196D01*
X606110Y248056D01*
X606090Y248016D01*
X606075Y247981D01*
X606055Y247941D01*
X606040Y247901D01*
X606030Y247861D01*
X606015Y247816D01*
X606010Y247776D01*
X606000Y247736D01*
X605995Y247691D01*
Y247651D01*
X605990Y247606D01*
X605995Y247561D01*
Y247521D01*
X606000Y247476D01*
X606010Y247436D01*
X606015Y247396D01*
X606030Y247351D01*
X606040Y247311D01*
X606055Y247271D01*
X606075Y247231D01*
X606090Y247196D01*
X606110Y247156D01*
X606210Y247016D01*
X606240Y246986D01*
Y243556D01*
X606250Y243431D01*
X606290Y243306D01*
X606350Y243196D01*
X606430Y243096D01*
X606530Y243016D01*
X606640Y242956D01*
X606765Y242916D01*
X606890Y242906D01*
X607015Y242916D01*
X607140Y242956D01*
X607250Y243016D01*
X607350Y243096D01*
X607430Y243196D01*
X607490Y243306D01*
X607530Y243431D01*
X607540Y243556D01*
Y246986D01*
X607570Y247016D01*
X607670Y247156D01*
X607690Y247196D01*
X607705Y247231D01*
X607725Y247271D01*
X607740Y247311D01*
X607750Y247351D01*
X607765Y247396D01*
X607770Y247436D01*
X607780Y247476D01*
X607785Y247521D01*
Y247561D01*
X607790Y247606D01*
X607785Y247651D01*
Y247691D01*
X607780Y247736D01*
X607770Y247776D01*
X607765Y247816D01*
X607750Y247861D01*
X607740Y247901D01*
X607725Y247941D01*
X607705Y247981D01*
X607690Y248016D01*
X607670Y248056D01*
X607570Y248196D01*
X607540Y248226D01*
Y249356D01*
X607530Y249481D01*
X607490Y249606D01*
X607430Y249716D01*
X607350Y249816D01*
X607250Y249896D01*
X607140Y249956D01*
X607015Y249996D01*
X606890Y250006D01*
G37*
G36*
G01X611614D02*
X611489Y249996D01*
X611364Y249956D01*
X611254Y249896D01*
X611154Y249816D01*
X611074Y249716D01*
X611014Y249606D01*
X610974Y249481D01*
X610964Y249356D01*
Y248226D01*
X610934Y248196D01*
X610834Y248056D01*
X610814Y248016D01*
X610799Y247981D01*
X610779Y247941D01*
X610764Y247901D01*
X610754Y247861D01*
X610739Y247816D01*
X610734Y247776D01*
X610724Y247736D01*
X610719Y247691D01*
Y247651D01*
X610714Y247606D01*
X610719Y247561D01*
Y247521D01*
X610724Y247476D01*
X610734Y247436D01*
X610739Y247396D01*
X610754Y247351D01*
X610764Y247311D01*
X610779Y247271D01*
X610799Y247231D01*
X610814Y247196D01*
X610834Y247156D01*
X610934Y247016D01*
X610964Y246986D01*
Y243556D01*
X610974Y243431D01*
X611014Y243306D01*
X611074Y243196D01*
X611154Y243096D01*
X611254Y243016D01*
X611364Y242956D01*
X611489Y242916D01*
X611614Y242906D01*
X611739Y242916D01*
X611864Y242956D01*
X611974Y243016D01*
X612074Y243096D01*
X612154Y243196D01*
X612214Y243306D01*
X612254Y243431D01*
X612264Y243556D01*
Y246986D01*
X612294Y247016D01*
X612394Y247156D01*
X612414Y247196D01*
X612429Y247231D01*
X612449Y247271D01*
X612464Y247311D01*
X612474Y247351D01*
X612489Y247396D01*
X612494Y247436D01*
X612504Y247476D01*
X612509Y247521D01*
Y247561D01*
X612514Y247606D01*
X612509Y247651D01*
Y247691D01*
X612504Y247736D01*
X612494Y247776D01*
X612489Y247816D01*
X612474Y247861D01*
X612464Y247901D01*
X612449Y247941D01*
X612429Y247981D01*
X612414Y248016D01*
X612394Y248056D01*
X612294Y248196D01*
X612264Y248226D01*
Y249356D01*
X612254Y249481D01*
X612214Y249606D01*
X612154Y249716D01*
X612074Y249816D01*
X611974Y249896D01*
X611864Y249956D01*
X611739Y249996D01*
X611614Y250006D01*
G37*
G36*
G01X616339D02*
X616214Y249996D01*
X616089Y249956D01*
X615979Y249896D01*
X615879Y249816D01*
X615799Y249716D01*
X615739Y249606D01*
X615699Y249481D01*
X615689Y249356D01*
Y248226D01*
X615659Y248196D01*
X615559Y248056D01*
X615539Y248016D01*
X615524Y247981D01*
X615504Y247941D01*
X615489Y247901D01*
X615479Y247861D01*
X615464Y247816D01*
X615459Y247776D01*
X615449Y247736D01*
X615444Y247691D01*
Y247651D01*
X615439Y247606D01*
X615444Y247561D01*
Y247521D01*
X615449Y247476D01*
X615459Y247436D01*
X615464Y247396D01*
X615479Y247351D01*
X615489Y247311D01*
X615504Y247271D01*
X615524Y247231D01*
X615539Y247196D01*
X615559Y247156D01*
X615659Y247016D01*
X615689Y246986D01*
Y243556D01*
X615699Y243431D01*
X615739Y243306D01*
X615799Y243196D01*
X615879Y243096D01*
X615979Y243016D01*
X616089Y242956D01*
X616214Y242916D01*
X616339Y242906D01*
X616464Y242916D01*
X616589Y242956D01*
X616699Y243016D01*
X616799Y243096D01*
X616879Y243196D01*
X616939Y243306D01*
X616979Y243431D01*
X616989Y243556D01*
Y246986D01*
X617019Y247016D01*
X617119Y247156D01*
X617139Y247196D01*
X617154Y247231D01*
X617174Y247271D01*
X617189Y247311D01*
X617199Y247351D01*
X617214Y247396D01*
X617219Y247436D01*
X617229Y247476D01*
X617234Y247521D01*
Y247561D01*
X617239Y247606D01*
X617234Y247651D01*
Y247691D01*
X617229Y247736D01*
X617219Y247776D01*
X617214Y247816D01*
X617199Y247861D01*
X617189Y247901D01*
X617174Y247941D01*
X617154Y247981D01*
X617139Y248016D01*
X617119Y248056D01*
X617019Y248196D01*
X616989Y248226D01*
Y249356D01*
X616979Y249481D01*
X616939Y249606D01*
X616879Y249716D01*
X616799Y249816D01*
X616699Y249896D01*
X616589Y249956D01*
X616464Y249996D01*
X616339Y250006D01*
G37*
G36*
G01X621063D02*
X620938Y249996D01*
X620813Y249956D01*
X620703Y249896D01*
X620603Y249816D01*
X620523Y249716D01*
X620463Y249606D01*
X620423Y249481D01*
X620413Y249356D01*
Y248226D01*
X620383Y248196D01*
X620283Y248056D01*
X620263Y248016D01*
X620248Y247981D01*
X620228Y247941D01*
X620213Y247901D01*
X620203Y247861D01*
X620188Y247816D01*
X620183Y247776D01*
X620173Y247736D01*
X620168Y247691D01*
Y247651D01*
X620163Y247606D01*
X620168Y247561D01*
Y247521D01*
X620173Y247476D01*
X620183Y247436D01*
X620188Y247396D01*
X620203Y247351D01*
X620213Y247311D01*
X620228Y247271D01*
X620248Y247231D01*
X620263Y247196D01*
X620283Y247156D01*
X620383Y247016D01*
X620413Y246986D01*
Y243556D01*
X620423Y243431D01*
X620463Y243306D01*
X620523Y243196D01*
X620603Y243096D01*
X620703Y243016D01*
X620813Y242956D01*
X620938Y242916D01*
X621063Y242906D01*
X621188Y242916D01*
X621313Y242956D01*
X621423Y243016D01*
X621523Y243096D01*
X621603Y243196D01*
X621663Y243306D01*
X621703Y243431D01*
X621713Y243556D01*
Y246986D01*
X621743Y247016D01*
X621843Y247156D01*
X621863Y247196D01*
X621878Y247231D01*
X621898Y247271D01*
X621913Y247311D01*
X621923Y247351D01*
X621938Y247396D01*
X621943Y247436D01*
X621953Y247476D01*
X621958Y247521D01*
Y247561D01*
X621963Y247606D01*
X621958Y247651D01*
Y247691D01*
X621953Y247736D01*
X621943Y247776D01*
X621938Y247816D01*
X621923Y247861D01*
X621913Y247901D01*
X621898Y247941D01*
X621878Y247981D01*
X621863Y248016D01*
X621843Y248056D01*
X621743Y248196D01*
X621713Y248226D01*
Y249356D01*
X621703Y249481D01*
X621663Y249606D01*
X621603Y249716D01*
X621523Y249816D01*
X621423Y249896D01*
X621313Y249956D01*
X621188Y249996D01*
X621063Y250006D01*
G37*
G36*
G01X625788D02*
X625663Y249996D01*
X625538Y249956D01*
X625428Y249896D01*
X625328Y249816D01*
X625248Y249716D01*
X625188Y249606D01*
X625148Y249481D01*
X625138Y249356D01*
Y248226D01*
X625108Y248196D01*
X625008Y248056D01*
X624988Y248016D01*
X624973Y247981D01*
X624953Y247941D01*
X624938Y247901D01*
X624928Y247861D01*
X624913Y247816D01*
X624908Y247776D01*
X624898Y247736D01*
X624893Y247691D01*
Y247651D01*
X624888Y247606D01*
X624893Y247561D01*
Y247521D01*
X624898Y247476D01*
X624908Y247436D01*
X624913Y247396D01*
X624928Y247351D01*
X624938Y247311D01*
X624953Y247271D01*
X624973Y247231D01*
X624988Y247196D01*
X625008Y247156D01*
X625108Y247016D01*
X625138Y246986D01*
Y243556D01*
X625148Y243431D01*
X625188Y243306D01*
X625248Y243196D01*
X625328Y243096D01*
X625428Y243016D01*
X625538Y242956D01*
X625663Y242916D01*
X625788Y242906D01*
X625913Y242916D01*
X626038Y242956D01*
X626148Y243016D01*
X626248Y243096D01*
X626328Y243196D01*
X626388Y243306D01*
X626428Y243431D01*
X626438Y243556D01*
Y246986D01*
X626468Y247016D01*
X626568Y247156D01*
X626588Y247196D01*
X626603Y247231D01*
X626623Y247271D01*
X626638Y247311D01*
X626648Y247351D01*
X626663Y247396D01*
X626668Y247436D01*
X626678Y247476D01*
X626683Y247521D01*
Y247561D01*
X626688Y247606D01*
X626683Y247651D01*
Y247691D01*
X626678Y247736D01*
X626668Y247776D01*
X626663Y247816D01*
X626648Y247861D01*
X626638Y247901D01*
X626623Y247941D01*
X626603Y247981D01*
X626588Y248016D01*
X626568Y248056D01*
X626468Y248196D01*
X626438Y248226D01*
Y249356D01*
X626428Y249481D01*
X626388Y249606D01*
X626328Y249716D01*
X626248Y249816D01*
X626148Y249896D01*
X626038Y249956D01*
X625913Y249996D01*
X625788Y250006D01*
G37*
G36*
G01X630512D02*
X630387Y249996D01*
X630262Y249956D01*
X630152Y249896D01*
X630052Y249816D01*
X629972Y249716D01*
X629912Y249606D01*
X629872Y249481D01*
X629862Y249356D01*
Y248226D01*
X629832Y248196D01*
X629732Y248056D01*
X629712Y248016D01*
X629697Y247981D01*
X629677Y247941D01*
X629662Y247901D01*
X629652Y247861D01*
X629637Y247816D01*
X629632Y247776D01*
X629622Y247736D01*
X629617Y247691D01*
Y247651D01*
X629612Y247606D01*
X629617Y247561D01*
Y247521D01*
X629622Y247476D01*
X629632Y247436D01*
X629637Y247396D01*
X629652Y247351D01*
X629662Y247311D01*
X629677Y247271D01*
X629697Y247231D01*
X629712Y247196D01*
X629732Y247156D01*
X629832Y247016D01*
X629862Y246986D01*
Y243556D01*
X629872Y243431D01*
X629912Y243306D01*
X629972Y243196D01*
X630052Y243096D01*
X630152Y243016D01*
X630262Y242956D01*
X630387Y242916D01*
X630512Y242906D01*
X630637Y242916D01*
X630762Y242956D01*
X630872Y243016D01*
X630972Y243096D01*
X631052Y243196D01*
X631112Y243306D01*
X631152Y243431D01*
X631162Y243556D01*
Y246986D01*
X631192Y247016D01*
X631292Y247156D01*
X631312Y247196D01*
X631327Y247231D01*
X631347Y247271D01*
X631362Y247311D01*
X631372Y247351D01*
X631387Y247396D01*
X631392Y247436D01*
X631402Y247476D01*
X631407Y247521D01*
Y247561D01*
X631412Y247606D01*
X631407Y247651D01*
Y247691D01*
X631402Y247736D01*
X631392Y247776D01*
X631387Y247816D01*
X631372Y247861D01*
X631362Y247901D01*
X631347Y247941D01*
X631327Y247981D01*
X631312Y248016D01*
X631292Y248056D01*
X631192Y248196D01*
X631162Y248226D01*
Y249356D01*
X631152Y249481D01*
X631112Y249606D01*
X631052Y249716D01*
X630972Y249816D01*
X630872Y249896D01*
X630762Y249956D01*
X630637Y249996D01*
X630512Y250006D01*
G37*
G36*
G01X635236D02*
X635111Y249996D01*
X634986Y249956D01*
X634876Y249896D01*
X634776Y249816D01*
X634696Y249716D01*
X634636Y249606D01*
X634596Y249481D01*
X634586Y249356D01*
Y248226D01*
X634556Y248196D01*
X634456Y248056D01*
X634436Y248016D01*
X634421Y247981D01*
X634401Y247941D01*
X634386Y247901D01*
X634376Y247861D01*
X634361Y247816D01*
X634356Y247776D01*
X634346Y247736D01*
X634341Y247691D01*
Y247651D01*
X634336Y247606D01*
X634341Y247561D01*
Y247521D01*
X634346Y247476D01*
X634356Y247436D01*
X634361Y247396D01*
X634376Y247351D01*
X634386Y247311D01*
X634401Y247271D01*
X634421Y247231D01*
X634436Y247196D01*
X634456Y247156D01*
X634556Y247016D01*
X634586Y246986D01*
Y243556D01*
X634596Y243431D01*
X634636Y243306D01*
X634696Y243196D01*
X634776Y243096D01*
X634876Y243016D01*
X634986Y242956D01*
X635111Y242916D01*
X635236Y242906D01*
X635361Y242916D01*
X635486Y242956D01*
X635596Y243016D01*
X635696Y243096D01*
X635776Y243196D01*
X635836Y243306D01*
X635876Y243431D01*
X635886Y243556D01*
Y246986D01*
X635916Y247016D01*
X636016Y247156D01*
X636036Y247196D01*
X636051Y247231D01*
X636071Y247271D01*
X636086Y247311D01*
X636096Y247351D01*
X636111Y247396D01*
X636116Y247436D01*
X636126Y247476D01*
X636131Y247521D01*
Y247561D01*
X636136Y247606D01*
X636131Y247651D01*
Y247691D01*
X636126Y247736D01*
X636116Y247776D01*
X636111Y247816D01*
X636096Y247861D01*
X636086Y247901D01*
X636071Y247941D01*
X636051Y247981D01*
X636036Y248016D01*
X636016Y248056D01*
X635916Y248196D01*
X635886Y248226D01*
Y249356D01*
X635876Y249481D01*
X635836Y249606D01*
X635776Y249716D01*
X635696Y249816D01*
X635596Y249896D01*
X635486Y249956D01*
X635361Y249996D01*
X635236Y250006D01*
G37*
G36*
G01X639961D02*
X639836Y249996D01*
X639711Y249956D01*
X639601Y249896D01*
X639501Y249816D01*
X639421Y249716D01*
X639361Y249606D01*
X639321Y249481D01*
X639311Y249356D01*
Y248226D01*
X639281Y248196D01*
X639181Y248056D01*
X639161Y248016D01*
X639146Y247981D01*
X639126Y247941D01*
X639111Y247901D01*
X639101Y247861D01*
X639086Y247816D01*
X639081Y247776D01*
X639071Y247736D01*
X639066Y247691D01*
Y247651D01*
X639061Y247606D01*
X639066Y247561D01*
Y247521D01*
X639071Y247476D01*
X639081Y247436D01*
X639086Y247396D01*
X639101Y247351D01*
X639111Y247311D01*
X639126Y247271D01*
X639146Y247231D01*
X639161Y247196D01*
X639181Y247156D01*
X639281Y247016D01*
X639311Y246986D01*
Y243556D01*
X639321Y243431D01*
X639361Y243306D01*
X639421Y243196D01*
X639501Y243096D01*
X639601Y243016D01*
X639711Y242956D01*
X639836Y242916D01*
X639961Y242906D01*
X640086Y242916D01*
X640211Y242956D01*
X640321Y243016D01*
X640421Y243096D01*
X640501Y243196D01*
X640561Y243306D01*
X640601Y243431D01*
X640611Y243556D01*
Y246986D01*
X640641Y247016D01*
X640741Y247156D01*
X640761Y247196D01*
X640776Y247231D01*
X640796Y247271D01*
X640811Y247311D01*
X640821Y247351D01*
X640836Y247396D01*
X640841Y247436D01*
X640851Y247476D01*
X640856Y247521D01*
Y247561D01*
X640861Y247606D01*
X640856Y247651D01*
Y247691D01*
X640851Y247736D01*
X640841Y247776D01*
X640836Y247816D01*
X640821Y247861D01*
X640811Y247901D01*
X640796Y247941D01*
X640776Y247981D01*
X640761Y248016D01*
X640741Y248056D01*
X640641Y248196D01*
X640611Y248226D01*
Y249356D01*
X640601Y249481D01*
X640561Y249606D01*
X640501Y249716D01*
X640421Y249816D01*
X640321Y249896D01*
X640211Y249956D01*
X640086Y249996D01*
X639961Y250006D01*
G37*
G36*
G01X644685D02*
X644560Y249996D01*
X644435Y249956D01*
X644325Y249896D01*
X644225Y249816D01*
X644145Y249716D01*
X644085Y249606D01*
X644045Y249481D01*
X644035Y249356D01*
Y248226D01*
X644005Y248196D01*
X643905Y248056D01*
X643885Y248016D01*
X643870Y247981D01*
X643850Y247941D01*
X643835Y247901D01*
X643825Y247861D01*
X643810Y247816D01*
X643805Y247776D01*
X643795Y247736D01*
X643790Y247691D01*
Y247651D01*
X643785Y247606D01*
X643790Y247561D01*
Y247521D01*
X643795Y247476D01*
X643805Y247436D01*
X643810Y247396D01*
X643825Y247351D01*
X643835Y247311D01*
X643850Y247271D01*
X643870Y247231D01*
X643885Y247196D01*
X643905Y247156D01*
X644005Y247016D01*
X644035Y246986D01*
Y243556D01*
X644045Y243431D01*
X644085Y243306D01*
X644145Y243196D01*
X644225Y243096D01*
X644325Y243016D01*
X644435Y242956D01*
X644560Y242916D01*
X644685Y242906D01*
X644810Y242916D01*
X644935Y242956D01*
X645045Y243016D01*
X645145Y243096D01*
X645225Y243196D01*
X645285Y243306D01*
X645325Y243431D01*
X645335Y243556D01*
Y246986D01*
X645365Y247016D01*
X645465Y247156D01*
X645485Y247196D01*
X645500Y247231D01*
X645520Y247271D01*
X645535Y247311D01*
X645545Y247351D01*
X645560Y247396D01*
X645565Y247436D01*
X645575Y247476D01*
X645580Y247521D01*
Y247561D01*
X645585Y247606D01*
X645580Y247651D01*
Y247691D01*
X645575Y247736D01*
X645565Y247776D01*
X645560Y247816D01*
X645545Y247861D01*
X645535Y247901D01*
X645520Y247941D01*
X645500Y247981D01*
X645485Y248016D01*
X645465Y248056D01*
X645365Y248196D01*
X645335Y248226D01*
Y249356D01*
X645325Y249481D01*
X645285Y249606D01*
X645225Y249716D01*
X645145Y249816D01*
X645045Y249896D01*
X644935Y249956D01*
X644810Y249996D01*
X644685Y250006D01*
G37*
G36*
G01X649410D02*
X649285Y249996D01*
X649160Y249956D01*
X649050Y249896D01*
X648950Y249816D01*
X648870Y249716D01*
X648810Y249606D01*
X648770Y249481D01*
X648760Y249356D01*
Y248226D01*
X648730Y248196D01*
X648630Y248056D01*
X648610Y248016D01*
X648595Y247981D01*
X648575Y247941D01*
X648560Y247901D01*
X648550Y247861D01*
X648535Y247816D01*
X648530Y247776D01*
X648520Y247736D01*
X648515Y247691D01*
Y247651D01*
X648510Y247606D01*
X648515Y247561D01*
Y247521D01*
X648520Y247476D01*
X648530Y247436D01*
X648535Y247396D01*
X648550Y247351D01*
X648560Y247311D01*
X648575Y247271D01*
X648595Y247231D01*
X648610Y247196D01*
X648630Y247156D01*
X648730Y247016D01*
X648760Y246986D01*
Y243556D01*
X648770Y243431D01*
X648810Y243306D01*
X648870Y243196D01*
X648950Y243096D01*
X649050Y243016D01*
X649160Y242956D01*
X649285Y242916D01*
X649410Y242906D01*
X649535Y242916D01*
X649660Y242956D01*
X649770Y243016D01*
X649870Y243096D01*
X649950Y243196D01*
X650010Y243306D01*
X650050Y243431D01*
X650060Y243556D01*
Y246986D01*
X650090Y247016D01*
X650190Y247156D01*
X650210Y247196D01*
X650225Y247231D01*
X650245Y247271D01*
X650260Y247311D01*
X650270Y247351D01*
X650285Y247396D01*
X650290Y247436D01*
X650300Y247476D01*
X650305Y247521D01*
Y247561D01*
X650310Y247606D01*
X650305Y247651D01*
Y247691D01*
X650300Y247736D01*
X650290Y247776D01*
X650285Y247816D01*
X650270Y247861D01*
X650260Y247901D01*
X650245Y247941D01*
X650225Y247981D01*
X650210Y248016D01*
X650190Y248056D01*
X650090Y248196D01*
X650060Y248226D01*
Y249356D01*
X650050Y249481D01*
X650010Y249606D01*
X649950Y249716D01*
X649870Y249816D01*
X649770Y249896D01*
X649660Y249956D01*
X649535Y249996D01*
X649410Y250006D01*
G37*
G36*
G01X654134D02*
X654009Y249996D01*
X653884Y249956D01*
X653774Y249896D01*
X653674Y249816D01*
X653594Y249716D01*
X653534Y249606D01*
X653494Y249481D01*
X653484Y249356D01*
Y248226D01*
X653454Y248196D01*
X653354Y248056D01*
X653334Y248016D01*
X653319Y247981D01*
X653299Y247941D01*
X653284Y247901D01*
X653274Y247861D01*
X653259Y247816D01*
X653254Y247776D01*
X653244Y247736D01*
X653239Y247691D01*
Y247651D01*
X653234Y247606D01*
X653239Y247561D01*
Y247521D01*
X653244Y247476D01*
X653254Y247436D01*
X653259Y247396D01*
X653274Y247351D01*
X653284Y247311D01*
X653299Y247271D01*
X653319Y247231D01*
X653334Y247196D01*
X653354Y247156D01*
X653454Y247016D01*
X653484Y246986D01*
Y243556D01*
X653494Y243431D01*
X653534Y243306D01*
X653594Y243196D01*
X653674Y243096D01*
X653774Y243016D01*
X653884Y242956D01*
X654009Y242916D01*
X654134Y242906D01*
X654259Y242916D01*
X654384Y242956D01*
X654494Y243016D01*
X654594Y243096D01*
X654674Y243196D01*
X654734Y243306D01*
X654774Y243431D01*
X654784Y243556D01*
Y246986D01*
X654814Y247016D01*
X654914Y247156D01*
X654934Y247196D01*
X654949Y247231D01*
X654969Y247271D01*
X654984Y247311D01*
X654994Y247351D01*
X655009Y247396D01*
X655014Y247436D01*
X655024Y247476D01*
X655029Y247521D01*
Y247561D01*
X655034Y247606D01*
X655029Y247651D01*
Y247691D01*
X655024Y247736D01*
X655014Y247776D01*
X655009Y247816D01*
X654994Y247861D01*
X654984Y247901D01*
X654969Y247941D01*
X654949Y247981D01*
X654934Y248016D01*
X654914Y248056D01*
X654814Y248196D01*
X654784Y248226D01*
Y249356D01*
X654774Y249481D01*
X654734Y249606D01*
X654674Y249716D01*
X654594Y249816D01*
X654494Y249896D01*
X654384Y249956D01*
X654259Y249996D01*
X654134Y250006D01*
G37*
G36*
G01X668307D02*
X668182Y249996D01*
X668057Y249956D01*
X667947Y249896D01*
X667847Y249816D01*
X667767Y249716D01*
X667707Y249606D01*
X667667Y249481D01*
X667657Y249356D01*
Y248226D01*
X667627Y248196D01*
X667527Y248056D01*
X667507Y248016D01*
X667492Y247981D01*
X667472Y247941D01*
X667457Y247901D01*
X667447Y247861D01*
X667432Y247816D01*
X667427Y247776D01*
X667417Y247736D01*
X667412Y247691D01*
Y247651D01*
X667407Y247606D01*
X667412Y247561D01*
Y247521D01*
X667417Y247476D01*
X667427Y247436D01*
X667432Y247396D01*
X667447Y247351D01*
X667457Y247311D01*
X667472Y247271D01*
X667492Y247231D01*
X667507Y247196D01*
X667527Y247156D01*
X667627Y247016D01*
X667657Y246986D01*
Y243556D01*
X667667Y243431D01*
X667707Y243306D01*
X667767Y243196D01*
X667847Y243096D01*
X667947Y243016D01*
X668057Y242956D01*
X668182Y242916D01*
X668307Y242906D01*
X668432Y242916D01*
X668557Y242956D01*
X668667Y243016D01*
X668767Y243096D01*
X668847Y243196D01*
X668907Y243306D01*
X668947Y243431D01*
X668957Y243556D01*
Y246986D01*
X668987Y247016D01*
X669087Y247156D01*
X669107Y247196D01*
X669122Y247231D01*
X669142Y247271D01*
X669157Y247311D01*
X669167Y247351D01*
X669182Y247396D01*
X669187Y247436D01*
X669197Y247476D01*
X669202Y247521D01*
Y247561D01*
X669207Y247606D01*
X669202Y247651D01*
Y247691D01*
X669197Y247736D01*
X669187Y247776D01*
X669182Y247816D01*
X669167Y247861D01*
X669157Y247901D01*
X669142Y247941D01*
X669122Y247981D01*
X669107Y248016D01*
X669087Y248056D01*
X668987Y248196D01*
X668957Y248226D01*
Y249356D01*
X668947Y249481D01*
X668907Y249606D01*
X668847Y249716D01*
X668767Y249816D01*
X668667Y249896D01*
X668557Y249956D01*
X668432Y249996D01*
X668307Y250006D01*
G37*
G36*
G01X673032D02*
X672907Y249996D01*
X672782Y249956D01*
X672672Y249896D01*
X672572Y249816D01*
X672492Y249716D01*
X672432Y249606D01*
X672392Y249481D01*
X672382Y249356D01*
Y248226D01*
X672352Y248196D01*
X672252Y248056D01*
X672232Y248016D01*
X672217Y247981D01*
X672197Y247941D01*
X672182Y247901D01*
X672172Y247861D01*
X672157Y247816D01*
X672152Y247776D01*
X672142Y247736D01*
X672137Y247691D01*
Y247651D01*
X672132Y247606D01*
X672137Y247561D01*
Y247521D01*
X672142Y247476D01*
X672152Y247436D01*
X672157Y247396D01*
X672172Y247351D01*
X672182Y247311D01*
X672197Y247271D01*
X672217Y247231D01*
X672232Y247196D01*
X672252Y247156D01*
X672352Y247016D01*
X672382Y246986D01*
Y243556D01*
X672392Y243431D01*
X672432Y243306D01*
X672492Y243196D01*
X672572Y243096D01*
X672672Y243016D01*
X672782Y242956D01*
X672907Y242916D01*
X673032Y242906D01*
X673157Y242916D01*
X673282Y242956D01*
X673392Y243016D01*
X673492Y243096D01*
X673572Y243196D01*
X673632Y243306D01*
X673672Y243431D01*
X673682Y243556D01*
Y246986D01*
X673712Y247016D01*
X673812Y247156D01*
X673832Y247196D01*
X673847Y247231D01*
X673867Y247271D01*
X673882Y247311D01*
X673892Y247351D01*
X673907Y247396D01*
X673912Y247436D01*
X673922Y247476D01*
X673927Y247521D01*
Y247561D01*
X673932Y247606D01*
X673927Y247651D01*
Y247691D01*
X673922Y247736D01*
X673912Y247776D01*
X673907Y247816D01*
X673892Y247861D01*
X673882Y247901D01*
X673867Y247941D01*
X673847Y247981D01*
X673832Y248016D01*
X673812Y248056D01*
X673712Y248196D01*
X673682Y248226D01*
Y249356D01*
X673672Y249481D01*
X673632Y249606D01*
X673572Y249716D01*
X673492Y249816D01*
X673392Y249896D01*
X673282Y249956D01*
X673157Y249996D01*
X673032Y250006D01*
G37*
G36*
G01X677756D02*
X677631Y249996D01*
X677506Y249956D01*
X677396Y249896D01*
X677296Y249816D01*
X677216Y249716D01*
X677156Y249606D01*
X677116Y249481D01*
X677106Y249356D01*
Y248226D01*
X677076Y248196D01*
X676976Y248056D01*
X676956Y248016D01*
X676941Y247981D01*
X676921Y247941D01*
X676906Y247901D01*
X676896Y247861D01*
X676881Y247816D01*
X676876Y247776D01*
X676866Y247736D01*
X676861Y247691D01*
Y247651D01*
X676856Y247606D01*
X676861Y247561D01*
Y247521D01*
X676866Y247476D01*
X676876Y247436D01*
X676881Y247396D01*
X676896Y247351D01*
X676906Y247311D01*
X676921Y247271D01*
X676941Y247231D01*
X676956Y247196D01*
X676976Y247156D01*
X677076Y247016D01*
X677106Y246986D01*
Y243556D01*
X677116Y243431D01*
X677156Y243306D01*
X677216Y243196D01*
X677296Y243096D01*
X677396Y243016D01*
X677506Y242956D01*
X677631Y242916D01*
X677756Y242906D01*
X677881Y242916D01*
X678006Y242956D01*
X678116Y243016D01*
X678216Y243096D01*
X678296Y243196D01*
X678356Y243306D01*
X678396Y243431D01*
X678406Y243556D01*
Y246986D01*
X678436Y247016D01*
X678536Y247156D01*
X678556Y247196D01*
X678571Y247231D01*
X678591Y247271D01*
X678606Y247311D01*
X678616Y247351D01*
X678631Y247396D01*
X678636Y247436D01*
X678646Y247476D01*
X678651Y247521D01*
Y247561D01*
X678656Y247606D01*
X678651Y247651D01*
Y247691D01*
X678646Y247736D01*
X678636Y247776D01*
X678631Y247816D01*
X678616Y247861D01*
X678606Y247901D01*
X678591Y247941D01*
X678571Y247981D01*
X678556Y248016D01*
X678536Y248056D01*
X678436Y248196D01*
X678406Y248226D01*
Y249356D01*
X678396Y249481D01*
X678356Y249606D01*
X678296Y249716D01*
X678216Y249816D01*
X678116Y249896D01*
X678006Y249956D01*
X677881Y249996D01*
X677756Y250006D01*
G37*
G36*
G01X682481D02*
X682356Y249996D01*
X682231Y249956D01*
X682121Y249896D01*
X682021Y249816D01*
X681941Y249716D01*
X681881Y249606D01*
X681841Y249481D01*
X681831Y249356D01*
Y248226D01*
X681801Y248196D01*
X681701Y248056D01*
X681681Y248016D01*
X681666Y247981D01*
X681646Y247941D01*
X681631Y247901D01*
X681621Y247861D01*
X681606Y247816D01*
X681601Y247776D01*
X681591Y247736D01*
X681586Y247691D01*
Y247651D01*
X681581Y247606D01*
X681586Y247561D01*
Y247521D01*
X681591Y247476D01*
X681601Y247436D01*
X681606Y247396D01*
X681621Y247351D01*
X681631Y247311D01*
X681646Y247271D01*
X681666Y247231D01*
X681681Y247196D01*
X681701Y247156D01*
X681801Y247016D01*
X681831Y246986D01*
Y243556D01*
X681841Y243431D01*
X681881Y243306D01*
X681941Y243196D01*
X682021Y243096D01*
X682121Y243016D01*
X682231Y242956D01*
X682356Y242916D01*
X682481Y242906D01*
X682606Y242916D01*
X682731Y242956D01*
X682841Y243016D01*
X682941Y243096D01*
X683021Y243196D01*
X683081Y243306D01*
X683121Y243431D01*
X683131Y243556D01*
Y246986D01*
X683161Y247016D01*
X683261Y247156D01*
X683281Y247196D01*
X683296Y247231D01*
X683316Y247271D01*
X683331Y247311D01*
X683341Y247351D01*
X683356Y247396D01*
X683361Y247436D01*
X683371Y247476D01*
X683376Y247521D01*
Y247561D01*
X683381Y247606D01*
X683376Y247651D01*
Y247691D01*
X683371Y247736D01*
X683361Y247776D01*
X683356Y247816D01*
X683341Y247861D01*
X683331Y247901D01*
X683316Y247941D01*
X683296Y247981D01*
X683281Y248016D01*
X683261Y248056D01*
X683161Y248196D01*
X683131Y248226D01*
Y249356D01*
X683121Y249481D01*
X683081Y249606D01*
X683021Y249716D01*
X682941Y249816D01*
X682841Y249896D01*
X682731Y249956D01*
X682606Y249996D01*
X682481Y250006D01*
G37*
G36*
G01X687205D02*
X687080Y249996D01*
X686955Y249956D01*
X686845Y249896D01*
X686745Y249816D01*
X686665Y249716D01*
X686605Y249606D01*
X686565Y249481D01*
X686555Y249356D01*
Y248226D01*
X686525Y248196D01*
X686425Y248056D01*
X686405Y248016D01*
X686390Y247981D01*
X686370Y247941D01*
X686355Y247901D01*
X686345Y247861D01*
X686330Y247816D01*
X686325Y247776D01*
X686315Y247736D01*
X686310Y247691D01*
Y247651D01*
X686305Y247606D01*
X686310Y247561D01*
Y247521D01*
X686315Y247476D01*
X686325Y247436D01*
X686330Y247396D01*
X686345Y247351D01*
X686355Y247311D01*
X686370Y247271D01*
X686390Y247231D01*
X686405Y247196D01*
X686425Y247156D01*
X686525Y247016D01*
X686555Y246986D01*
Y243556D01*
X686565Y243431D01*
X686605Y243306D01*
X686665Y243196D01*
X686745Y243096D01*
X686845Y243016D01*
X686955Y242956D01*
X687080Y242916D01*
X687205Y242906D01*
X687330Y242916D01*
X687455Y242956D01*
X687565Y243016D01*
X687665Y243096D01*
X687745Y243196D01*
X687805Y243306D01*
X687845Y243431D01*
X687855Y243556D01*
Y246986D01*
X687885Y247016D01*
X687985Y247156D01*
X688005Y247196D01*
X688020Y247231D01*
X688040Y247271D01*
X688055Y247311D01*
X688065Y247351D01*
X688080Y247396D01*
X688085Y247436D01*
X688095Y247476D01*
X688100Y247521D01*
Y247561D01*
X688105Y247606D01*
X688100Y247651D01*
Y247691D01*
X688095Y247736D01*
X688085Y247776D01*
X688080Y247816D01*
X688065Y247861D01*
X688055Y247901D01*
X688040Y247941D01*
X688020Y247981D01*
X688005Y248016D01*
X687985Y248056D01*
X687885Y248196D01*
X687855Y248226D01*
Y249356D01*
X687845Y249481D01*
X687805Y249606D01*
X687745Y249716D01*
X687665Y249816D01*
X687565Y249896D01*
X687455Y249956D01*
X687330Y249996D01*
X687205Y250006D01*
G37*
G36*
G01X691929D02*
X691804Y249996D01*
X691679Y249956D01*
X691569Y249896D01*
X691469Y249816D01*
X691389Y249716D01*
X691329Y249606D01*
X691289Y249481D01*
X691279Y249356D01*
Y248226D01*
X691249Y248196D01*
X691149Y248056D01*
X691129Y248016D01*
X691114Y247981D01*
X691094Y247941D01*
X691079Y247901D01*
X691069Y247861D01*
X691054Y247816D01*
X691049Y247776D01*
X691039Y247736D01*
X691034Y247691D01*
Y247651D01*
X691029Y247606D01*
X691034Y247561D01*
Y247521D01*
X691039Y247476D01*
X691049Y247436D01*
X691054Y247396D01*
X691069Y247351D01*
X691079Y247311D01*
X691094Y247271D01*
X691114Y247231D01*
X691129Y247196D01*
X691149Y247156D01*
X691249Y247016D01*
X691279Y246986D01*
Y243556D01*
X691289Y243431D01*
X691329Y243306D01*
X691389Y243196D01*
X691469Y243096D01*
X691569Y243016D01*
X691679Y242956D01*
X691804Y242916D01*
X691929Y242906D01*
X692054Y242916D01*
X692179Y242956D01*
X692289Y243016D01*
X692389Y243096D01*
X692469Y243196D01*
X692529Y243306D01*
X692569Y243431D01*
X692579Y243556D01*
Y246986D01*
X692609Y247016D01*
X692709Y247156D01*
X692729Y247196D01*
X692744Y247231D01*
X692764Y247271D01*
X692779Y247311D01*
X692789Y247351D01*
X692804Y247396D01*
X692809Y247436D01*
X692819Y247476D01*
X692824Y247521D01*
Y247561D01*
X692829Y247606D01*
X692824Y247651D01*
Y247691D01*
X692819Y247736D01*
X692809Y247776D01*
X692804Y247816D01*
X692789Y247861D01*
X692779Y247901D01*
X692764Y247941D01*
X692744Y247981D01*
X692729Y248016D01*
X692709Y248056D01*
X692609Y248196D01*
X692579Y248226D01*
Y249356D01*
X692569Y249481D01*
X692529Y249606D01*
X692469Y249716D01*
X692389Y249816D01*
X692289Y249896D01*
X692179Y249956D01*
X692054Y249996D01*
X691929Y250006D01*
G37*
G36*
G01X696654D02*
X696529Y249996D01*
X696404Y249956D01*
X696294Y249896D01*
X696194Y249816D01*
X696114Y249716D01*
X696054Y249606D01*
X696014Y249481D01*
X696004Y249356D01*
Y248226D01*
X695974Y248196D01*
X695874Y248056D01*
X695854Y248016D01*
X695839Y247981D01*
X695819Y247941D01*
X695804Y247901D01*
X695794Y247861D01*
X695779Y247816D01*
X695774Y247776D01*
X695764Y247736D01*
X695759Y247691D01*
Y247651D01*
X695754Y247606D01*
X695759Y247561D01*
Y247521D01*
X695764Y247476D01*
X695774Y247436D01*
X695779Y247396D01*
X695794Y247351D01*
X695804Y247311D01*
X695819Y247271D01*
X695839Y247231D01*
X695854Y247196D01*
X695874Y247156D01*
X695974Y247016D01*
X696004Y246986D01*
Y243556D01*
X696014Y243431D01*
X696054Y243306D01*
X696114Y243196D01*
X696194Y243096D01*
X696294Y243016D01*
X696404Y242956D01*
X696529Y242916D01*
X696654Y242906D01*
X696779Y242916D01*
X696904Y242956D01*
X697014Y243016D01*
X697114Y243096D01*
X697194Y243196D01*
X697254Y243306D01*
X697294Y243431D01*
X697304Y243556D01*
Y246986D01*
X697334Y247016D01*
X697434Y247156D01*
X697454Y247196D01*
X697469Y247231D01*
X697489Y247271D01*
X697504Y247311D01*
X697514Y247351D01*
X697529Y247396D01*
X697534Y247436D01*
X697544Y247476D01*
X697549Y247521D01*
Y247561D01*
X697554Y247606D01*
X697549Y247651D01*
Y247691D01*
X697544Y247736D01*
X697534Y247776D01*
X697529Y247816D01*
X697514Y247861D01*
X697504Y247901D01*
X697489Y247941D01*
X697469Y247981D01*
X697454Y248016D01*
X697434Y248056D01*
X697334Y248196D01*
X697304Y248226D01*
Y249356D01*
X697294Y249481D01*
X697254Y249606D01*
X697194Y249716D01*
X697114Y249816D01*
X697014Y249896D01*
X696904Y249956D01*
X696779Y249996D01*
X696654Y250006D01*
G37*
G36*
G01X701378D02*
X701253Y249996D01*
X701128Y249956D01*
X701018Y249896D01*
X700918Y249816D01*
X700838Y249716D01*
X700778Y249606D01*
X700738Y249481D01*
X700728Y249356D01*
Y248226D01*
X700698Y248196D01*
X700598Y248056D01*
X700578Y248016D01*
X700563Y247981D01*
X700543Y247941D01*
X700528Y247901D01*
X700518Y247861D01*
X700503Y247816D01*
X700498Y247776D01*
X700488Y247736D01*
X700483Y247691D01*
Y247651D01*
X700478Y247606D01*
X700483Y247561D01*
Y247521D01*
X700488Y247476D01*
X700498Y247436D01*
X700503Y247396D01*
X700518Y247351D01*
X700528Y247311D01*
X700543Y247271D01*
X700563Y247231D01*
X700578Y247196D01*
X700598Y247156D01*
X700698Y247016D01*
X700728Y246986D01*
Y243556D01*
X700738Y243431D01*
X700778Y243306D01*
X700838Y243196D01*
X700918Y243096D01*
X701018Y243016D01*
X701128Y242956D01*
X701253Y242916D01*
X701378Y242906D01*
X701503Y242916D01*
X701628Y242956D01*
X701738Y243016D01*
X701838Y243096D01*
X701918Y243196D01*
X701978Y243306D01*
X702018Y243431D01*
X702028Y243556D01*
Y246986D01*
X702058Y247016D01*
X702158Y247156D01*
X702178Y247196D01*
X702193Y247231D01*
X702213Y247271D01*
X702228Y247311D01*
X702238Y247351D01*
X702253Y247396D01*
X702258Y247436D01*
X702268Y247476D01*
X702273Y247521D01*
Y247561D01*
X702278Y247606D01*
X702273Y247651D01*
Y247691D01*
X702268Y247736D01*
X702258Y247776D01*
X702253Y247816D01*
X702238Y247861D01*
X702228Y247901D01*
X702213Y247941D01*
X702193Y247981D01*
X702178Y248016D01*
X702158Y248056D01*
X702058Y248196D01*
X702028Y248226D01*
Y249356D01*
X702018Y249481D01*
X701978Y249606D01*
X701918Y249716D01*
X701838Y249816D01*
X701738Y249896D01*
X701628Y249956D01*
X701503Y249996D01*
X701378Y250006D01*
G37*
G36*
G01X706103D02*
X705978Y249996D01*
X705853Y249956D01*
X705743Y249896D01*
X705643Y249816D01*
X705563Y249716D01*
X705503Y249606D01*
X705463Y249481D01*
X705453Y249356D01*
Y248226D01*
X705423Y248196D01*
X705323Y248056D01*
X705303Y248016D01*
X705288Y247981D01*
X705268Y247941D01*
X705253Y247901D01*
X705243Y247861D01*
X705228Y247816D01*
X705223Y247776D01*
X705213Y247736D01*
X705208Y247691D01*
Y247651D01*
X705203Y247606D01*
X705208Y247561D01*
Y247521D01*
X705213Y247476D01*
X705223Y247436D01*
X705228Y247396D01*
X705243Y247351D01*
X705253Y247311D01*
X705268Y247271D01*
X705288Y247231D01*
X705303Y247196D01*
X705323Y247156D01*
X705423Y247016D01*
X705453Y246986D01*
Y243556D01*
X705463Y243431D01*
X705503Y243306D01*
X705563Y243196D01*
X705643Y243096D01*
X705743Y243016D01*
X705853Y242956D01*
X705978Y242916D01*
X706103Y242906D01*
X706228Y242916D01*
X706353Y242956D01*
X706463Y243016D01*
X706563Y243096D01*
X706643Y243196D01*
X706703Y243306D01*
X706743Y243431D01*
X706753Y243556D01*
Y246986D01*
X706783Y247016D01*
X706883Y247156D01*
X706903Y247196D01*
X706918Y247231D01*
X706938Y247271D01*
X706953Y247311D01*
X706963Y247351D01*
X706978Y247396D01*
X706983Y247436D01*
X706993Y247476D01*
X706998Y247521D01*
Y247561D01*
X707003Y247606D01*
X706998Y247651D01*
Y247691D01*
X706993Y247736D01*
X706983Y247776D01*
X706978Y247816D01*
X706963Y247861D01*
X706953Y247901D01*
X706938Y247941D01*
X706918Y247981D01*
X706903Y248016D01*
X706883Y248056D01*
X706783Y248196D01*
X706753Y248226D01*
Y249356D01*
X706743Y249481D01*
X706703Y249606D01*
X706643Y249716D01*
X706563Y249816D01*
X706463Y249896D01*
X706353Y249956D01*
X706228Y249996D01*
X706103Y250006D01*
G37*
G36*
G01X710827D02*
X710702Y249996D01*
X710577Y249956D01*
X710467Y249896D01*
X710367Y249816D01*
X710287Y249716D01*
X710227Y249606D01*
X710187Y249481D01*
X710177Y249356D01*
Y248226D01*
X710147Y248196D01*
X710047Y248056D01*
X710027Y248016D01*
X710012Y247981D01*
X709992Y247941D01*
X709977Y247901D01*
X709967Y247861D01*
X709952Y247816D01*
X709947Y247776D01*
X709937Y247736D01*
X709932Y247691D01*
Y247651D01*
X709927Y247606D01*
X709932Y247561D01*
Y247521D01*
X709937Y247476D01*
X709947Y247436D01*
X709952Y247396D01*
X709967Y247351D01*
X709977Y247311D01*
X709992Y247271D01*
X710012Y247231D01*
X710027Y247196D01*
X710047Y247156D01*
X710147Y247016D01*
X710177Y246986D01*
Y243556D01*
X710187Y243431D01*
X710227Y243306D01*
X710287Y243196D01*
X710367Y243096D01*
X710467Y243016D01*
X710577Y242956D01*
X710702Y242916D01*
X710827Y242906D01*
X710952Y242916D01*
X711077Y242956D01*
X711187Y243016D01*
X711287Y243096D01*
X711367Y243196D01*
X711427Y243306D01*
X711467Y243431D01*
X711477Y243556D01*
Y246986D01*
X711507Y247016D01*
X711607Y247156D01*
X711627Y247196D01*
X711642Y247231D01*
X711662Y247271D01*
X711677Y247311D01*
X711687Y247351D01*
X711702Y247396D01*
X711707Y247436D01*
X711717Y247476D01*
X711722Y247521D01*
Y247561D01*
X711727Y247606D01*
X711722Y247651D01*
Y247691D01*
X711717Y247736D01*
X711707Y247776D01*
X711702Y247816D01*
X711687Y247861D01*
X711677Y247901D01*
X711662Y247941D01*
X711642Y247981D01*
X711627Y248016D01*
X711607Y248056D01*
X711507Y248196D01*
X711477Y248226D01*
Y249356D01*
X711467Y249481D01*
X711427Y249606D01*
X711367Y249716D01*
X711287Y249816D01*
X711187Y249896D01*
X711077Y249956D01*
X710952Y249996D01*
X710827Y250006D01*
G37*
G36*
G01X715551D02*
X715426Y249996D01*
X715301Y249956D01*
X715191Y249896D01*
X715091Y249816D01*
X715011Y249716D01*
X714951Y249606D01*
X714911Y249481D01*
X714901Y249356D01*
Y248226D01*
X714871Y248196D01*
X714771Y248056D01*
X714751Y248016D01*
X714736Y247981D01*
X714716Y247941D01*
X714701Y247901D01*
X714691Y247861D01*
X714676Y247816D01*
X714671Y247776D01*
X714661Y247736D01*
X714656Y247691D01*
Y247651D01*
X714651Y247606D01*
X714656Y247561D01*
Y247521D01*
X714661Y247476D01*
X714671Y247436D01*
X714676Y247396D01*
X714691Y247351D01*
X714701Y247311D01*
X714716Y247271D01*
X714736Y247231D01*
X714751Y247196D01*
X714771Y247156D01*
X714871Y247016D01*
X714901Y246986D01*
Y243556D01*
X714911Y243431D01*
X714951Y243306D01*
X715011Y243196D01*
X715091Y243096D01*
X715191Y243016D01*
X715301Y242956D01*
X715426Y242916D01*
X715551Y242906D01*
X715676Y242916D01*
X715801Y242956D01*
X715911Y243016D01*
X716011Y243096D01*
X716091Y243196D01*
X716151Y243306D01*
X716191Y243431D01*
X716201Y243556D01*
Y246986D01*
X716231Y247016D01*
X716331Y247156D01*
X716351Y247196D01*
X716366Y247231D01*
X716386Y247271D01*
X716401Y247311D01*
X716411Y247351D01*
X716426Y247396D01*
X716431Y247436D01*
X716441Y247476D01*
X716446Y247521D01*
Y247561D01*
X716451Y247606D01*
X716446Y247651D01*
Y247691D01*
X716441Y247736D01*
X716431Y247776D01*
X716426Y247816D01*
X716411Y247861D01*
X716401Y247901D01*
X716386Y247941D01*
X716366Y247981D01*
X716351Y248016D01*
X716331Y248056D01*
X716231Y248196D01*
X716201Y248226D01*
Y249356D01*
X716191Y249481D01*
X716151Y249606D01*
X716091Y249716D01*
X716011Y249816D01*
X715911Y249896D01*
X715801Y249956D01*
X715676Y249996D01*
X715551Y250006D01*
G37*
G36*
G01X720276D02*
X720151Y249996D01*
X720026Y249956D01*
X719916Y249896D01*
X719816Y249816D01*
X719736Y249716D01*
X719676Y249606D01*
X719636Y249481D01*
X719626Y249356D01*
Y248226D01*
X719596Y248196D01*
X719496Y248056D01*
X719476Y248016D01*
X719461Y247981D01*
X719441Y247941D01*
X719426Y247901D01*
X719416Y247861D01*
X719401Y247816D01*
X719396Y247776D01*
X719386Y247736D01*
X719381Y247691D01*
Y247651D01*
X719376Y247606D01*
X719381Y247561D01*
Y247521D01*
X719386Y247476D01*
X719396Y247436D01*
X719401Y247396D01*
X719416Y247351D01*
X719426Y247311D01*
X719441Y247271D01*
X719461Y247231D01*
X719476Y247196D01*
X719496Y247156D01*
X719596Y247016D01*
X719626Y246986D01*
Y243556D01*
X719636Y243431D01*
X719676Y243306D01*
X719736Y243196D01*
X719816Y243096D01*
X719916Y243016D01*
X720026Y242956D01*
X720151Y242916D01*
X720276Y242906D01*
X720401Y242916D01*
X720526Y242956D01*
X720636Y243016D01*
X720736Y243096D01*
X720816Y243196D01*
X720876Y243306D01*
X720916Y243431D01*
X720926Y243556D01*
Y246986D01*
X720956Y247016D01*
X721056Y247156D01*
X721076Y247196D01*
X721091Y247231D01*
X721111Y247271D01*
X721126Y247311D01*
X721136Y247351D01*
X721151Y247396D01*
X721156Y247436D01*
X721166Y247476D01*
X721171Y247521D01*
Y247561D01*
X721176Y247606D01*
X721171Y247651D01*
Y247691D01*
X721166Y247736D01*
X721156Y247776D01*
X721151Y247816D01*
X721136Y247861D01*
X721126Y247901D01*
X721111Y247941D01*
X721091Y247981D01*
X721076Y248016D01*
X721056Y248056D01*
X720956Y248196D01*
X720926Y248226D01*
Y249356D01*
X720916Y249481D01*
X720876Y249606D01*
X720816Y249716D01*
X720736Y249816D01*
X720636Y249896D01*
X720526Y249956D01*
X720401Y249996D01*
X720276Y250006D01*
G37*
G36*
G01X725000D02*
X724875Y249996D01*
X724750Y249956D01*
X724640Y249896D01*
X724540Y249816D01*
X724460Y249716D01*
X724400Y249606D01*
X724360Y249481D01*
X724350Y249356D01*
Y248226D01*
X724320Y248196D01*
X724220Y248056D01*
X724200Y248016D01*
X724185Y247981D01*
X724165Y247941D01*
X724150Y247901D01*
X724140Y247861D01*
X724125Y247816D01*
X724120Y247776D01*
X724110Y247736D01*
X724105Y247691D01*
Y247651D01*
X724100Y247606D01*
X724105Y247561D01*
Y247521D01*
X724110Y247476D01*
X724120Y247436D01*
X724125Y247396D01*
X724140Y247351D01*
X724150Y247311D01*
X724165Y247271D01*
X724185Y247231D01*
X724200Y247196D01*
X724220Y247156D01*
X724320Y247016D01*
X724350Y246986D01*
Y243556D01*
X724360Y243431D01*
X724400Y243306D01*
X724460Y243196D01*
X724540Y243096D01*
X724640Y243016D01*
X724750Y242956D01*
X724875Y242916D01*
X725000Y242906D01*
X725125Y242916D01*
X725250Y242956D01*
X725360Y243016D01*
X725460Y243096D01*
X725540Y243196D01*
X725600Y243306D01*
X725640Y243431D01*
X725650Y243556D01*
Y246986D01*
X725680Y247016D01*
X725780Y247156D01*
X725800Y247196D01*
X725815Y247231D01*
X725835Y247271D01*
X725850Y247311D01*
X725860Y247351D01*
X725875Y247396D01*
X725880Y247436D01*
X725890Y247476D01*
X725895Y247521D01*
Y247561D01*
X725900Y247606D01*
X725895Y247651D01*
Y247691D01*
X725890Y247736D01*
X725880Y247776D01*
X725875Y247816D01*
X725860Y247861D01*
X725850Y247901D01*
X725835Y247941D01*
X725815Y247981D01*
X725800Y248016D01*
X725780Y248056D01*
X725680Y248196D01*
X725650Y248226D01*
Y249356D01*
X725640Y249481D01*
X725600Y249606D01*
X725540Y249716D01*
X725460Y249816D01*
X725360Y249896D01*
X725250Y249956D01*
X725125Y249996D01*
X725000Y250006D01*
G37*
G36*
G01X729725D02*
X729600Y249996D01*
X729475Y249956D01*
X729365Y249896D01*
X729265Y249816D01*
X729185Y249716D01*
X729125Y249606D01*
X729085Y249481D01*
X729075Y249356D01*
Y248226D01*
X729045Y248196D01*
X728945Y248056D01*
X728925Y248016D01*
X728910Y247981D01*
X728890Y247941D01*
X728875Y247901D01*
X728865Y247861D01*
X728850Y247816D01*
X728845Y247776D01*
X728835Y247736D01*
X728830Y247691D01*
Y247651D01*
X728825Y247606D01*
X728830Y247561D01*
Y247521D01*
X728835Y247476D01*
X728845Y247436D01*
X728850Y247396D01*
X728865Y247351D01*
X728875Y247311D01*
X728890Y247271D01*
X728910Y247231D01*
X728925Y247196D01*
X728945Y247156D01*
X729045Y247016D01*
X729075Y246986D01*
Y243556D01*
X729085Y243431D01*
X729125Y243306D01*
X729185Y243196D01*
X729265Y243096D01*
X729365Y243016D01*
X729475Y242956D01*
X729600Y242916D01*
X729725Y242906D01*
X729850Y242916D01*
X729975Y242956D01*
X730085Y243016D01*
X730185Y243096D01*
X730265Y243196D01*
X730325Y243306D01*
X730365Y243431D01*
X730375Y243556D01*
Y246986D01*
X730405Y247016D01*
X730505Y247156D01*
X730525Y247196D01*
X730540Y247231D01*
X730560Y247271D01*
X730575Y247311D01*
X730585Y247351D01*
X730600Y247396D01*
X730605Y247436D01*
X730615Y247476D01*
X730620Y247521D01*
Y247561D01*
X730625Y247606D01*
X730620Y247651D01*
Y247691D01*
X730615Y247736D01*
X730605Y247776D01*
X730600Y247816D01*
X730585Y247861D01*
X730575Y247901D01*
X730560Y247941D01*
X730540Y247981D01*
X730525Y248016D01*
X730505Y248056D01*
X730405Y248196D01*
X730375Y248226D01*
Y249356D01*
X730365Y249481D01*
X730325Y249606D01*
X730265Y249716D01*
X730185Y249816D01*
X730085Y249896D01*
X729975Y249956D01*
X729850Y249996D01*
X729725Y250006D01*
G37*
G36*
G01X734449D02*
X734324Y249996D01*
X734199Y249956D01*
X734089Y249896D01*
X733989Y249816D01*
X733909Y249716D01*
X733849Y249606D01*
X733809Y249481D01*
X733799Y249356D01*
Y248226D01*
X733769Y248196D01*
X733669Y248056D01*
X733649Y248016D01*
X733634Y247981D01*
X733614Y247941D01*
X733599Y247901D01*
X733589Y247861D01*
X733574Y247816D01*
X733569Y247776D01*
X733559Y247736D01*
X733554Y247691D01*
Y247651D01*
X733549Y247606D01*
X733554Y247561D01*
Y247521D01*
X733559Y247476D01*
X733569Y247436D01*
X733574Y247396D01*
X733589Y247351D01*
X733599Y247311D01*
X733614Y247271D01*
X733634Y247231D01*
X733649Y247196D01*
X733669Y247156D01*
X733769Y247016D01*
X733799Y246986D01*
Y243556D01*
X733809Y243431D01*
X733849Y243306D01*
X733909Y243196D01*
X733989Y243096D01*
X734089Y243016D01*
X734199Y242956D01*
X734324Y242916D01*
X734449Y242906D01*
X734574Y242916D01*
X734699Y242956D01*
X734809Y243016D01*
X734909Y243096D01*
X734989Y243196D01*
X735049Y243306D01*
X735089Y243431D01*
X735099Y243556D01*
Y246986D01*
X735129Y247016D01*
X735229Y247156D01*
X735249Y247196D01*
X735264Y247231D01*
X735284Y247271D01*
X735299Y247311D01*
X735309Y247351D01*
X735324Y247396D01*
X735329Y247436D01*
X735339Y247476D01*
X735344Y247521D01*
Y247561D01*
X735349Y247606D01*
X735344Y247651D01*
Y247691D01*
X735339Y247736D01*
X735329Y247776D01*
X735324Y247816D01*
X735309Y247861D01*
X735299Y247901D01*
X735284Y247941D01*
X735264Y247981D01*
X735249Y248016D01*
X735229Y248056D01*
X735129Y248196D01*
X735099Y248226D01*
Y249356D01*
X735089Y249481D01*
X735049Y249606D01*
X734989Y249716D01*
X734909Y249816D01*
X734809Y249896D01*
X734699Y249956D01*
X734574Y249996D01*
X734449Y250006D01*
G37*
G36*
G01X739173D02*
X739048Y249996D01*
X738923Y249956D01*
X738813Y249896D01*
X738713Y249816D01*
X738633Y249716D01*
X738573Y249606D01*
X738533Y249481D01*
X738523Y249356D01*
Y248226D01*
X738493Y248196D01*
X738393Y248056D01*
X738373Y248016D01*
X738358Y247981D01*
X738338Y247941D01*
X738323Y247901D01*
X738313Y247861D01*
X738298Y247816D01*
X738293Y247776D01*
X738283Y247736D01*
X738278Y247691D01*
Y247651D01*
X738273Y247606D01*
X738278Y247561D01*
Y247521D01*
X738283Y247476D01*
X738293Y247436D01*
X738298Y247396D01*
X738313Y247351D01*
X738323Y247311D01*
X738338Y247271D01*
X738358Y247231D01*
X738373Y247196D01*
X738393Y247156D01*
X738493Y247016D01*
X738523Y246986D01*
Y243556D01*
X738533Y243431D01*
X738573Y243306D01*
X738633Y243196D01*
X738713Y243096D01*
X738813Y243016D01*
X738923Y242956D01*
X739048Y242916D01*
X739173Y242906D01*
X739298Y242916D01*
X739423Y242956D01*
X739533Y243016D01*
X739633Y243096D01*
X739713Y243196D01*
X739773Y243306D01*
X739813Y243431D01*
X739823Y243556D01*
Y246986D01*
X739853Y247016D01*
X739953Y247156D01*
X739973Y247196D01*
X739988Y247231D01*
X740008Y247271D01*
X740023Y247311D01*
X740033Y247351D01*
X740048Y247396D01*
X740053Y247436D01*
X740063Y247476D01*
X740068Y247521D01*
Y247561D01*
X740073Y247606D01*
X740068Y247651D01*
Y247691D01*
X740063Y247736D01*
X740053Y247776D01*
X740048Y247816D01*
X740033Y247861D01*
X740023Y247901D01*
X740008Y247941D01*
X739988Y247981D01*
X739973Y248016D01*
X739953Y248056D01*
X739853Y248196D01*
X739823Y248226D01*
Y249356D01*
X739813Y249481D01*
X739773Y249606D01*
X739713Y249716D01*
X739633Y249816D01*
X739533Y249896D01*
X739423Y249956D01*
X739298Y249996D01*
X739173Y250006D01*
G37*
G36*
G01X743898D02*
X743773Y249996D01*
X743648Y249956D01*
X743538Y249896D01*
X743438Y249816D01*
X743358Y249716D01*
X743298Y249606D01*
X743258Y249481D01*
X743248Y249356D01*
Y248226D01*
X743218Y248196D01*
X743118Y248056D01*
X743098Y248016D01*
X743083Y247981D01*
X743063Y247941D01*
X743048Y247901D01*
X743038Y247861D01*
X743023Y247816D01*
X743018Y247776D01*
X743008Y247736D01*
X743003Y247691D01*
Y247651D01*
X742998Y247606D01*
X743003Y247561D01*
Y247521D01*
X743008Y247476D01*
X743018Y247436D01*
X743023Y247396D01*
X743038Y247351D01*
X743048Y247311D01*
X743063Y247271D01*
X743083Y247231D01*
X743098Y247196D01*
X743118Y247156D01*
X743218Y247016D01*
X743248Y246986D01*
Y243556D01*
X743258Y243431D01*
X743298Y243306D01*
X743358Y243196D01*
X743438Y243096D01*
X743538Y243016D01*
X743648Y242956D01*
X743773Y242916D01*
X743898Y242906D01*
X744023Y242916D01*
X744148Y242956D01*
X744258Y243016D01*
X744358Y243096D01*
X744438Y243196D01*
X744498Y243306D01*
X744538Y243431D01*
X744548Y243556D01*
Y246986D01*
X744578Y247016D01*
X744678Y247156D01*
X744698Y247196D01*
X744713Y247231D01*
X744733Y247271D01*
X744748Y247311D01*
X744758Y247351D01*
X744773Y247396D01*
X744778Y247436D01*
X744788Y247476D01*
X744793Y247521D01*
Y247561D01*
X744798Y247606D01*
X744793Y247651D01*
Y247691D01*
X744788Y247736D01*
X744778Y247776D01*
X744773Y247816D01*
X744758Y247861D01*
X744748Y247901D01*
X744733Y247941D01*
X744713Y247981D01*
X744698Y248016D01*
X744678Y248056D01*
X744578Y248196D01*
X744548Y248226D01*
Y249356D01*
X744538Y249481D01*
X744498Y249606D01*
X744438Y249716D01*
X744358Y249816D01*
X744258Y249896D01*
X744148Y249956D01*
X744023Y249996D01*
X743898Y250006D01*
G37*
G36*
G01X748622D02*
X748497Y249996D01*
X748372Y249956D01*
X748262Y249896D01*
X748162Y249816D01*
X748082Y249716D01*
X748022Y249606D01*
X747982Y249481D01*
X747972Y249356D01*
Y248226D01*
X747942Y248196D01*
X747842Y248056D01*
X747822Y248016D01*
X747807Y247981D01*
X747787Y247941D01*
X747772Y247901D01*
X747762Y247861D01*
X747747Y247816D01*
X747742Y247776D01*
X747732Y247736D01*
X747727Y247691D01*
Y247651D01*
X747722Y247606D01*
X747727Y247561D01*
Y247521D01*
X747732Y247476D01*
X747742Y247436D01*
X747747Y247396D01*
X747762Y247351D01*
X747772Y247311D01*
X747787Y247271D01*
X747807Y247231D01*
X747822Y247196D01*
X747842Y247156D01*
X747942Y247016D01*
X747972Y246986D01*
Y243556D01*
X747982Y243431D01*
X748022Y243306D01*
X748082Y243196D01*
X748162Y243096D01*
X748262Y243016D01*
X748372Y242956D01*
X748497Y242916D01*
X748622Y242906D01*
X748747Y242916D01*
X748872Y242956D01*
X748982Y243016D01*
X749082Y243096D01*
X749162Y243196D01*
X749222Y243306D01*
X749262Y243431D01*
X749272Y243556D01*
Y246986D01*
X749302Y247016D01*
X749402Y247156D01*
X749422Y247196D01*
X749437Y247231D01*
X749457Y247271D01*
X749472Y247311D01*
X749482Y247351D01*
X749497Y247396D01*
X749502Y247436D01*
X749512Y247476D01*
X749517Y247521D01*
Y247561D01*
X749522Y247606D01*
X749517Y247651D01*
Y247691D01*
X749512Y247736D01*
X749502Y247776D01*
X749497Y247816D01*
X749482Y247861D01*
X749472Y247901D01*
X749457Y247941D01*
X749437Y247981D01*
X749422Y248016D01*
X749402Y248056D01*
X749302Y248196D01*
X749272Y248226D01*
Y249356D01*
X749262Y249481D01*
X749222Y249606D01*
X749162Y249716D01*
X749082Y249816D01*
X748982Y249896D01*
X748872Y249956D01*
X748747Y249996D01*
X748622Y250006D01*
G37*
G54D98*
X804032Y27032D03*
X794032D03*
X804032Y37032D03*
Y47032D03*
X794032Y37032D03*
Y47032D03*
X804032Y57032D03*
X794032D03*
X804032Y67032D03*
X794032D03*
G54D99*
X804400Y212800D03*
X794600D03*
M02*
